G04 ================== begin FILE IDENTIFICATION RECORD ==================*
G04 Layout Name:  9324_DA0F0TMBIJ0_F0T_Motherboard_J_v01_20230324_0910.brd*
G04 Film Name:    fab*
G04 File Format:  Gerber RS274X*
G04 File Origin:  Cadence Allegro 17.2-S081*
G04 Origin Date:  Sat Mar 25 08:45:15 2023*
G04 *
G04 Layer:  MANUFACTURING/NCBACKDRILL-18-7*
G04 Layer:  MANUFACTURING/NCBACKDRILL-18-9*
G04 Layer:  MANUFACTURING/NCBACKDRILL-18-17*
G04 Layer:  MANUFACTURING/NCBACKDRILL-18-15*
G04 Layer:  MANUFACTURING/NCBACKDRILL-1-15*
G04 Layer:  MANUFACTURING/NCBACKDRILL-1-13*
G04 Layer:  MANUFACTURING/NCBACKDRILL-1-11*
G04 Layer:  MANUFACTURING/NCBACKDRILL-1-6*
G04 Layer:  MANUFACTURING/NCBACKDRILL-1-2*
G04 Layer:  MANUFACTURING/NCBACKDRILL-18-8*
G04 Layer:  MANUFACTURING/NCBACKDRILL-18-6*
G04 Layer:  MANUFACTURING/NCBACKDRILL-18-4*
G04 Layer:  MANUFACTURING/NCBACKDRILL-18-13*
G04 Layer:  PIN/SPECIAL_DRILL*
G04 Layer:  DRAWING FORMAT/TITLE_BLOCK_A*
G04 Layer:  MANUFACTURING/NCLEGEND-1-18*
G04 Layer:  BOARD GEOMETRY/DESIGN_OUTLINE*
G04 Layer:  BOARD GEOMETRY/CUTOUT*
G04 Layer:  MANUFACTURING/NCDRILL_LEGEND*
G04 Layer:  MANUFACTURING/NCDRILL_FIGURE*
G04 Layer:  MANUFACTURING/PHOTOPLOT_OUTLINE*
G04 Layer:  MANUFACTURING/DIMENSION*
G04 Layer:  MANUFACTURING/DETAILS*
G04 Layer:  DRAWING FORMAT/TITLE_BLOCK*
G04 Layer:  DRAWING FORMAT/TITLE_DATA_FAB*
G04 *
G04 Offset:    (0.00 0.00)*
G04 Mirror:    No*
G04 Mode:      Positive*
G04 Rotation:  0*
G04 FullContactRelief:  No*
G04 UndefLineWidth:     6.00*
G04 ================== end FILE IDENTIFICATION RECORD ====================*
%FSLAX25Y25*MOIN*%
%IR0*IPPOS*OFA0.00000B0.00000*MIA0B0*SFA1.00000B1.00000*%
%AMMACRO24*
1,1,.006,.014497,-.035*
20,1,.006,.014497,-.035,-.014497,-.035,0.0*
1,1,.006,-.014497,-.035*
20,1,.006,-.014497,-.035,-.035,-.014497,0.0*
1,1,.006,-.035,-.014497*
20,1,.006,-.035,-.014497,-.035,.014497,0.0*
1,1,.006,-.035,.014497*
20,1,.006,-.035,.014497,-.014497,.035,0.0*
1,1,.006,-.014497,.035*
20,1,.006,-.014497,.035,.014497,.035,0.0*
1,1,.006,.014497,.035*
20,1,.006,.014497,.035,.035,.014497,0.0*
1,1,.006,.035,.014497*
20,1,.006,.035,.014497,.035,-.014497,0.0*
1,1,.006,.035,-.014497*
20,1,.006,.035,-.014497,.014497,-.035,0.0*
1,1,.006,.014497,-.035*
1,1,.006,-.0229,-.01041*
20,1,.006,-.0229,-.01041,-.0229,.00729,0.0*
1,1,.006,-.0229,.00729*
20,1,.006,-.0229,.00729,-.02221,.00902,0.0*
1,1,.006,-.02221,.00902*
20,1,.006,-.02221,.00902,-.02082,.01006,0.0*
1,1,.006,-.02082,.01006*
20,1,.006,-.02082,.01006,-.01874,.01041,0.0*
1,1,.006,-.01874,.01041*
20,1,.006,-.01874,.01041,-.01666,.00972,0.0*
1,1,.006,-.01666,.00972*
20,1,.006,-.01666,.00972,-.01562,.00798,0.0*
1,1,.006,-.01562,.00798*
1,1,.006,-.01978,.00208*
20,1,.006,-.01978,.00208,-.02672,.00208,0.0*
1,1,.006,-.02672,.00208*
1,1,.006,.00001,.00347*
20,1,.006,.00001,.00347,.00001,-.01041,0.0*
1,1,.006,.00001,-.01041*
1,1,.006,.00001,.00902*
20,1,.006,.00001,.00902,-.00068,.00937,0.0*
1,1,.006,-.00068,.00937*
20,1,.006,-.00068,.00937,-.00068,.01006,0.0*
1,1,.006,-.00068,.01006*
20,1,.006,-.00068,.01006,.00001,.01041,0.0*
1,1,.006,.00001,.01041*
20,1,.006,.00001,.01041,.0007,.01006,0.0*
1,1,.006,.0007,.01006*
20,1,.006,.0007,.01006,.0007,.00937,0.0*
1,1,.006,.0007,.00937*
20,1,.006,.0007,.00937,.00001,.00902,0.0*
1,1,.006,.00001,.00902*
1,1,.006,.02084,.01041*
20,1,.006,.02084,.01041,.02084,-.01041,0.0*
1,1,.006,.02084,-.01041*
1,1,.006,.01598,.00347*
20,1,.006,.01598,.00347,.0257,.00347,0.0*
1,1,.006,.0257,.00347*
%
%ADD24MACRO24*%
%AMMACRO40*
1,1,.006,.035,.035*
20,1,.006,.035,.035,.035,-.035,0.0*
1,1,.006,.035,-.035*
20,1,.006,.035,-.035,-.035,-.035,0.0*
1,1,.006,-.035,-.035*
20,1,.006,-.035,-.035,-.035,.035,0.0*
1,1,.006,-.035,.035*
20,1,.006,-.035,.035,.035,.035,0.0*
1,1,.006,.035,.035*
1,1,.006,-.03185,-.02042*
20,1,.006,-.03185,-.02042,-.03185,.00408,0.0*
1,1,.006,-.03185,.00408*
1,1,.006,-.03185,.00041*
20,1,.006,-.03185,.00041,-.02981,.00245,0.0*
1,1,.006,-.02981,.00245*
20,1,.006,-.02981,.00245,-.02777,.00367,0.0*
1,1,.006,-.02777,.00367*
20,1,.006,-.02777,.00367,-.0245,.00408,0.0*
1,1,.006,-.0245,.00408*
20,1,.006,-.0245,.00408,-.02164,.00367,0.0*
1,1,.006,-.02164,.00367*
20,1,.006,-.02164,.00367,-.01878,.00163,0.0*
1,1,.006,-.01878,.00163*
20,1,.006,-.01878,.00163,-.01756,-.00123,0.0*
1,1,.006,-.01756,-.00123*
20,1,.006,-.01756,-.00123,-.01715,-.00408,0.0*
1,1,.006,-.01715,-.00408*
20,1,.006,-.01715,-.00408,-.01756,-.00694,0.0*
1,1,.006,-.01756,-.00694*
20,1,.006,-.01756,-.00694,-.01878,-.0098,0.0*
1,1,.006,-.01878,-.0098*
20,1,.006,-.01878,-.0098,-.02123,-.01143,0.0*
1,1,.006,-.02123,-.01143*
20,1,.006,-.02123,-.01143,-.0245,-.01225,0.0*
1,1,.006,-.0245,-.01225*
20,1,.006,-.0245,-.01225,-.02736,-.01184,0.0*
1,1,.006,-.02736,-.01184*
20,1,.006,-.02736,-.01184,-.03022,-.01062,0.0*
1,1,.006,-.03022,-.01062*
20,1,.006,-.03022,-.01062,-.03185,-.00898,0.0*
1,1,.006,-.03185,-.00898*
1,1,.006,-.00611,-.00123*
20,1,.006,-.00611,-.00123,.00695,-.00123,0.0*
1,1,.006,.00695,-.00123*
20,1,.006,.00695,-.00123,.00573,.00163,0.0*
1,1,.006,.00573,.00163*
20,1,.006,.00573,.00163,.00369,.00327,0.0*
1,1,.006,.00369,.00327*
20,1,.006,.00369,.00327,.00083,.00408,0.0*
1,1,.006,.00083,.00408*
20,1,.006,.00083,.00408,-.00203,.00367,0.0*
1,1,.006,-.00203,.00367*
20,1,.006,-.00203,.00367,-.00448,.00245,0.0*
1,1,.006,-.00448,.00245*
20,1,.006,-.00448,.00245,-.00611,-.00041,0.0*
1,1,.006,-.00611,-.00041*
20,1,.006,-.00611,-.00041,-.00693,-.00286,0.0*
1,1,.006,-.00693,-.00286*
20,1,.006,-.00693,-.00286,-.00693,-.00531,0.0*
1,1,.006,-.00693,-.00531*
20,1,.006,-.00693,-.00531,-.00611,-.00776,0.0*
1,1,.006,-.00611,-.00776*
20,1,.006,-.00611,-.00776,-.00407,-.01021,0.0*
1,1,.006,-.00407,-.01021*
20,1,.006,-.00407,-.01021,-.00162,-.01184,0.0*
1,1,.006,-.00162,-.01184*
20,1,.006,-.00162,-.01184,.00124,-.01225,0.0*
1,1,.006,.00124,-.01225*
20,1,.006,.00124,-.01225,.00409,-.01143,0.0*
1,1,.006,.00409,-.01143*
20,1,.006,.00409,-.01143,.00695,-.00898,0.0*
1,1,.006,.00695,-.00898*
1,1,.006,.01717,-.02042*
20,1,.006,.01717,-.02042,.01717,.00408,0.0*
1,1,.006,.01717,.00408*
1,1,.006,.01717,.00041*
20,1,.006,.01717,.00041,.01921,.00245,0.0*
1,1,.006,.01921,.00245*
20,1,.006,.01921,.00245,.02125,.00367,0.0*
1,1,.006,.02125,.00367*
20,1,.006,.02125,.00367,.02452,.00408,0.0*
1,1,.006,.02452,.00408*
20,1,.006,.02452,.00408,.02738,.00367,0.0*
1,1,.006,.02738,.00367*
20,1,.006,.02738,.00367,.03024,.00163,0.0*
1,1,.006,.03024,.00163*
20,1,.006,.03024,.00163,.03146,-.00123,0.0*
1,1,.006,.03146,-.00123*
20,1,.006,.03146,-.00123,.03187,-.00408,0.0*
1,1,.006,.03187,-.00408*
20,1,.006,.03187,-.00408,.03146,-.00694,0.0*
1,1,.006,.03146,-.00694*
20,1,.006,.03146,-.00694,.03024,-.0098,0.0*
1,1,.006,.03024,-.0098*
20,1,.006,.03024,-.0098,.02779,-.01143,0.0*
1,1,.006,.02779,-.01143*
20,1,.006,.02779,-.01143,.02452,-.01225,0.0*
1,1,.006,.02452,-.01225*
20,1,.006,.02452,-.01225,.02166,-.01184,0.0*
1,1,.006,.02166,-.01184*
20,1,.006,.02166,-.01184,.0188,-.01062,0.0*
1,1,.006,.0188,-.01062*
20,1,.006,.0188,-.01062,.01717,-.00898,0.0*
1,1,.006,.01717,-.00898*
%
%ADD40MACRO40*%
%AMMACRO36*
1,1,.006,0.0,.0395*
20,1,.006,0.0,.0395,.034208,-.01975,0.0*
1,1,.006,.034208,-.01975*
20,1,.006,.034208,-.01975,-.034208,-.01975,0.0*
1,1,.006,-.034208,-.01975*
20,1,.006,-.034208,-.01975,0.0,.0395,0.0*
1,1,.006,0.0,.0395*
1,1,.006,-.01244,.00622*
20,1,.006,-.01244,.00622,-.0141,.00581,0.0*
1,1,.006,-.0141,.00581*
20,1,.006,-.0141,.00581,-.01534,.00477,0.0*
1,1,.006,-.01534,.00477*
20,1,.006,-.01534,.00477,-.01617,.00352,0.0*
1,1,.006,-.01617,.00352*
20,1,.006,-.01617,.00352,-.01679,.00187,0.0*
1,1,.006,-.01679,.00187*
20,1,.006,-.01679,.00187,-.017,0.0,0.0*
1,1,.006,-.017,0.0*
20,1,.006,-.017,0.0,-.01679,-.00187,0.0*
1,1,.006,-.01679,-.00187*
20,1,.006,-.01679,-.00187,-.01617,-.00352,0.0*
1,1,.006,-.01617,-.00352*
20,1,.006,-.01617,-.00352,-.01534,-.00477,0.0*
1,1,.006,-.01534,-.00477*
20,1,.006,-.01534,-.00477,-.0141,-.00581,0.0*
1,1,.006,-.0141,-.00581*
20,1,.006,-.0141,-.00581,-.01244,-.00622,0.0*
1,1,.006,-.01244,-.00622*
20,1,.006,-.01244,-.00622,-.01078,-.00581,0.0*
1,1,.006,-.01078,-.00581*
20,1,.006,-.01078,-.00581,-.00954,-.00477,0.0*
1,1,.006,-.00954,-.00477*
20,1,.006,-.00954,-.00477,-.00871,-.00352,0.0*
1,1,.006,-.00871,-.00352*
20,1,.006,-.00871,-.00352,-.00809,-.00187,0.0*
1,1,.006,-.00809,-.00187*
20,1,.006,-.00809,-.00187,-.00788,0.0,0.0*
1,1,.006,-.00788,0.0*
20,1,.006,-.00788,0.0,-.00809,.00187,0.0*
1,1,.006,-.00809,.00187*
20,1,.006,-.00809,.00187,-.00871,.00352,0.0*
1,1,.006,-.00871,.00352*
20,1,.006,-.00871,.00352,-.00954,.00477,0.0*
1,1,.006,-.00954,.00477*
20,1,.006,-.00954,.00477,-.01078,.00581,0.0*
1,1,.006,-.01078,.00581*
20,1,.006,-.01078,.00581,-.01244,.00622,0.0*
1,1,.006,-.01244,.00622*
1,1,.006,-.0004,-.00622*
20,1,.006,-.0004,-.00622,.00001,-.00352,0.0*
1,1,.006,.00001,-.00352*
20,1,.006,.00001,-.00352,.00063,-.00124,0.0*
1,1,.006,.00063,-.00124*
20,1,.006,.00063,-.00124,.00146,.00083,0.0*
1,1,.006,.00146,.00083*
20,1,.006,.00146,.00083,.0025,.00311,0.0*
1,1,.006,.0025,.00311*
20,1,.006,.0025,.00311,.00416,.00622,0.0*
1,1,.006,.00416,.00622*
20,1,.006,.00416,.00622,-.00414,.00622,0.0*
1,1,.006,-.00414,.00622*
1,1,.006,.00894,-.00477*
20,1,.006,.00894,-.00477,.01039,-.00581,0.0*
1,1,.006,.01039,-.00581*
20,1,.006,.01039,-.00581,.01205,-.00622,0.0*
1,1,.006,.01205,-.00622*
20,1,.006,.01205,-.00622,.0137,-.00581,0.0*
1,1,.006,.0137,-.00581*
20,1,.006,.0137,-.00581,.01516,-.00456,0.0*
1,1,.006,.01516,-.00456*
20,1,.006,.01516,-.00456,.01619,-.0027,0.0*
1,1,.006,.01619,-.0027*
20,1,.006,.01619,-.0027,.01661,-.00083,0.0*
1,1,.006,.01661,-.00083*
20,1,.006,.01661,-.00083,.01661,.00145,0.0*
1,1,.006,.01661,.00145*
20,1,.006,.01661,.00145,.01619,.00332,0.0*
1,1,.006,.01619,.00332*
20,1,.006,.01619,.00332,.01516,.00498,0.0*
1,1,.006,.01516,.00498*
20,1,.006,.01516,.00498,.01391,.00581,0.0*
1,1,.006,.01391,.00581*
20,1,.006,.01391,.00581,.01246,.00622,0.0*
1,1,.006,.01246,.00622*
20,1,.006,.01246,.00622,.0108,.00581,0.0*
1,1,.006,.0108,.00581*
20,1,.006,.0108,.00581,.00956,.00498,0.0*
1,1,.006,.00956,.00498*
20,1,.006,.00956,.00498,.00873,.00373,0.0*
1,1,.006,.00873,.00373*
20,1,.006,.00873,.00373,.00831,.00207,0.0*
1,1,.006,.00831,.00207*
20,1,.006,.00831,.00207,.00873,.00062,0.0*
1,1,.006,.00873,.00062*
20,1,.006,.00873,.00062,.00976,-.00083,0.0*
1,1,.006,.00976,-.00083*
20,1,.006,.00976,-.00083,.01101,-.00166,0.0*
1,1,.006,.01101,-.00166*
20,1,.006,.01101,-.00166,.01246,-.00187,0.0*
1,1,.006,.01246,-.00187*
20,1,.006,.01246,-.00187,.01412,-.00145,0.0*
1,1,.006,.01412,-.00145*
20,1,.006,.01412,-.00145,.01536,-.00041,0.0*
1,1,.006,.01536,-.00041*
20,1,.006,.01536,-.00041,.01661,.00145,0.0*
1,1,.006,.01661,.00145*
%
%ADD36MACRO36*%
%AMMACRO32*
1,1,.006,.06,0.0*
20,1,.006,.06,0.0,0.0,-.06,0.0*
1,1,.006,0.0,-.06*
20,1,.006,0.0,-.06,-.06,0.0,0.0*
1,1,.006,-.06,0.0*
20,1,.006,-.06,0.0,0.0,.06,0.0*
1,1,.006,0.0,.06*
20,1,.006,0.0,.06,.06,0.0,0.0*
1,1,.006,.06,0.0*
1,1,.006,-.0294,-.035*
20,1,.006,-.0294,-.035,-.0294,.007,0.0*
1,1,.006,-.0294,.007*
1,1,.006,-.0294,.0007*
20,1,.006,-.0294,.0007,-.0329,.0042,0.0*
1,1,.006,-.0329,.0042*
20,1,.006,-.0329,.0042,-.0371,.0063,0.0*
1,1,.006,-.0371,.0063*
20,1,.006,-.0371,.0063,-.042,.007,0.0*
1,1,.006,-.042,.007*
20,1,.006,-.042,.007,-.0462,.0063,0.0*
1,1,.006,-.0462,.0063*
20,1,.006,-.0462,.0063,-.0511,.0028,0.0*
1,1,.006,-.0511,.0028*
20,1,.006,-.0511,.0028,-.0539,-.0021,0.0*
1,1,.006,-.0539,-.0021*
20,1,.006,-.0539,-.0021,-.0546,-.007,0.0*
1,1,.006,-.0546,-.007*
20,1,.006,-.0546,-.007,-.0539,-.0119,0.0*
1,1,.006,-.0539,-.0119*
20,1,.006,-.0539,-.0119,-.0511,-.0168,0.0*
1,1,.006,-.0511,-.0168*
20,1,.006,-.0511,-.0168,-.0462,-.0203,0.0*
1,1,.006,-.0462,-.0203*
20,1,.006,-.0462,-.0203,-.042,-.021,0.0*
1,1,.006,-.042,-.021*
20,1,.006,-.042,-.021,-.0371,-.0203,0.0*
1,1,.006,-.0371,-.0203*
20,1,.006,-.0371,-.0203,-.0329,-.0182,0.0*
1,1,.006,-.0329,-.0182*
20,1,.006,-.0329,-.0182,-.0294,-.0147,0.0*
1,1,.006,-.0294,-.0147*
1,1,.006,-.01749,.007*
20,1,.006,-.01749,.007,-.00909,-.021,0.0*
1,1,.006,-.00909,-.021*
20,1,.006,-.00909,-.021,.00001,.007,0.0*
1,1,.006,.00001,.007*
20,1,.006,.00001,.007,.00911,-.021,0.0*
1,1,.006,.00911,-.021*
20,1,.006,.00911,-.021,.01751,.007,0.0*
1,1,.006,.01751,.007*
1,1,.006,.02942,-.035*
20,1,.006,.02942,-.035,.02942,.007,0.0*
1,1,.006,.02942,.007*
1,1,.006,.02942,.0007*
20,1,.006,.02942,.0007,.03292,.0042,0.0*
1,1,.006,.03292,.0042*
20,1,.006,.03292,.0042,.03642,.0063,0.0*
1,1,.006,.03642,.0063*
20,1,.006,.03642,.0063,.04202,.007,0.0*
1,1,.006,.04202,.007*
20,1,.006,.04202,.007,.04692,.0063,0.0*
1,1,.006,.04692,.0063*
20,1,.006,.04692,.0063,.05182,.0028,0.0*
1,1,.006,.05182,.0028*
20,1,.006,.05182,.0028,.05392,-.0021,0.0*
1,1,.006,.05392,-.0021*
20,1,.006,.05392,-.0021,.05462,-.007,0.0*
1,1,.006,.05462,-.007*
20,1,.006,.05462,-.007,.05392,-.0119,0.0*
1,1,.006,.05392,-.0119*
20,1,.006,.05392,-.0119,.05182,-.0168,0.0*
1,1,.006,.05182,-.0168*
20,1,.006,.05182,-.0168,.04762,-.0196,0.0*
1,1,.006,.04762,-.0196*
20,1,.006,.04762,-.0196,.04202,-.021,0.0*
1,1,.006,.04202,-.021*
20,1,.006,.04202,-.021,.03712,-.0203,0.0*
1,1,.006,.03712,-.0203*
20,1,.006,.03712,-.0203,.03222,-.0182,0.0*
1,1,.006,.03222,-.0182*
20,1,.006,.03222,-.0182,.02942,-.0154,0.0*
1,1,.006,.02942,-.0154*
%
%ADD32MACRO32*%
%AMMACRO20*
1,1,.006,.035,.035*
20,1,.006,.035,.035,.035,-.035,0.0*
1,1,.006,.035,-.035*
20,1,.006,.035,-.035,-.035,-.035,0.0*
1,1,.006,-.035,-.035*
20,1,.006,-.035,-.035,-.035,.035,0.0*
1,1,.006,-.035,.035*
20,1,.006,-.035,.035,.035,.035,0.0*
1,1,.006,.035,.035*
1,1,.006,-.03185,-.02042*
20,1,.006,-.03185,-.02042,-.03185,.00408,0.0*
1,1,.006,-.03185,.00408*
1,1,.006,-.03185,.00041*
20,1,.006,-.03185,.00041,-.02981,.00245,0.0*
1,1,.006,-.02981,.00245*
20,1,.006,-.02981,.00245,-.02777,.00367,0.0*
1,1,.006,-.02777,.00367*
20,1,.006,-.02777,.00367,-.0245,.00408,0.0*
1,1,.006,-.0245,.00408*
20,1,.006,-.0245,.00408,-.02164,.00367,0.0*
1,1,.006,-.02164,.00367*
20,1,.006,-.02164,.00367,-.01878,.00163,0.0*
1,1,.006,-.01878,.00163*
20,1,.006,-.01878,.00163,-.01756,-.00123,0.0*
1,1,.006,-.01756,-.00123*
20,1,.006,-.01756,-.00123,-.01715,-.00408,0.0*
1,1,.006,-.01715,-.00408*
20,1,.006,-.01715,-.00408,-.01756,-.00694,0.0*
1,1,.006,-.01756,-.00694*
20,1,.006,-.01756,-.00694,-.01878,-.0098,0.0*
1,1,.006,-.01878,-.0098*
20,1,.006,-.01878,-.0098,-.02123,-.01143,0.0*
1,1,.006,-.02123,-.01143*
20,1,.006,-.02123,-.01143,-.0245,-.01225,0.0*
1,1,.006,-.0245,-.01225*
20,1,.006,-.0245,-.01225,-.02736,-.01184,0.0*
1,1,.006,-.02736,-.01184*
20,1,.006,-.02736,-.01184,-.03022,-.01062,0.0*
1,1,.006,-.03022,-.01062*
20,1,.006,-.03022,-.01062,-.03185,-.00898,0.0*
1,1,.006,-.03185,-.00898*
1,1,.006,-.00571,-.01225*
20,1,.006,-.00571,-.01225,-.00571,.00408,0.0*
1,1,.006,-.00571,.00408*
1,1,.006,-.00571,.00082*
20,1,.006,-.00571,.00082,-.00367,.00245,0.0*
1,1,.006,-.00367,.00245*
20,1,.006,-.00367,.00245,-.00162,.00367,0.0*
1,1,.006,-.00162,.00367*
20,1,.006,-.00162,.00367,.00124,.00408,0.0*
1,1,.006,.00124,.00408*
20,1,.006,.00124,.00408,.00328,.00367,0.0*
1,1,.006,.00328,.00367*
20,1,.006,.00328,.00367,.00573,.00245,0.0*
1,1,.006,.00573,.00245*
1,1,.006,.01717,-.02042*
20,1,.006,.01717,-.02042,.01717,.00408,0.0*
1,1,.006,.01717,.00408*
1,1,.006,.01717,.00041*
20,1,.006,.01717,.00041,.01921,.00245,0.0*
1,1,.006,.01921,.00245*
20,1,.006,.01921,.00245,.02125,.00367,0.0*
1,1,.006,.02125,.00367*
20,1,.006,.02125,.00367,.02452,.00408,0.0*
1,1,.006,.02452,.00408*
20,1,.006,.02452,.00408,.02738,.00367,0.0*
1,1,.006,.02738,.00367*
20,1,.006,.02738,.00367,.03024,.00163,0.0*
1,1,.006,.03024,.00163*
20,1,.006,.03024,.00163,.03146,-.00123,0.0*
1,1,.006,.03146,-.00123*
20,1,.006,.03146,-.00123,.03187,-.00408,0.0*
1,1,.006,.03187,-.00408*
20,1,.006,.03187,-.00408,.03146,-.00694,0.0*
1,1,.006,.03146,-.00694*
20,1,.006,.03146,-.00694,.03024,-.0098,0.0*
1,1,.006,.03024,-.0098*
20,1,.006,.03024,-.0098,.02779,-.01143,0.0*
1,1,.006,.02779,-.01143*
20,1,.006,.02779,-.01143,.02452,-.01225,0.0*
1,1,.006,.02452,-.01225*
20,1,.006,.02452,-.01225,.02166,-.01184,0.0*
1,1,.006,.02166,-.01184*
20,1,.006,.02166,-.01184,.0188,-.01062,0.0*
1,1,.006,.0188,-.01062*
20,1,.006,.0188,-.01062,.01717,-.00898,0.0*
1,1,.006,.01717,-.00898*
%
%ADD20MACRO20*%
%AMMACRO15*
1,1,.006,.197,.197*
20,1,.006,.197,.197,.197,-.197,0.0*
1,1,.006,.197,-.197*
20,1,.006,.197,-.197,-.197,-.197,0.0*
1,1,.006,-.197,-.197*
20,1,.006,-.197,-.197,-.197,.197,0.0*
1,1,.006,-.197,.197*
20,1,.006,-.197,.197,.197,.197,0.0*
1,1,.006,.197,.197*
1,1,.006,-.17237,-.0069*
20,1,.006,-.17237,-.0069,-.09883,-.0069,0.0*
1,1,.006,-.09883,-.0069*
20,1,.006,-.09883,-.0069,-.10572,.00919,0.0*
1,1,.006,-.10572,.00919*
20,1,.006,-.10572,.00919,-.11721,.01838,0.0*
1,1,.006,-.11721,.01838*
20,1,.006,-.11721,.01838,-.1333,.02298,0.0*
1,1,.006,-.1333,.02298*
20,1,.006,-.1333,.02298,-.14939,.02068,0.0*
1,1,.006,-.14939,.02068*
20,1,.006,-.14939,.02068,-.16318,.01379,0.0*
1,1,.006,-.16318,.01379*
20,1,.006,-.16318,.01379,-.17237,-.0023,0.0*
1,1,.006,-.17237,-.0023*
20,1,.006,-.17237,-.0023,-.17697,-.01609,0.0*
1,1,.006,-.17697,-.01609*
20,1,.006,-.17697,-.01609,-.17697,-.02988,0.0*
1,1,.006,-.17697,-.02988*
20,1,.006,-.17697,-.02988,-.17237,-.04367,0.0*
1,1,.006,-.17237,-.04367*
20,1,.006,-.17237,-.04367,-.16088,-.05746,0.0*
1,1,.006,-.16088,-.05746*
20,1,.006,-.16088,-.05746,-.14709,-.06665,0.0*
1,1,.006,-.14709,-.06665*
20,1,.006,-.14709,-.06665,-.131,-.06895,0.0*
1,1,.006,-.131,-.06895*
20,1,.006,-.131,-.06895,-.11492,-.06435,0.0*
1,1,.006,-.11492,-.06435*
20,1,.006,-.11492,-.06435,-.09883,-.05057,0.0*
1,1,.006,-.09883,-.05057*
1,1,.006,.00001,-.06895*
20,1,.006,.00001,-.06895,-.01378,-.06665,0.0*
1,1,.006,-.01378,-.06665*
20,1,.006,-.01378,-.06665,-.02757,-.05746,0.0*
1,1,.006,-.02757,-.05746*
20,1,.006,-.02757,-.05746,-.03677,-.04137,0.0*
1,1,.006,-.03677,-.04137*
20,1,.006,-.03677,-.04137,-.04136,-.02298,0.0*
1,1,.006,-.04136,-.02298*
20,1,.006,-.04136,-.02298,-.03677,-.0046,0.0*
1,1,.006,-.03677,-.0046*
20,1,.006,-.03677,-.0046,-.02757,.01149,0.0*
1,1,.006,-.02757,.01149*
20,1,.006,-.02757,.01149,-.01378,.02068,0.0*
1,1,.006,-.01378,.02068*
20,1,.006,-.01378,.02068,.00001,.02298,0.0*
1,1,.006,.00001,.02298*
20,1,.006,.00001,.02298,.0138,.02068,0.0*
1,1,.006,.0138,.02068*
20,1,.006,.0138,.02068,.02759,.01149,0.0*
1,1,.006,.02759,.01149*
20,1,.006,.02759,.01149,.03678,-.0046,0.0*
1,1,.006,.03678,-.0046*
20,1,.006,.03678,-.0046,.03908,-.02298,0.0*
1,1,.006,.03908,-.02298*
20,1,.006,.03908,-.02298,.03678,-.04137,0.0*
1,1,.006,.03678,-.04137*
20,1,.006,.03678,-.04137,.02759,-.05746,0.0*
1,1,.006,.02759,-.05746*
20,1,.006,.02759,-.05746,.0138,-.06665,0.0*
1,1,.006,.0138,-.06665*
20,1,.006,.0138,-.06665,.00001,-.06895,0.0*
1,1,.006,.00001,-.06895*
1,1,.006,.10574,-.06895*
20,1,.006,.10574,-.06895,.10574,.02298,0.0*
1,1,.006,.10574,.02298*
1,1,.006,.10574,.0046*
20,1,.006,.10574,.0046,.11723,.01379,0.0*
1,1,.006,.11723,.01379*
20,1,.006,.11723,.01379,.12873,.02068,0.0*
1,1,.006,.12873,.02068*
20,1,.006,.12873,.02068,.14482,.02298,0.0*
1,1,.006,.14482,.02298*
20,1,.006,.14482,.02298,.1563,.02068,0.0*
1,1,.006,.1563,.02068*
20,1,.006,.1563,.02068,.1701,.01379,0.0*
1,1,.006,.1701,.01379*
%
%ADD15MACRO15*%
%AMMACRO10*
1,1,.006,.045771,-.1105*
20,1,.006,.045771,-.1105,-.045771,-.1105,0.0*
1,1,.006,-.045771,-.1105*
20,1,.006,-.045771,-.1105,-.1105,-.045771,0.0*
1,1,.006,-.1105,-.045771*
20,1,.006,-.1105,-.045771,-.1105,.045771,0.0*
1,1,.006,-.1105,.045771*
20,1,.006,-.1105,.045771,-.045771,.1105,0.0*
1,1,.006,-.045771,.1105*
20,1,.006,-.045771,.1105,.045771,.1105,0.0*
1,1,.006,.045771,.1105*
20,1,.006,.045771,.1105,.1105,.045771,0.0*
1,1,.006,.1105,.045771*
20,1,.006,.1105,.045771,.1105,-.045771,0.0*
1,1,.006,.1105,-.045771*
20,1,.006,.1105,-.045771,.045771,-.1105,0.0*
1,1,.006,.045771,-.1105*
1,1,.006,-.08657,.02192*
20,1,.006,-.08657,.02192,-.07999,.0285,0.0*
1,1,.006,-.07999,.0285*
20,1,.006,-.07999,.0285,-.07232,.03178,0.0*
1,1,.006,-.07232,.03178*
20,1,.006,-.07232,.03178,-.06355,.03288,0.0*
1,1,.006,-.06355,.03288*
20,1,.006,-.06355,.03288,-.05259,.03069,0.0*
1,1,.006,-.05259,.03069*
20,1,.006,-.05259,.03069,-.04492,.02521,0.0*
1,1,.006,-.04492,.02521*
20,1,.006,-.04492,.02521,-.04273,.01864,0.0*
1,1,.006,-.04273,.01864*
20,1,.006,-.04273,.01864,-.04383,.01206,0.0*
1,1,.006,-.04383,.01206*
20,1,.006,-.04383,.01206,-.04821,.00658,0.0*
1,1,.006,-.04821,.00658*
20,1,.006,-.04821,.00658,-.07013,-.00438,0.0*
1,1,.006,-.07013,-.00438*
20,1,.006,-.07013,-.00438,-.07999,-.01205,0.0*
1,1,.006,-.07999,-.01205*
20,1,.006,-.07999,-.01205,-.08657,-.02301,0.0*
1,1,.006,-.08657,-.02301*
20,1,.006,-.08657,-.02301,-.08876,-.03287,0.0*
1,1,.006,-.08876,-.03287*
20,1,.006,-.08876,-.03287,-.04273,-.03287,0.0*
1,1,.006,-.04273,-.03287*
1,1,.006,-.02081,.02192*
20,1,.006,-.02081,.02192,-.01423,.0285,0.0*
1,1,.006,-.01423,.0285*
20,1,.006,-.01423,.0285,-.00656,.03178,0.0*
1,1,.006,-.00656,.03178*
20,1,.006,-.00656,.03178,.00221,.03288,0.0*
1,1,.006,.00221,.03288*
20,1,.006,.00221,.03288,.01317,.03069,0.0*
1,1,.006,.01317,.03069*
20,1,.006,.01317,.03069,.02084,.02521,0.0*
1,1,.006,.02084,.02521*
20,1,.006,.02084,.02521,.02303,.01864,0.0*
1,1,.006,.02303,.01864*
20,1,.006,.02303,.01864,.02193,.01206,0.0*
1,1,.006,.02193,.01206*
20,1,.006,.02193,.01206,.01755,.00658,0.0*
1,1,.006,.01755,.00658*
20,1,.006,.01755,.00658,-.00437,-.00438,0.0*
1,1,.006,-.00437,-.00438*
20,1,.006,-.00437,-.00438,-.01423,-.01205,0.0*
1,1,.006,-.01423,-.01205*
20,1,.006,-.01423,-.01205,-.02081,-.02301,0.0*
1,1,.006,-.02081,-.02301*
20,1,.006,-.02081,-.02301,-.023,-.03287,0.0*
1,1,.006,-.023,-.03287*
20,1,.006,-.023,-.03287,.02303,-.03287,0.0*
1,1,.006,.02303,-.03287*
1,1,.006,.06577,-.03287*
20,1,.006,.06577,-.03287,.06577,.03288,0.0*
1,1,.006,.06577,.03288*
20,1,.006,.06577,.03288,.05262,.01973,0.0*
1,1,.006,.05262,.01973*
1,1,.006,.05262,-.03287*
20,1,.006,.05262,-.03287,.07892,-.03287,0.0*
1,1,.006,.07892,-.03287*
%
%ADD10MACRO10*%
%AMMACRO34*
1,1,.006,.044942,-.1085*
20,1,.006,.044942,-.1085,-.044942,-.1085,0.0*
1,1,.006,-.044942,-.1085*
20,1,.006,-.044942,-.1085,-.1085,-.044942,0.0*
1,1,.006,-.1085,-.044942*
20,1,.006,-.1085,-.044942,-.1085,.044942,0.0*
1,1,.006,-.1085,.044942*
20,1,.006,-.1085,.044942,-.044942,.1085,0.0*
1,1,.006,-.044942,.1085*
20,1,.006,-.044942,.1085,.044942,.1085,0.0*
1,1,.006,.044942,.1085*
20,1,.006,.044942,.1085,.1085,.044942,0.0*
1,1,.006,.1085,.044942*
20,1,.006,.1085,.044942,.1085,-.044942,0.0*
1,1,.006,.1085,-.044942*
20,1,.006,.1085,-.044942,.044942,-.1085,0.0*
1,1,.006,.044942,-.1085*
1,1,.006,-.09146,.01076*
20,1,.006,-.09146,.01076,-.07855,-.03228,0.0*
1,1,.006,-.07855,-.03228*
20,1,.006,-.07855,-.03228,-.06456,.01076,0.0*
1,1,.006,-.06456,.01076*
20,1,.006,-.06456,.01076,-.05057,-.03228,0.0*
1,1,.006,-.05057,-.03228*
20,1,.006,-.05057,-.03228,-.03766,.01076,0.0*
1,1,.006,-.03766,.01076*
1,1,.006,.01938,-.0538*
20,1,.006,.01938,-.0538,.01938,.01076,0.0*
1,1,.006,.01938,.01076*
1,1,.006,.01938,.00108*
20,1,.006,.01938,.00108,.014,.00646,0.0*
1,1,.006,.014,.00646*
20,1,.006,.014,.00646,.00754,.00968,0.0*
1,1,.006,.00754,.00968*
20,1,.006,.00754,.00968,.00001,.01076,0.0*
1,1,.006,.00001,.01076*
20,1,.006,.00001,.01076,-.00645,.00968,0.0*
1,1,.006,-.00645,.00968*
20,1,.006,-.00645,.00968,-.01398,.0043,0.0*
1,1,.006,-.01398,.0043*
20,1,.006,-.01398,.0043,-.01828,-.00323,0.0*
1,1,.006,-.01828,-.00323*
20,1,.006,-.01828,-.00323,-.01936,-.01076,0.0*
1,1,.006,-.01936,-.01076*
20,1,.006,-.01936,-.01076,-.01828,-.01829,0.0*
1,1,.006,-.01828,-.01829*
20,1,.006,-.01828,-.01829,-.01398,-.02583,0.0*
1,1,.006,-.01398,-.02583*
20,1,.006,-.01398,-.02583,-.00645,-.0312,0.0*
1,1,.006,-.00645,-.0312*
20,1,.006,-.00645,-.0312,.00001,-.03228,0.0*
1,1,.006,.00001,-.03228*
20,1,.006,.00001,-.03228,.00754,-.0312,0.0*
1,1,.006,.00754,-.0312*
20,1,.006,.00754,-.0312,.014,-.02798,0.0*
1,1,.006,.014,-.02798*
20,1,.006,.014,-.02798,.01938,-.0226,0.0*
1,1,.006,.01938,-.0226*
1,1,.006,.04629,.01076*
20,1,.006,.04629,.01076,.04629,-.01937,0.0*
1,1,.006,.04629,-.01937*
20,1,.006,.04629,-.01937,.05059,-.0269,0.0*
1,1,.006,.05059,-.0269*
20,1,.006,.05059,-.0269,.05705,-.0312,0.0*
1,1,.006,.05705,-.0312*
20,1,.006,.05705,-.0312,.06458,-.03228,0.0*
1,1,.006,.06458,-.03228*
20,1,.006,.06458,-.03228,.07211,-.0312,0.0*
1,1,.006,.07211,-.0312*
20,1,.006,.07211,-.0312,.07857,-.0269,0.0*
1,1,.006,.07857,-.0269*
20,1,.006,.07857,-.0269,.08287,-.01937,0.0*
1,1,.006,.08287,-.01937*
1,1,.006,.08287,-.03228*
20,1,.006,.08287,-.03228,.08287,.01076,0.0*
1,1,.006,.08287,.01076*
%
%ADD34MACRO34*%
%AMMACRO12*
1,1,.006,.035,0.0*
20,1,.006,.035,0.0,.034468,-.006078,0.0*
1,1,.006,.034468,-.006078*
20,1,.006,.034468,-.006078,.032889,-.011971,0.0*
1,1,.006,.032889,-.011971*
20,1,.006,.032889,-.011971,.030311,-.0175,0.0*
1,1,.006,.030311,-.0175*
20,1,.006,.030311,-.0175,.026812,-.022498,0.0*
1,1,.006,.026812,-.022498*
20,1,.006,.026812,-.022498,.022498,-.026812,0.0*
1,1,.006,.022498,-.026812*
20,1,.006,.022498,-.026812,.0175,-.030311,0.0*
1,1,.006,.0175,-.030311*
20,1,.006,.0175,-.030311,.011971,-.032889,0.0*
1,1,.006,.011971,-.032889*
20,1,.006,.011971,-.032889,.006078,-.034468,0.0*
1,1,.006,.006078,-.034468*
20,1,.006,.006078,-.034468,0.0,-.035,0.0*
1,1,.006,0.0,-.035*
20,1,.006,0.0,-.035,-.006078,-.034468,0.0*
1,1,.006,-.006078,-.034468*
20,1,.006,-.006078,-.034468,-.011971,-.032889,0.0*
1,1,.006,-.011971,-.032889*
20,1,.006,-.011971,-.032889,-.0175,-.030311,0.0*
1,1,.006,-.0175,-.030311*
20,1,.006,-.0175,-.030311,-.022498,-.026812,0.0*
1,1,.006,-.022498,-.026812*
20,1,.006,-.022498,-.026812,-.026812,-.022498,0.0*
1,1,.006,-.026812,-.022498*
20,1,.006,-.026812,-.022498,-.030311,-.0175,0.0*
1,1,.006,-.030311,-.0175*
20,1,.006,-.030311,-.0175,-.032889,-.011971,0.0*
1,1,.006,-.032889,-.011971*
20,1,.006,-.032889,-.011971,-.034468,-.006078,0.0*
1,1,.006,-.034468,-.006078*
20,1,.006,-.034468,-.006078,-.035,0.0,0.0*
1,1,.006,-.035,0.0*
20,1,.006,-.035,0.0,-.034468,.006078,0.0*
1,1,.006,-.034468,.006078*
20,1,.006,-.034468,.006078,-.032889,.011971,0.0*
1,1,.006,-.032889,.011971*
20,1,.006,-.032889,.011971,-.030311,.0175,0.0*
1,1,.006,-.030311,.0175*
20,1,.006,-.030311,.0175,-.026812,.022498,0.0*
1,1,.006,-.026812,.022498*
20,1,.006,-.026812,.022498,-.022498,.026812,0.0*
1,1,.006,-.022498,.026812*
20,1,.006,-.022498,.026812,-.0175,.030311,0.0*
1,1,.006,-.0175,.030311*
20,1,.006,-.0175,.030311,-.011971,.032889,0.0*
1,1,.006,-.011971,.032889*
20,1,.006,-.011971,.032889,-.006078,.034468,0.0*
1,1,.006,-.006078,.034468*
20,1,.006,-.006078,.034468,0.0,.035,0.0*
1,1,.006,0.0,.035*
20,1,.006,0.0,.035,.006078,.034468,0.0*
1,1,.006,.006078,.034468*
20,1,.006,.006078,.034468,.011971,.032889,0.0*
1,1,.006,.011971,.032889*
20,1,.006,.011971,.032889,.0175,.030311,0.0*
1,1,.006,.0175,.030311*
20,1,.006,.0175,.030311,.022498,.026812,0.0*
1,1,.006,.022498,.026812*
20,1,.006,.022498,.026812,.026812,.022498,0.0*
1,1,.006,.026812,.022498*
20,1,.006,.026812,.022498,.030311,.0175,0.0*
1,1,.006,.030311,.0175*
20,1,.006,.030311,.0175,.032889,.011971,0.0*
1,1,.006,.032889,.011971*
20,1,.006,.032889,.011971,.034468,.006078,0.0*
1,1,.006,.034468,.006078*
20,1,.006,.034468,.006078,.035,0.0,0.0*
1,1,.006,.035,0.0*
1,1,.006,-.02082,.01041*
20,1,.006,-.02082,.01041,-.02082,-.01041,0.0*
1,1,.006,-.02082,-.01041*
1,1,.006,-.0288,.01041*
20,1,.006,-.0288,.01041,-.01284,.01041,0.0*
1,1,.006,-.01284,.01041*
1,1,.006,-.00693,-.01041*
20,1,.006,-.00693,-.01041,-.00693,.01041,0.0*
1,1,.006,-.00693,.01041*
20,1,.006,-.00693,.01041,.0014,.01041,0.0*
1,1,.006,.0014,.01041*
20,1,.006,.0014,.01041,.00417,.00937,0.0*
1,1,.006,.00417,.00937*
20,1,.006,.00417,.00937,.00626,.00694,0.0*
1,1,.006,.00626,.00694*
20,1,.006,.00626,.00694,.00695,.00416,0.0*
1,1,.006,.00695,.00416*
20,1,.006,.00695,.00416,.00626,.00139,0.0*
1,1,.006,.00626,.00139*
20,1,.006,.00626,.00139,.00452,-.00069,0.0*
1,1,.006,.00452,-.00069*
20,1,.006,.00452,-.00069,.0014,-.00174,0.0*
1,1,.006,.0014,-.00174*
20,1,.006,.0014,-.00174,-.00693,-.00174,0.0*
1,1,.006,-.00693,-.00174*
1,1,.006,.01216,.01041*
20,1,.006,.01216,.01041,.02084,-.01041,0.0*
1,1,.006,.02084,-.01041*
20,1,.006,.02084,-.01041,.02952,.01041,0.0*
1,1,.006,.02952,.01041*
%
%ADD12MACRO12*%
%AMMACRO33*
1,1,.006,.035,.035*
20,1,.006,.035,.035,.035,-.035,0.0*
1,1,.006,.035,-.035*
20,1,.006,.035,-.035,-.035,-.035,0.0*
1,1,.006,-.035,-.035*
20,1,.006,-.035,-.035,-.035,.035,0.0*
1,1,.006,-.035,.035*
20,1,.006,-.035,.035,.035,.035,0.0*
1,1,.006,.035,.035*
1,1,.006,-.0245,.01225*
20,1,.006,-.0245,.01225,-.02777,.01143,0.0*
1,1,.006,-.02777,.01143*
20,1,.006,-.02777,.01143,-.03022,.00939,0.0*
1,1,.006,-.03022,.00939*
20,1,.006,-.03022,.00939,-.03185,.00694,0.0*
1,1,.006,-.03185,.00694*
20,1,.006,-.03185,.00694,-.03308,.00367,0.0*
1,1,.006,-.03308,.00367*
20,1,.006,-.03308,.00367,-.03348,0.0,0.0*
1,1,.006,-.03348,0.0*
20,1,.006,-.03348,0.0,-.03308,-.00368,0.0*
1,1,.006,-.03308,-.00368*
20,1,.006,-.03308,-.00368,-.03185,-.00694,0.0*
1,1,.006,-.03185,-.00694*
20,1,.006,-.03185,-.00694,-.03022,-.00939,0.0*
1,1,.006,-.03022,-.00939*
20,1,.006,-.03022,-.00939,-.02777,-.01143,0.0*
1,1,.006,-.02777,-.01143*
20,1,.006,-.02777,-.01143,-.0245,-.01225,0.0*
1,1,.006,-.0245,-.01225*
20,1,.006,-.0245,-.01225,-.02123,-.01143,0.0*
1,1,.006,-.02123,-.01143*
20,1,.006,-.02123,-.01143,-.01878,-.00939,0.0*
1,1,.006,-.01878,-.00939*
20,1,.006,-.01878,-.00939,-.01715,-.00694,0.0*
1,1,.006,-.01715,-.00694*
20,1,.006,-.01715,-.00694,-.01592,-.00368,0.0*
1,1,.006,-.01592,-.00368*
20,1,.006,-.01592,-.00368,-.01552,0.0,0.0*
1,1,.006,-.01552,0.0*
20,1,.006,-.01552,0.0,-.01592,.00367,0.0*
1,1,.006,-.01592,.00367*
20,1,.006,-.01592,.00367,-.01715,.00694,0.0*
1,1,.006,-.01715,.00694*
20,1,.006,-.01715,.00694,-.01878,.00939,0.0*
1,1,.006,-.01878,.00939*
20,1,.006,-.01878,.00939,-.02123,.01143,0.0*
1,1,.006,-.02123,.01143*
20,1,.006,-.02123,.01143,-.0245,.01225,0.0*
1,1,.006,-.0245,.01225*
1,1,.006,-.00775,.00817*
20,1,.006,-.00775,.00817,-.0053,.01062,0.0*
1,1,.006,-.0053,.01062*
20,1,.006,-.0053,.01062,-.00244,.01184,0.0*
1,1,.006,-.00244,.01184*
20,1,.006,-.00244,.01184,.00083,.01225,0.0*
1,1,.006,.00083,.01225*
20,1,.006,.00083,.01225,.00491,.01143,0.0*
1,1,.006,.00491,.01143*
20,1,.006,.00491,.01143,.00777,.00939,0.0*
1,1,.006,.00777,.00939*
20,1,.006,.00777,.00939,.00859,.00694,0.0*
1,1,.006,.00859,.00694*
20,1,.006,.00859,.00694,.00818,.00449,0.0*
1,1,.006,.00818,.00449*
20,1,.006,.00818,.00449,.00654,.00245,0.0*
1,1,.006,.00654,.00245*
20,1,.006,.00654,.00245,-.00162,-.00163,0.0*
1,1,.006,-.00162,-.00163*
20,1,.006,-.00162,-.00163,-.0053,-.00449,0.0*
1,1,.006,-.0053,-.00449*
20,1,.006,-.0053,-.00449,-.00775,-.00858,0.0*
1,1,.006,-.00775,-.00858*
20,1,.006,-.00775,-.00858,-.00857,-.01225,0.0*
1,1,.006,-.00857,-.01225*
20,1,.006,-.00857,-.01225,.00859,-.01225,0.0*
1,1,.006,.00859,-.01225*
1,1,.006,.01676,.00817*
20,1,.006,.01676,.00817,.01921,.01062,0.0*
1,1,.006,.01921,.01062*
20,1,.006,.01921,.01062,.02207,.01184,0.0*
1,1,.006,.02207,.01184*
20,1,.006,.02207,.01184,.02534,.01225,0.0*
1,1,.006,.02534,.01225*
20,1,.006,.02534,.01225,.02942,.01143,0.0*
1,1,.006,.02942,.01143*
20,1,.006,.02942,.01143,.03228,.00939,0.0*
1,1,.006,.03228,.00939*
20,1,.006,.03228,.00939,.0331,.00694,0.0*
1,1,.006,.0331,.00694*
20,1,.006,.0331,.00694,.03269,.00449,0.0*
1,1,.006,.03269,.00449*
20,1,.006,.03269,.00449,.03105,.00245,0.0*
1,1,.006,.03105,.00245*
20,1,.006,.03105,.00245,.02289,-.00163,0.0*
1,1,.006,.02289,-.00163*
20,1,.006,.02289,-.00163,.01921,-.00449,0.0*
1,1,.006,.01921,-.00449*
20,1,.006,.01921,-.00449,.01676,-.00858,0.0*
1,1,.006,.01676,-.00858*
20,1,.006,.01676,-.00858,.01594,-.01225,0.0*
1,1,.006,.01594,-.01225*
20,1,.006,.01594,-.01225,.0331,-.01225,0.0*
1,1,.006,.0331,-.01225*
%
%ADD33MACRO33*%
%AMMACRO22*
1,1,.006,.035,.035*
20,1,.006,.035,.035,.035,-.035,0.0*
1,1,.006,.035,-.035*
20,1,.006,.035,-.035,-.035,-.035,0.0*
1,1,.006,-.035,-.035*
20,1,.006,-.035,-.035,-.035,.035,0.0*
1,1,.006,-.035,.035*
20,1,.006,-.035,.035,.035,.035,0.0*
1,1,.006,.035,.035*
1,1,.006,-.0245,.01225*
20,1,.006,-.0245,.01225,-.02777,.01143,0.0*
1,1,.006,-.02777,.01143*
20,1,.006,-.02777,.01143,-.03022,.00939,0.0*
1,1,.006,-.03022,.00939*
20,1,.006,-.03022,.00939,-.03185,.00694,0.0*
1,1,.006,-.03185,.00694*
20,1,.006,-.03185,.00694,-.03308,.00367,0.0*
1,1,.006,-.03308,.00367*
20,1,.006,-.03308,.00367,-.03348,0.0,0.0*
1,1,.006,-.03348,0.0*
20,1,.006,-.03348,0.0,-.03308,-.00368,0.0*
1,1,.006,-.03308,-.00368*
20,1,.006,-.03308,-.00368,-.03185,-.00694,0.0*
1,1,.006,-.03185,-.00694*
20,1,.006,-.03185,-.00694,-.03022,-.00939,0.0*
1,1,.006,-.03022,-.00939*
20,1,.006,-.03022,-.00939,-.02777,-.01143,0.0*
1,1,.006,-.02777,-.01143*
20,1,.006,-.02777,-.01143,-.0245,-.01225,0.0*
1,1,.006,-.0245,-.01225*
20,1,.006,-.0245,-.01225,-.02123,-.01143,0.0*
1,1,.006,-.02123,-.01143*
20,1,.006,-.02123,-.01143,-.01878,-.00939,0.0*
1,1,.006,-.01878,-.00939*
20,1,.006,-.01878,-.00939,-.01715,-.00694,0.0*
1,1,.006,-.01715,-.00694*
20,1,.006,-.01715,-.00694,-.01592,-.00368,0.0*
1,1,.006,-.01592,-.00368*
20,1,.006,-.01592,-.00368,-.01552,0.0,0.0*
1,1,.006,-.01552,0.0*
20,1,.006,-.01552,0.0,-.01592,.00367,0.0*
1,1,.006,-.01592,.00367*
20,1,.006,-.01592,.00367,-.01715,.00694,0.0*
1,1,.006,-.01715,.00694*
20,1,.006,-.01715,.00694,-.01878,.00939,0.0*
1,1,.006,-.01878,.00939*
20,1,.006,-.01878,.00939,-.02123,.01143,0.0*
1,1,.006,-.02123,.01143*
20,1,.006,-.02123,.01143,-.0245,.01225,0.0*
1,1,.006,-.0245,.01225*
1,1,.006,.00491,-.01225*
20,1,.006,.00491,-.01225,.00491,.01225,0.0*
1,1,.006,.00491,.01225*
20,1,.006,.00491,.01225,-.0102,-.00531,0.0*
1,1,.006,-.0102,-.00531*
20,1,.006,-.0102,-.00531,.01022,-.00531,0.0*
1,1,.006,.01022,-.00531*
1,1,.006,.02452,.01225*
20,1,.006,.02452,.01225,.02125,.01143,0.0*
1,1,.006,.02125,.01143*
20,1,.006,.02125,.01143,.0188,.00939,0.0*
1,1,.006,.0188,.00939*
20,1,.006,.0188,.00939,.01717,.00694,0.0*
1,1,.006,.01717,.00694*
20,1,.006,.01717,.00694,.01594,.00367,0.0*
1,1,.006,.01594,.00367*
20,1,.006,.01594,.00367,.01554,0.0,0.0*
1,1,.006,.01554,0.0*
20,1,.006,.01554,0.0,.01594,-.00368,0.0*
1,1,.006,.01594,-.00368*
20,1,.006,.01594,-.00368,.01717,-.00694,0.0*
1,1,.006,.01717,-.00694*
20,1,.006,.01717,-.00694,.0188,-.00939,0.0*
1,1,.006,.0188,-.00939*
20,1,.006,.0188,-.00939,.02125,-.01143,0.0*
1,1,.006,.02125,-.01143*
20,1,.006,.02125,-.01143,.02452,-.01225,0.0*
1,1,.006,.02452,-.01225*
20,1,.006,.02452,-.01225,.02779,-.01143,0.0*
1,1,.006,.02779,-.01143*
20,1,.006,.02779,-.01143,.03024,-.00939,0.0*
1,1,.006,.03024,-.00939*
20,1,.006,.03024,-.00939,.03187,-.00694,0.0*
1,1,.006,.03187,-.00694*
20,1,.006,.03187,-.00694,.0331,-.00368,0.0*
1,1,.006,.0331,-.00368*
20,1,.006,.0331,-.00368,.0335,0.0,0.0*
1,1,.006,.0335,0.0*
20,1,.006,.0335,0.0,.0331,.00367,0.0*
1,1,.006,.0331,.00367*
20,1,.006,.0331,.00367,.03187,.00694,0.0*
1,1,.006,.03187,.00694*
20,1,.006,.03187,.00694,.03024,.00939,0.0*
1,1,.006,.03024,.00939*
20,1,.006,.03024,.00939,.02779,.01143,0.0*
1,1,.006,.02779,.01143*
20,1,.006,.02779,.01143,.02452,.01225,0.0*
1,1,.006,.02452,.01225*
%
%ADD22MACRO22*%
%AMMACRO39*
1,1,.006,-.166,-.083*
20,1,.006,-.166,-.083,-.166,.083,0.0*
1,1,.006,-.166,.083*
20,1,.006,-.166,.083,-.1992,.0498,0.0*
1,1,.006,-.1992,.0498*
1,1,.006,-.1992,-.083*
20,1,.006,-.1992,-.083,-.1328,-.083,0.0*
1,1,.006,-.1328,-.083*
1,1,.006,-.05256,-.01384*
20,1,.006,-.05256,-.01384,-.03319,.00553,0.0*
1,1,.006,-.03319,.00553*
20,1,.006,-.03319,.00553,-.01659,.0166,0.0*
1,1,.006,-.01659,.0166*
20,1,.006,-.01659,.0166,.00554,.02213,0.0*
1,1,.006,.00554,.02213*
20,1,.006,.00554,.02213,.02491,.0166,0.0*
1,1,.006,.02491,.0166*
20,1,.006,.02491,.0166,.03874,.00553,0.0*
1,1,.006,.03874,.00553*
20,1,.006,.03874,.00553,.04981,-.01107,0.0*
1,1,.006,.04981,-.01107*
20,1,.006,.04981,-.01107,.05258,-.03043,0.0*
1,1,.006,.05258,-.03043*
20,1,.006,.05258,-.03043,.04981,-.04704,0.0*
1,1,.006,.04981,-.04704*
20,1,.006,.04981,-.04704,.03874,-.06364,0.0*
1,1,.006,.03874,-.06364*
20,1,.006,.03874,-.06364,.02214,-.07747,0.0*
1,1,.006,.02214,-.07747*
20,1,.006,.02214,-.07747,.00278,-.083,0.0*
1,1,.006,.00278,-.083*
20,1,.006,.00278,-.083,-.01936,-.07747,0.0*
1,1,.006,-.01936,-.07747*
20,1,.006,-.01936,-.07747,-.03872,-.06087,0.0*
1,1,.006,-.03872,-.06087*
20,1,.006,-.03872,-.06087,-.04979,-.03597,0.0*
1,1,.006,-.04979,-.03597*
20,1,.006,-.04979,-.03597,-.05256,-.0083,0.0*
1,1,.006,-.05256,-.0083*
20,1,.006,-.05256,-.0083,-.04703,.02766,0.0*
1,1,.006,-.04703,.02766*
20,1,.006,-.04703,.02766,-.03872,.04704,0.0*
1,1,.006,-.03872,.04704*
20,1,.006,-.03872,.04704,-.02489,.0664,0.0*
1,1,.006,-.02489,.0664*
20,1,.006,-.02489,.0664,-.00552,.08023,0.0*
1,1,.006,-.00552,.08023*
20,1,.006,-.00552,.08023,.01384,.083,0.0*
1,1,.006,.01384,.083*
20,1,.006,.01384,.083,.03321,.07747,0.0*
1,1,.006,.03321,.07747*
20,1,.006,.03321,.07747,.04705,.06363,0.0*
1,1,.006,.04705,.06363*
1,1,.006,.11345,-.01384*
20,1,.006,.11345,-.01384,.13282,.00553,0.0*
1,1,.006,.13282,.00553*
20,1,.006,.13282,.00553,.14942,.0166,0.0*
1,1,.006,.14942,.0166*
20,1,.006,.14942,.0166,.17155,.02213,0.0*
1,1,.006,.17155,.02213*
20,1,.006,.17155,.02213,.19092,.0166,0.0*
1,1,.006,.19092,.0166*
20,1,.006,.19092,.0166,.20475,.00553,0.0*
1,1,.006,.20475,.00553*
20,1,.006,.20475,.00553,.21582,-.01107,0.0*
1,1,.006,.21582,-.01107*
20,1,.006,.21582,-.01107,.21859,-.03043,0.0*
1,1,.006,.21859,-.03043*
20,1,.006,.21859,-.03043,.21582,-.04704,0.0*
1,1,.006,.21582,-.04704*
20,1,.006,.21582,-.04704,.20475,-.06364,0.0*
1,1,.006,.20475,-.06364*
20,1,.006,.20475,-.06364,.18815,-.07747,0.0*
1,1,.006,.18815,-.07747*
20,1,.006,.18815,-.07747,.16879,-.083,0.0*
1,1,.006,.16879,-.083*
20,1,.006,.16879,-.083,.14665,-.07747,0.0*
1,1,.006,.14665,-.07747*
20,1,.006,.14665,-.07747,.12729,-.06087,0.0*
1,1,.006,.12729,-.06087*
20,1,.006,.12729,-.06087,.11622,-.03597,0.0*
1,1,.006,.11622,-.03597*
20,1,.006,.11622,-.03597,.11345,-.0083,0.0*
1,1,.006,.11345,-.0083*
20,1,.006,.11345,-.0083,.11898,.02766,0.0*
1,1,.006,.11898,.02766*
20,1,.006,.11898,.02766,.12729,.04704,0.0*
1,1,.006,.12729,.04704*
20,1,.006,.12729,.04704,.14112,.0664,0.0*
1,1,.006,.14112,.0664*
20,1,.006,.14112,.0664,.16049,.08023,0.0*
1,1,.006,.16049,.08023*
20,1,.006,.16049,.08023,.17985,.083,0.0*
1,1,.006,.17985,.083*
20,1,.006,.17985,.083,.19922,.07747,0.0*
1,1,.006,.19922,.07747*
20,1,.006,.19922,.07747,.21306,.06363,0.0*
1,1,.006,.21306,.06363*
%
%ADD39MACRO39*%
%AMMACRO42*
1,1,.006,.035,0.0*
20,1,.006,.035,0.0,.034468,-.006078,0.0*
1,1,.006,.034468,-.006078*
20,1,.006,.034468,-.006078,.032889,-.011971,0.0*
1,1,.006,.032889,-.011971*
20,1,.006,.032889,-.011971,.030311,-.0175,0.0*
1,1,.006,.030311,-.0175*
20,1,.006,.030311,-.0175,.026812,-.022498,0.0*
1,1,.006,.026812,-.022498*
20,1,.006,.026812,-.022498,.022498,-.026812,0.0*
1,1,.006,.022498,-.026812*
20,1,.006,.022498,-.026812,.0175,-.030311,0.0*
1,1,.006,.0175,-.030311*
20,1,.006,.0175,-.030311,.011971,-.032889,0.0*
1,1,.006,.011971,-.032889*
20,1,.006,.011971,-.032889,.006078,-.034468,0.0*
1,1,.006,.006078,-.034468*
20,1,.006,.006078,-.034468,0.0,-.035,0.0*
1,1,.006,0.0,-.035*
20,1,.006,0.0,-.035,-.006078,-.034468,0.0*
1,1,.006,-.006078,-.034468*
20,1,.006,-.006078,-.034468,-.011971,-.032889,0.0*
1,1,.006,-.011971,-.032889*
20,1,.006,-.011971,-.032889,-.0175,-.030311,0.0*
1,1,.006,-.0175,-.030311*
20,1,.006,-.0175,-.030311,-.022498,-.026812,0.0*
1,1,.006,-.022498,-.026812*
20,1,.006,-.022498,-.026812,-.026812,-.022498,0.0*
1,1,.006,-.026812,-.022498*
20,1,.006,-.026812,-.022498,-.030311,-.0175,0.0*
1,1,.006,-.030311,-.0175*
20,1,.006,-.030311,-.0175,-.032889,-.011971,0.0*
1,1,.006,-.032889,-.011971*
20,1,.006,-.032889,-.011971,-.034468,-.006078,0.0*
1,1,.006,-.034468,-.006078*
20,1,.006,-.034468,-.006078,-.035,0.0,0.0*
1,1,.006,-.035,0.0*
20,1,.006,-.035,0.0,-.034468,.006078,0.0*
1,1,.006,-.034468,.006078*
20,1,.006,-.034468,.006078,-.032889,.011971,0.0*
1,1,.006,-.032889,.011971*
20,1,.006,-.032889,.011971,-.030311,.0175,0.0*
1,1,.006,-.030311,.0175*
20,1,.006,-.030311,.0175,-.026812,.022498,0.0*
1,1,.006,-.026812,.022498*
20,1,.006,-.026812,.022498,-.022498,.026812,0.0*
1,1,.006,-.022498,.026812*
20,1,.006,-.022498,.026812,-.0175,.030311,0.0*
1,1,.006,-.0175,.030311*
20,1,.006,-.0175,.030311,-.011971,.032889,0.0*
1,1,.006,-.011971,.032889*
20,1,.006,-.011971,.032889,-.006078,.034468,0.0*
1,1,.006,-.006078,.034468*
20,1,.006,-.006078,.034468,0.0,.035,0.0*
1,1,.006,0.0,.035*
20,1,.006,0.0,.035,.006078,.034468,0.0*
1,1,.006,.006078,.034468*
20,1,.006,.006078,.034468,.011971,.032889,0.0*
1,1,.006,.011971,.032889*
20,1,.006,.011971,.032889,.0175,.030311,0.0*
1,1,.006,.0175,.030311*
20,1,.006,.0175,.030311,.022498,.026812,0.0*
1,1,.006,.022498,.026812*
20,1,.006,.022498,.026812,.026812,.022498,0.0*
1,1,.006,.026812,.022498*
20,1,.006,.026812,.022498,.030311,.0175,0.0*
1,1,.006,.030311,.0175*
20,1,.006,.030311,.0175,.032889,.011971,0.0*
1,1,.006,.032889,.011971*
20,1,.006,.032889,.011971,.034468,.006078,0.0*
1,1,.006,.034468,.006078*
20,1,.006,.034468,.006078,.035,0.0,0.0*
1,1,.006,.035,0.0*
1,1,.006,-.01488,.01488*
20,1,.006,-.01488,.01488,-.01488,-.01487,0.0*
1,1,.006,-.01488,-.01487*
1,1,.006,-.02628,.01488*
20,1,.006,-.02628,.01488,-.00347,.01488,0.0*
1,1,.006,-.00347,.01488*
1,1,.006,.00497,-.01487*
20,1,.006,.00497,-.01487,.00497,.01488,0.0*
1,1,.006,.00497,.01488*
20,1,.006,.00497,.01488,.01687,.01488,0.0*
1,1,.006,.01687,.01488*
20,1,.006,.01687,.01488,.02084,.01339,0.0*
1,1,.006,.02084,.01339*
20,1,.006,.02084,.01339,.02381,.00992,0.0*
1,1,.006,.02381,.00992*
20,1,.006,.02381,.00992,.0248,.00596,0.0*
1,1,.006,.0248,.00596*
20,1,.006,.0248,.00596,.02381,.00199,0.0*
1,1,.006,.02381,.00199*
20,1,.006,.02381,.00199,.02133,-.00099,0.0*
1,1,.006,.02133,-.00099*
20,1,.006,.02133,-.00099,.01687,-.00247,0.0*
1,1,.006,.01687,-.00247*
20,1,.006,.01687,-.00247,.00497,-.00247,0.0*
1,1,.006,.00497,-.00247*
%
%ADD42MACRO42*%
%AMMACRO38*
1,1,.006,-.0275,.1*
20,1,.006,-.0275,.1,.0275,.1,0.0*
1,1,.006,.0275,.1*
20,1,.006,.0275,.1,.044865,.098481,0.0*
1,1,.006,.044865,.098481*
20,1,.006,.044865,.098481,.061702,.093969,0.0*
1,1,.006,.061702,.093969*
20,1,.006,.061702,.093969,.0775,.086603,0.0*
1,1,.006,.0775,.086603*
20,1,.006,.0775,.086603,.091779,.076604,0.0*
1,1,.006,.091779,.076604*
20,1,.006,.091779,.076604,.104104,.064279,0.0*
1,1,.006,.104104,.064279*
20,1,.006,.104104,.064279,.114103,.05,0.0*
1,1,.006,.114103,.05*
20,1,.006,.114103,.05,.121469,.034202,0.0*
1,1,.006,.121469,.034202*
20,1,.006,.121469,.034202,.125981,.017365,0.0*
1,1,.006,.125981,.017365*
20,1,.006,.125981,.017365,.1275,0.0,0.0*
1,1,.006,.1275,0.0*
20,1,.006,.1275,0.0,.125981,-.017365,0.0*
1,1,.006,.125981,-.017365*
20,1,.006,.125981,-.017365,.121469,-.034202,0.0*
1,1,.006,.121469,-.034202*
20,1,.006,.121469,-.034202,.114103,-.05,0.0*
1,1,.006,.114103,-.05*
20,1,.006,.114103,-.05,.104104,-.064279,0.0*
1,1,.006,.104104,-.064279*
20,1,.006,.104104,-.064279,.091779,-.076604,0.0*
1,1,.006,.091779,-.076604*
20,1,.006,.091779,-.076604,.0775,-.086603,0.0*
1,1,.006,.0775,-.086603*
20,1,.006,.0775,-.086603,.061702,-.093969,0.0*
1,1,.006,.061702,-.093969*
20,1,.006,.061702,-.093969,.044865,-.098481,0.0*
1,1,.006,.044865,-.098481*
20,1,.006,.044865,-.098481,.0275,-.1,0.0*
1,1,.006,.0275,-.1*
20,1,.006,.0275,-.1,-.0275,-.1,0.0*
1,1,.006,-.0275,-.1*
20,1,.006,-.0275,-.1,-.044865,-.098481,0.0*
1,1,.006,-.044865,-.098481*
20,1,.006,-.044865,-.098481,-.061702,-.093969,0.0*
1,1,.006,-.061702,-.093969*
20,1,.006,-.061702,-.093969,-.0775,-.086603,0.0*
1,1,.006,-.0775,-.086603*
20,1,.006,-.0775,-.086603,-.091779,-.076604,0.0*
1,1,.006,-.091779,-.076604*
20,1,.006,-.091779,-.076604,-.104104,-.064279,0.0*
1,1,.006,-.104104,-.064279*
20,1,.006,-.104104,-.064279,-.114103,-.05,0.0*
1,1,.006,-.114103,-.05*
20,1,.006,-.114103,-.05,-.121469,-.034202,0.0*
1,1,.006,-.121469,-.034202*
20,1,.006,-.121469,-.034202,-.125981,-.017365,0.0*
1,1,.006,-.125981,-.017365*
20,1,.006,-.125981,-.017365,-.1275,0.0,0.0*
1,1,.006,-.1275,0.0*
20,1,.006,-.1275,0.0,-.125981,.017365,0.0*
1,1,.006,-.125981,.017365*
20,1,.006,-.125981,.017365,-.121469,.034202,0.0*
1,1,.006,-.121469,.034202*
20,1,.006,-.121469,.034202,-.114103,.05,0.0*
1,1,.006,-.114103,.05*
20,1,.006,-.114103,.05,-.104104,.064279,0.0*
1,1,.006,-.104104,.064279*
20,1,.006,-.104104,.064279,-.091779,.076604,0.0*
1,1,.006,-.091779,.076604*
20,1,.006,-.091779,.076604,-.0775,.086603,0.0*
1,1,.006,-.0775,.086603*
20,1,.006,-.0775,.086603,-.061702,.093969,0.0*
1,1,.006,-.061702,.093969*
20,1,.006,-.061702,.093969,-.044865,.098481,0.0*
1,1,.006,-.044865,.098481*
20,1,.006,-.044865,.098481,-.0275,.1,0.0*
1,1,.006,-.0275,.1*
1,1,.006,-.08167,-.05833*
20,1,.006,-.08167,-.05833,-.05833,-.05833,0.0*
1,1,.006,-.05833,-.05833*
20,1,.006,-.05833,-.05833,-.05833,.035,0.0*
1,1,.006,-.05833,.035*
20,1,.006,-.05833,.035,-.08167,.035,0.0*
1,1,.006,-.08167,.035*
1,1,.006,.02334,-.035*
20,1,.006,.02334,-.035,-.02332,-.035,0.0*
1,1,.006,-.02332,-.035*
20,1,.006,-.02332,-.035,-.02332,.035,0.0*
1,1,.006,-.02332,.035*
20,1,.006,-.02332,.035,.02334,.035,0.0*
1,1,.006,.02334,.035*
1,1,.006,.00468,.00117*
20,1,.006,.00468,.00117,-.02332,.00117,0.0*
1,1,.006,-.02332,.00117*
1,1,.006,.09335,-.035*
20,1,.006,.09335,-.035,.04669,-.035,0.0*
1,1,.006,.04669,-.035*
20,1,.006,.04669,-.035,.04669,.035,0.0*
1,1,.006,.04669,.035*
20,1,.006,.04669,.035,.09335,.035,0.0*
1,1,.006,.09335,.035*
1,1,.006,.07469,.00117*
20,1,.006,.07469,.00117,.04669,.00117,0.0*
1,1,.006,.04669,.00117*
%
%ADD38MACRO38*%
%AMMACRO26*
1,1,.006,.0675,0.0*
20,1,.006,.0675,0.0,.03375,.058457,0.0*
1,1,.006,.03375,.058457*
20,1,.006,.03375,.058457,-.03375,.058457,0.0*
1,1,.006,-.03375,.058457*
20,1,.006,-.03375,.058457,-.0675,0.0,0.0*
1,1,.006,-.0675,0.0*
20,1,.006,-.0675,0.0,-.03375,-.058457,0.0*
1,1,.006,-.03375,-.058457*
20,1,.006,-.03375,-.058457,.03375,-.058457,0.0*
1,1,.006,.03375,-.058457*
20,1,.006,.03375,-.058457,.0675,0.0,0.0*
1,1,.006,.0675,0.0*
1,1,.006,-.02314,-.02755*
20,1,.006,-.02314,-.02755,-.02314,.00552,0.0*
1,1,.006,-.02314,.00552*
1,1,.006,-.02314,.00056*
20,1,.006,-.02314,.00056,-.0259,.00331,0.0*
1,1,.006,-.0259,.00331*
20,1,.006,-.0259,.00331,-.02921,.00496,0.0*
1,1,.006,-.02921,.00496*
20,1,.006,-.02921,.00496,-.03307,.00552,0.0*
1,1,.006,-.03307,.00552*
20,1,.006,-.03307,.00552,-.03637,.00496,0.0*
1,1,.006,-.03637,.00496*
20,1,.006,-.03637,.00496,-.04023,.00221,0.0*
1,1,.006,-.04023,.00221*
20,1,.006,-.04023,.00221,-.04244,-.00165,0.0*
1,1,.006,-.04244,-.00165*
20,1,.006,-.04244,-.00165,-.04299,-.00551,0.0*
1,1,.006,-.04299,-.00551*
20,1,.006,-.04299,-.00551,-.04244,-.00937,0.0*
1,1,.006,-.04244,-.00937*
20,1,.006,-.04244,-.00937,-.04023,-.01322,0.0*
1,1,.006,-.04023,-.01322*
20,1,.006,-.04023,-.01322,-.03637,-.01598,0.0*
1,1,.006,-.03637,-.01598*
20,1,.006,-.03637,-.01598,-.03307,-.01653,0.0*
1,1,.006,-.03307,-.01653*
20,1,.006,-.03307,-.01653,-.02921,-.01598,0.0*
1,1,.006,-.02921,-.01598*
20,1,.006,-.02921,-.01598,-.0259,-.01433,0.0*
1,1,.006,-.0259,-.01433*
20,1,.006,-.0259,-.01433,-.02314,-.01157,0.0*
1,1,.006,-.02314,-.01157*
1,1,.006,-.00825,-.00165*
20,1,.006,-.00825,-.00165,.00939,-.00165,0.0*
1,1,.006,.00939,-.00165*
20,1,.006,.00939,-.00165,.00773,.00221,0.0*
1,1,.006,.00773,.00221*
20,1,.006,.00773,.00221,.00498,.00441,0.0*
1,1,.006,.00498,.00441*
20,1,.006,.00498,.00441,.00112,.00552,0.0*
1,1,.006,.00112,.00552*
20,1,.006,.00112,.00552,-.00274,.00496,0.0*
1,1,.006,-.00274,.00496*
20,1,.006,-.00274,.00496,-.00605,.00331,0.0*
1,1,.006,-.00605,.00331*
20,1,.006,-.00605,.00331,-.00825,-.00055,0.0*
1,1,.006,-.00825,-.00055*
20,1,.006,-.00825,-.00055,-.00936,-.00385,0.0*
1,1,.006,-.00936,-.00385*
20,1,.006,-.00936,-.00385,-.00936,-.00716,0.0*
1,1,.006,-.00936,-.00716*
20,1,.006,-.00936,-.00716,-.00825,-.01047,0.0*
1,1,.006,-.00825,-.01047*
20,1,.006,-.00825,-.01047,-.0055,-.01377,0.0*
1,1,.006,-.0055,-.01377*
20,1,.006,-.0055,-.01377,-.00219,-.01598,0.0*
1,1,.006,-.00219,-.01598*
20,1,.006,-.00219,-.01598,.00167,-.01653,0.0*
1,1,.006,.00167,-.01653*
20,1,.006,.00167,-.01653,.00553,-.01543,0.0*
1,1,.006,.00553,-.01543*
20,1,.006,.00553,-.01543,.00939,-.01212,0.0*
1,1,.006,.00939,-.01212*
1,1,.006,.03309,.01654*
20,1,.006,.03309,.01654,.03309,-.01653,0.0*
1,1,.006,.03309,-.01653*
1,1,.006,.02538,.00552*
20,1,.006,.02538,.00552,.04081,.00552,0.0*
1,1,.006,.04081,.00552*
%
%ADD26MACRO26*%
%AMMACRO11*
1,1,.006,.035,0.0*
20,1,.006,.035,0.0,.034468,-.006078,0.0*
1,1,.006,.034468,-.006078*
20,1,.006,.034468,-.006078,.032889,-.011971,0.0*
1,1,.006,.032889,-.011971*
20,1,.006,.032889,-.011971,.030311,-.0175,0.0*
1,1,.006,.030311,-.0175*
20,1,.006,.030311,-.0175,.026812,-.022498,0.0*
1,1,.006,.026812,-.022498*
20,1,.006,.026812,-.022498,.022498,-.026812,0.0*
1,1,.006,.022498,-.026812*
20,1,.006,.022498,-.026812,.0175,-.030311,0.0*
1,1,.006,.0175,-.030311*
20,1,.006,.0175,-.030311,.011971,-.032889,0.0*
1,1,.006,.011971,-.032889*
20,1,.006,.011971,-.032889,.006078,-.034468,0.0*
1,1,.006,.006078,-.034468*
20,1,.006,.006078,-.034468,0.0,-.035,0.0*
1,1,.006,0.0,-.035*
20,1,.006,0.0,-.035,-.006078,-.034468,0.0*
1,1,.006,-.006078,-.034468*
20,1,.006,-.006078,-.034468,-.011971,-.032889,0.0*
1,1,.006,-.011971,-.032889*
20,1,.006,-.011971,-.032889,-.0175,-.030311,0.0*
1,1,.006,-.0175,-.030311*
20,1,.006,-.0175,-.030311,-.022498,-.026812,0.0*
1,1,.006,-.022498,-.026812*
20,1,.006,-.022498,-.026812,-.026812,-.022498,0.0*
1,1,.006,-.026812,-.022498*
20,1,.006,-.026812,-.022498,-.030311,-.0175,0.0*
1,1,.006,-.030311,-.0175*
20,1,.006,-.030311,-.0175,-.032889,-.011971,0.0*
1,1,.006,-.032889,-.011971*
20,1,.006,-.032889,-.011971,-.034468,-.006078,0.0*
1,1,.006,-.034468,-.006078*
20,1,.006,-.034468,-.006078,-.035,0.0,0.0*
1,1,.006,-.035,0.0*
20,1,.006,-.035,0.0,-.034468,.006078,0.0*
1,1,.006,-.034468,.006078*
20,1,.006,-.034468,.006078,-.032889,.011971,0.0*
1,1,.006,-.032889,.011971*
20,1,.006,-.032889,.011971,-.030311,.0175,0.0*
1,1,.006,-.030311,.0175*
20,1,.006,-.030311,.0175,-.026812,.022498,0.0*
1,1,.006,-.026812,.022498*
20,1,.006,-.026812,.022498,-.022498,.026812,0.0*
1,1,.006,-.022498,.026812*
20,1,.006,-.022498,.026812,-.0175,.030311,0.0*
1,1,.006,-.0175,.030311*
20,1,.006,-.0175,.030311,-.011971,.032889,0.0*
1,1,.006,-.011971,.032889*
20,1,.006,-.011971,.032889,-.006078,.034468,0.0*
1,1,.006,-.006078,.034468*
20,1,.006,-.006078,.034468,0.0,.035,0.0*
1,1,.006,0.0,.035*
20,1,.006,0.0,.035,.006078,.034468,0.0*
1,1,.006,.006078,.034468*
20,1,.006,.006078,.034468,.011971,.032889,0.0*
1,1,.006,.011971,.032889*
20,1,.006,.011971,.032889,.0175,.030311,0.0*
1,1,.006,.0175,.030311*
20,1,.006,.0175,.030311,.022498,.026812,0.0*
1,1,.006,.022498,.026812*
20,1,.006,.022498,.026812,.026812,.022498,0.0*
1,1,.006,.026812,.022498*
20,1,.006,.026812,.022498,.030311,.0175,0.0*
1,1,.006,.030311,.0175*
20,1,.006,.030311,.0175,.032889,.011971,0.0*
1,1,.006,.032889,.011971*
20,1,.006,.032889,.011971,.034468,.006078,0.0*
1,1,.006,.034468,.006078*
20,1,.006,.034468,.006078,.035,0.0,0.0*
1,1,.006,.035,0.0*
1,1,.006,-.0295,.01041*
20,1,.006,-.0295,.01041,-.02082,-.01041,0.0*
1,1,.006,-.02082,-.01041*
20,1,.006,-.02082,-.01041,-.01214,.01041,0.0*
1,1,.006,-.01214,.01041*
1,1,.006,.00001,-.01041*
20,1,.006,.00001,-.01041,.00001,.01041,0.0*
1,1,.006,.00001,.01041*
20,1,.006,.00001,.01041,-.00415,.00625,0.0*
1,1,.006,-.00415,.00625*
1,1,.006,-.00415,-.01041*
20,1,.006,-.00415,-.01041,.00417,-.01041,0.0*
1,1,.006,.00417,-.01041*
1,1,.006,.02084,.01041*
20,1,.006,.02084,.01041,.01806,.00972,0.0*
1,1,.006,.01806,.00972*
20,1,.006,.01806,.00972,.01598,.00798,0.0*
1,1,.006,.01598,.00798*
20,1,.006,.01598,.00798,.01459,.0059,0.0*
1,1,.006,.01459,.0059*
20,1,.006,.01459,.0059,.01355,.00312,0.0*
1,1,.006,.01355,.00312*
20,1,.006,.01355,.00312,.01321,0.0,0.0*
1,1,.006,.01321,0.0*
20,1,.006,.01321,0.0,.01355,-.00312,0.0*
1,1,.006,.01355,-.00312*
20,1,.006,.01355,-.00312,.01459,-.0059,0.0*
1,1,.006,.01459,-.0059*
20,1,.006,.01459,-.0059,.01598,-.00798,0.0*
1,1,.006,.01598,-.00798*
20,1,.006,.01598,-.00798,.01806,-.00972,0.0*
1,1,.006,.01806,-.00972*
20,1,.006,.01806,-.00972,.02084,-.01041,0.0*
1,1,.006,.02084,-.01041*
20,1,.006,.02084,-.01041,.02362,-.00972,0.0*
1,1,.006,.02362,-.00972*
20,1,.006,.02362,-.00972,.0257,-.00798,0.0*
1,1,.006,.0257,-.00798*
20,1,.006,.0257,-.00798,.02709,-.0059,0.0*
1,1,.006,.02709,-.0059*
20,1,.006,.02709,-.0059,.02813,-.00312,0.0*
1,1,.006,.02813,-.00312*
20,1,.006,.02813,-.00312,.02847,0.0,0.0*
1,1,.006,.02847,0.0*
20,1,.006,.02847,0.0,.02813,.00312,0.0*
1,1,.006,.02813,.00312*
20,1,.006,.02813,.00312,.02709,.0059,0.0*
1,1,.006,.02709,.0059*
20,1,.006,.02709,.0059,.0257,.00798,0.0*
1,1,.006,.0257,.00798*
20,1,.006,.0257,.00798,.02362,.00972,0.0*
1,1,.006,.02362,.00972*
20,1,.006,.02362,.00972,.02084,.01041,0.0*
1,1,.006,.02084,.01041*
%
%ADD11MACRO11*%
%ADD13C,.125*%
%AMMACRO14*
1,1,.006,.035,0.0*
20,1,.006,.035,0.0,.034468,-.006078,0.0*
1,1,.006,.034468,-.006078*
20,1,.006,.034468,-.006078,.032889,-.011971,0.0*
1,1,.006,.032889,-.011971*
20,1,.006,.032889,-.011971,.030311,-.0175,0.0*
1,1,.006,.030311,-.0175*
20,1,.006,.030311,-.0175,.026812,-.022498,0.0*
1,1,.006,.026812,-.022498*
20,1,.006,.026812,-.022498,.022498,-.026812,0.0*
1,1,.006,.022498,-.026812*
20,1,.006,.022498,-.026812,.0175,-.030311,0.0*
1,1,.006,.0175,-.030311*
20,1,.006,.0175,-.030311,.011971,-.032889,0.0*
1,1,.006,.011971,-.032889*
20,1,.006,.011971,-.032889,.006078,-.034468,0.0*
1,1,.006,.006078,-.034468*
20,1,.006,.006078,-.034468,0.0,-.035,0.0*
1,1,.006,0.0,-.035*
20,1,.006,0.0,-.035,-.006078,-.034468,0.0*
1,1,.006,-.006078,-.034468*
20,1,.006,-.006078,-.034468,-.011971,-.032889,0.0*
1,1,.006,-.011971,-.032889*
20,1,.006,-.011971,-.032889,-.0175,-.030311,0.0*
1,1,.006,-.0175,-.030311*
20,1,.006,-.0175,-.030311,-.022498,-.026812,0.0*
1,1,.006,-.022498,-.026812*
20,1,.006,-.022498,-.026812,-.026812,-.022498,0.0*
1,1,.006,-.026812,-.022498*
20,1,.006,-.026812,-.022498,-.030311,-.0175,0.0*
1,1,.006,-.030311,-.0175*
20,1,.006,-.030311,-.0175,-.032889,-.011971,0.0*
1,1,.006,-.032889,-.011971*
20,1,.006,-.032889,-.011971,-.034468,-.006078,0.0*
1,1,.006,-.034468,-.006078*
20,1,.006,-.034468,-.006078,-.035,0.0,0.0*
1,1,.006,-.035,0.0*
20,1,.006,-.035,0.0,-.034468,.006078,0.0*
1,1,.006,-.034468,.006078*
20,1,.006,-.034468,.006078,-.032889,.011971,0.0*
1,1,.006,-.032889,.011971*
20,1,.006,-.032889,.011971,-.030311,.0175,0.0*
1,1,.006,-.030311,.0175*
20,1,.006,-.030311,.0175,-.026812,.022498,0.0*
1,1,.006,-.026812,.022498*
20,1,.006,-.026812,.022498,-.022498,.026812,0.0*
1,1,.006,-.022498,.026812*
20,1,.006,-.022498,.026812,-.0175,.030311,0.0*
1,1,.006,-.0175,.030311*
20,1,.006,-.0175,.030311,-.011971,.032889,0.0*
1,1,.006,-.011971,.032889*
20,1,.006,-.011971,.032889,-.006078,.034468,0.0*
1,1,.006,-.006078,.034468*
20,1,.006,-.006078,.034468,0.0,.035,0.0*
1,1,.006,0.0,.035*
20,1,.006,0.0,.035,.006078,.034468,0.0*
1,1,.006,.006078,.034468*
20,1,.006,.006078,.034468,.011971,.032889,0.0*
1,1,.006,.011971,.032889*
20,1,.006,.011971,.032889,.0175,.030311,0.0*
1,1,.006,.0175,.030311*
20,1,.006,.0175,.030311,.022498,.026812,0.0*
1,1,.006,.022498,.026812*
20,1,.006,.022498,.026812,.026812,.022498,0.0*
1,1,.006,.026812,.022498*
20,1,.006,.026812,.022498,.030311,.0175,0.0*
1,1,.006,.030311,.0175*
20,1,.006,.030311,.0175,.032889,.011971,0.0*
1,1,.006,.032889,.011971*
20,1,.006,.032889,.011971,.034468,.006078,0.0*
1,1,.006,.034468,.006078*
20,1,.006,.034468,.006078,.035,0.0,0.0*
1,1,.006,.035,0.0*
1,1,.006,-.0295,.01041*
20,1,.006,-.0295,.01041,-.02082,-.01041,0.0*
1,1,.006,-.02082,-.01041*
20,1,.006,-.02082,-.01041,-.01214,.01041,0.0*
1,1,.006,-.01214,.01041*
1,1,.006,.00001,.01041*
20,1,.006,.00001,.01041,-.00277,.00972,0.0*
1,1,.006,-.00277,.00972*
20,1,.006,-.00277,.00972,-.00485,.00798,0.0*
1,1,.006,-.00485,.00798*
20,1,.006,-.00485,.00798,-.00624,.0059,0.0*
1,1,.006,-.00624,.0059*
20,1,.006,-.00624,.0059,-.00728,.00312,0.0*
1,1,.006,-.00728,.00312*
20,1,.006,-.00728,.00312,-.00762,0.0,0.0*
1,1,.006,-.00762,0.0*
20,1,.006,-.00762,0.0,-.00728,-.00312,0.0*
1,1,.006,-.00728,-.00312*
20,1,.006,-.00728,-.00312,-.00624,-.0059,0.0*
1,1,.006,-.00624,-.0059*
20,1,.006,-.00624,-.0059,-.00485,-.00798,0.0*
1,1,.006,-.00485,-.00798*
20,1,.006,-.00485,-.00798,-.00277,-.00972,0.0*
1,1,.006,-.00277,-.00972*
20,1,.006,-.00277,-.00972,.00001,-.01041,0.0*
1,1,.006,.00001,-.01041*
20,1,.006,.00001,-.01041,.00279,-.00972,0.0*
1,1,.006,.00279,-.00972*
20,1,.006,.00279,-.00972,.00487,-.00798,0.0*
1,1,.006,.00487,-.00798*
20,1,.006,.00487,-.00798,.00626,-.0059,0.0*
1,1,.006,.00626,-.0059*
20,1,.006,.00626,-.0059,.0073,-.00312,0.0*
1,1,.006,.0073,-.00312*
20,1,.006,.0073,-.00312,.00764,0.0,0.0*
1,1,.006,.00764,0.0*
20,1,.006,.00764,0.0,.0073,.00312,0.0*
1,1,.006,.0073,.00312*
20,1,.006,.0073,.00312,.00626,.0059,0.0*
1,1,.006,.00626,.0059*
20,1,.006,.00626,.0059,.00487,.00798,0.0*
1,1,.006,.00487,.00798*
20,1,.006,.00487,.00798,.00279,.00972,0.0*
1,1,.006,.00279,.00972*
20,1,.006,.00279,.00972,.00001,.01041,0.0*
1,1,.006,.00001,.01041*
1,1,.006,.02084,-.01041*
20,1,.006,.02084,-.01041,.02327,-.01006,0.0*
1,1,.006,.02327,-.01006*
20,1,.006,.02327,-.01006,.02604,-.00902,0.0*
1,1,.006,.02604,-.00902*
20,1,.006,.02604,-.00902,.02778,-.00729,0.0*
1,1,.006,.02778,-.00729*
20,1,.006,.02778,-.00729,.02847,-.00486,0.0*
1,1,.006,.02847,-.00486*
20,1,.006,.02847,-.00486,.02778,-.00243,0.0*
1,1,.006,.02778,-.00243*
20,1,.006,.02778,-.00243,.0257,-.00035,0.0*
1,1,.006,.0257,-.00035*
20,1,.006,.0257,-.00035,.02257,.00069,0.0*
1,1,.006,.02257,.00069*
20,1,.006,.02257,.00069,.01911,.00069,0.0*
1,1,.006,.01911,.00069*
20,1,.006,.01911,.00069,.01702,.00139,0.0*
1,1,.006,.01702,.00139*
20,1,.006,.01702,.00139,.01529,.00312,0.0*
1,1,.006,.01529,.00312*
20,1,.006,.01529,.00312,.01459,.00555,0.0*
1,1,.006,.01459,.00555*
20,1,.006,.01459,.00555,.01564,.00798,0.0*
1,1,.006,.01564,.00798*
20,1,.006,.01564,.00798,.01806,.00972,0.0*
1,1,.006,.01806,.00972*
20,1,.006,.01806,.00972,.02084,.01041,0.0*
1,1,.006,.02084,.01041*
20,1,.006,.02084,.01041,.02362,.00972,0.0*
1,1,.006,.02362,.00972*
20,1,.006,.02362,.00972,.02604,.00798,0.0*
1,1,.006,.02604,.00798*
20,1,.006,.02604,.00798,.02709,.00555,0.0*
1,1,.006,.02709,.00555*
20,1,.006,.02709,.00555,.02639,.00312,0.0*
1,1,.006,.02639,.00312*
20,1,.006,.02639,.00312,.02466,.00139,0.0*
1,1,.006,.02466,.00139*
20,1,.006,.02466,.00139,.02257,.00069,0.0*
1,1,.006,.02257,.00069*
20,1,.006,.02257,.00069,.01911,.00069,0.0*
1,1,.006,.01911,.00069*
20,1,.006,.01911,.00069,.01598,-.00035,0.0*
1,1,.006,.01598,-.00035*
20,1,.006,.01598,-.00035,.0139,-.00243,0.0*
1,1,.006,.0139,-.00243*
20,1,.006,.0139,-.00243,.01321,-.00486,0.0*
1,1,.006,.01321,-.00486*
20,1,.006,.01321,-.00486,.0139,-.00729,0.0*
1,1,.006,.0139,-.00729*
20,1,.006,.0139,-.00729,.01564,-.00902,0.0*
1,1,.006,.01564,-.00902*
20,1,.006,.01564,-.00902,.01841,-.01006,0.0*
1,1,.006,.01841,-.01006*
20,1,.006,.01841,-.01006,.02084,-.01041,0.0*
1,1,.006,.02084,-.01041*
%
%ADD14MACRO14*%
%AMMACRO41*
1,1,.006,.061,0.0*
20,1,.006,.061,0.0,.0305,.052828,0.0*
1,1,.006,.0305,.052828*
20,1,.006,.0305,.052828,-.0305,.052828,0.0*
1,1,.006,-.0305,.052828*
20,1,.006,-.0305,.052828,-.061,0.0,0.0*
1,1,.006,-.061,0.0*
20,1,.006,-.061,0.0,-.0305,-.052828,0.0*
1,1,.006,-.0305,-.052828*
20,1,.006,-.0305,-.052828,.0305,-.052828,0.0*
1,1,.006,.0305,-.052828*
20,1,.006,.0305,-.052828,.061,0.0,0.0*
1,1,.006,.061,0.0*
1,1,.006,-.02092,-.0249*
20,1,.006,-.02092,-.0249,-.02092,.00499,0.0*
1,1,.006,-.02092,.00499*
1,1,.006,-.02092,.0005*
20,1,.006,-.02092,.0005,-.02341,.00299,0.0*
1,1,.006,-.02341,.00299*
20,1,.006,-.02341,.00299,-.0264,.00449,0.0*
1,1,.006,-.0264,.00449*
20,1,.006,-.0264,.00449,-.02989,.00499,0.0*
1,1,.006,-.02989,.00499*
20,1,.006,-.02989,.00499,-.03287,.00449,0.0*
1,1,.006,-.03287,.00449*
20,1,.006,-.03287,.00449,-.03636,.002,0.0*
1,1,.006,-.03636,.002*
20,1,.006,-.03636,.002,-.03835,-.00149,0.0*
1,1,.006,-.03835,-.00149*
20,1,.006,-.03835,-.00149,-.03885,-.00498,0.0*
1,1,.006,-.03885,-.00498*
20,1,.006,-.03885,-.00498,-.03835,-.00846,0.0*
1,1,.006,-.03835,-.00846*
20,1,.006,-.03835,-.00846,-.03636,-.01195,0.0*
1,1,.006,-.03636,-.01195*
20,1,.006,-.03636,-.01195,-.03287,-.01444,0.0*
1,1,.006,-.03287,-.01444*
20,1,.006,-.03287,-.01444,-.02989,-.01494,0.0*
1,1,.006,-.02989,-.01494*
20,1,.006,-.02989,-.01494,-.0264,-.01444,0.0*
1,1,.006,-.0264,-.01444*
20,1,.006,-.0264,-.01444,-.02341,-.01295,0.0*
1,1,.006,-.02341,-.01295*
20,1,.006,-.02341,-.01295,-.02092,-.01046,0.0*
1,1,.006,-.02092,-.01046*
1,1,.006,-.01244,.00499*
20,1,.006,-.01244,.00499,-.00646,-.01494,0.0*
1,1,.006,-.00646,-.01494*
20,1,.006,-.00646,-.01494,.00001,.00499,0.0*
1,1,.006,.00001,.00499*
20,1,.006,.00001,.00499,.00649,-.01494,0.0*
1,1,.006,.00649,-.01494*
20,1,.006,.00649,-.01494,.01247,.00499,0.0*
1,1,.006,.01247,.00499*
1,1,.006,.01746,.00499*
20,1,.006,.01746,.00499,.02344,-.01494,0.0*
1,1,.006,.02344,-.01494*
20,1,.006,.02344,-.01494,.02991,.00499,0.0*
1,1,.006,.02991,.00499*
20,1,.006,.02991,.00499,.03639,-.01494,0.0*
1,1,.006,.03639,-.01494*
20,1,.006,.03639,-.01494,.04237,.00499,0.0*
1,1,.006,.04237,.00499*
%
%ADD41MACRO41*%
%AMMACRO31*
1,1,.006,0.0,.035*
20,1,.006,0.0,.035,.030311,-.0175,0.0*
1,1,.006,.030311,-.0175*
20,1,.006,.030311,-.0175,-.030311,-.0175,0.0*
1,1,.006,-.030311,-.0175*
20,1,.006,-.030311,-.0175,0.0,.035,0.0*
1,1,.006,0.0,.035*
1,1,.006,-.01433,-.00918*
20,1,.006,-.01433,-.00918,-.01433,.00184,0.0*
1,1,.006,-.01433,.00184*
1,1,.006,-.01433,.00018*
20,1,.006,-.01433,.00018,-.01341,.0011,0.0*
1,1,.006,-.01341,.0011*
20,1,.006,-.01341,.0011,-.01249,.00165,0.0*
1,1,.006,-.01249,.00165*
20,1,.006,-.01249,.00165,-.01102,.00184,0.0*
1,1,.006,-.01102,.00184*
20,1,.006,-.01102,.00184,-.00973,.00165,0.0*
1,1,.006,-.00973,.00165*
20,1,.006,-.00973,.00165,-.00845,.00073,0.0*
1,1,.006,-.00845,.00073*
20,1,.006,-.00845,.00073,-.0079,-.00055,0.0*
1,1,.006,-.0079,-.00055*
20,1,.006,-.0079,-.00055,-.00771,-.00184,0.0*
1,1,.006,-.00771,-.00184*
20,1,.006,-.00771,-.00184,-.0079,-.00312,0.0*
1,1,.006,-.0079,-.00312*
20,1,.006,-.0079,-.00312,-.00845,-.00441,0.0*
1,1,.006,-.00845,-.00441*
20,1,.006,-.00845,-.00441,-.00955,-.00514,0.0*
1,1,.006,-.00955,-.00514*
20,1,.006,-.00955,-.00514,-.01102,-.00551,0.0*
1,1,.006,-.01102,-.00551*
20,1,.006,-.01102,-.00551,-.01231,-.00533,0.0*
1,1,.006,-.01231,-.00533*
20,1,.006,-.01231,-.00533,-.01359,-.00478,0.0*
1,1,.006,-.01359,-.00478*
20,1,.006,-.01359,-.00478,-.01433,-.00404,0.0*
1,1,.006,-.01433,-.00404*
1,1,.006,-.00256,-.00551*
20,1,.006,-.00256,-.00551,-.00256,.00184,0.0*
1,1,.006,-.00256,.00184*
1,1,.006,-.00256,.00037*
20,1,.006,-.00256,.00037,-.00164,.0011,0.0*
1,1,.006,-.00164,.0011*
20,1,.006,-.00164,.0011,-.00072,.00165,0.0*
1,1,.006,-.00072,.00165*
20,1,.006,-.00072,.00165,.00056,.00184,0.0*
1,1,.006,.00056,.00184*
20,1,.006,.00056,.00184,.00148,.00165,0.0*
1,1,.006,.00148,.00165*
20,1,.006,.00148,.00165,.00258,.0011,0.0*
1,1,.006,.00258,.0011*
1,1,.006,.01435,-.00918*
20,1,.006,.01435,-.00918,.01435,.00184,0.0*
1,1,.006,.01435,.00184*
1,1,.006,.01435,.00018*
20,1,.006,.01435,.00018,.01343,.0011,0.0*
1,1,.006,.01343,.0011*
20,1,.006,.01343,.0011,.01233,.00165,0.0*
1,1,.006,.01233,.00165*
20,1,.006,.01233,.00165,.01104,.00184,0.0*
1,1,.006,.01104,.00184*
20,1,.006,.01104,.00184,.00994,.00165,0.0*
1,1,.006,.00994,.00165*
20,1,.006,.00994,.00165,.00865,.00073,0.0*
1,1,.006,.00865,.00073*
20,1,.006,.00865,.00073,.00792,-.00055,0.0*
1,1,.006,.00792,-.00055*
20,1,.006,.00792,-.00055,.00773,-.00184,0.0*
1,1,.006,.00773,-.00184*
20,1,.006,.00773,-.00184,.00792,-.00312,0.0*
1,1,.006,.00792,-.00312*
20,1,.006,.00792,-.00312,.00865,-.00441,0.0*
1,1,.006,.00865,-.00441*
20,1,.006,.00865,-.00441,.00994,-.00533,0.0*
1,1,.006,.00994,-.00533*
20,1,.006,.00994,-.00533,.01104,-.00551,0.0*
1,1,.006,.01104,-.00551*
20,1,.006,.01104,-.00551,.01233,-.00533,0.0*
1,1,.006,.01233,-.00533*
20,1,.006,.01233,-.00533,.01343,-.00478,0.0*
1,1,.006,.01343,-.00478*
20,1,.006,.01343,-.00478,.01435,-.00386,0.0*
1,1,.006,.01435,-.00386*
%
%ADD31MACRO31*%
%AMMACRO35*
1,1,.006,.079,0.0*
20,1,.006,.079,0.0,.0395,.068416,0.0*
1,1,.006,.0395,.068416*
20,1,.006,.0395,.068416,-.0395,.068416,0.0*
1,1,.006,-.0395,.068416*
20,1,.006,-.0395,.068416,-.079,0.0,0.0*
1,1,.006,-.079,0.0*
20,1,.006,-.079,0.0,-.0395,-.068416,0.0*
1,1,.006,-.0395,-.068416*
20,1,.006,-.0395,-.068416,.0395,-.068416,0.0*
1,1,.006,.0395,-.068416*
20,1,.006,.0395,-.068416,.079,0.0,0.0*
1,1,.006,.079,0.0*
1,1,.006,-.02709,-.03225*
20,1,.006,-.02709,-.03225,-.02709,.00646,0.0*
1,1,.006,-.02709,.00646*
1,1,.006,-.02709,.00065*
20,1,.006,-.02709,.00065,-.03032,.00388,0.0*
1,1,.006,-.03032,.00388*
20,1,.006,-.03032,.00388,-.03419,.00581,0.0*
1,1,.006,-.03419,.00581*
20,1,.006,-.03419,.00581,-.03871,.00646,0.0*
1,1,.006,-.03871,.00646*
20,1,.006,-.03871,.00646,-.04258,.00581,0.0*
1,1,.006,-.04258,.00581*
20,1,.006,-.04258,.00581,-.04709,.00259,0.0*
1,1,.006,-.04709,.00259*
20,1,.006,-.04709,.00259,-.04967,-.00193,0.0*
1,1,.006,-.04967,-.00193*
20,1,.006,-.04967,-.00193,-.05032,-.00645,0.0*
1,1,.006,-.05032,-.00645*
20,1,.006,-.05032,-.00645,-.04967,-.01096,0.0*
1,1,.006,-.04967,-.01096*
20,1,.006,-.04967,-.01096,-.04709,-.01548,0.0*
1,1,.006,-.04709,-.01548*
20,1,.006,-.04709,-.01548,-.04258,-.0187,0.0*
1,1,.006,-.04258,-.0187*
20,1,.006,-.04258,-.0187,-.03871,-.01935,0.0*
1,1,.006,-.03871,-.01935*
20,1,.006,-.03871,-.01935,-.03419,-.0187,0.0*
1,1,.006,-.03419,-.0187*
20,1,.006,-.03419,-.0187,-.03032,-.01677,0.0*
1,1,.006,-.03032,-.01677*
20,1,.006,-.03032,-.01677,-.02709,-.01354,0.0*
1,1,.006,-.02709,-.01354*
1,1,.006,.00001,.01936*
20,1,.006,.00001,.01936,.00001,-.01935,0.0*
1,1,.006,.00001,-.01935*
1,1,.006,-.00902,.00646*
20,1,.006,-.00902,.00646,.00905,.00646,0.0*
1,1,.006,.00905,.00646*
1,1,.006,.03873,.00646*
20,1,.006,.03873,.00646,.03873,-.01935,0.0*
1,1,.006,.03873,-.01935*
1,1,.006,.03873,.01678*
20,1,.006,.03873,.01678,.03744,.01742,0.0*
1,1,.006,.03744,.01742*
20,1,.006,.03744,.01742,.03744,.01871,0.0*
1,1,.006,.03744,.01871*
20,1,.006,.03744,.01871,.03873,.01936,0.0*
1,1,.006,.03873,.01936*
20,1,.006,.03873,.01936,.04003,.01871,0.0*
1,1,.006,.04003,.01871*
20,1,.006,.04003,.01871,.04003,.01742,0.0*
1,1,.006,.04003,.01742*
20,1,.006,.04003,.01742,.03873,.01678,0.0*
1,1,.006,.03873,.01678*
%
%ADD35MACRO35*%
%AMMACRO19*
1,1,.006,0.0,.035*
20,1,.006,0.0,.035,.030311,-.0175,0.0*
1,1,.006,.030311,-.0175*
20,1,.006,.030311,-.0175,-.030311,-.0175,0.0*
1,1,.006,-.030311,-.0175*
20,1,.006,-.030311,-.0175,0.0,.035,0.0*
1,1,.006,0.0,.035*
1,1,.006,-.01433,-.00918*
20,1,.006,-.01433,-.00918,-.01433,.00184,0.0*
1,1,.006,-.01433,.00184*
1,1,.006,-.01433,.00018*
20,1,.006,-.01433,.00018,-.01341,.0011,0.0*
1,1,.006,-.01341,.0011*
20,1,.006,-.01341,.0011,-.01249,.00165,0.0*
1,1,.006,-.01249,.00165*
20,1,.006,-.01249,.00165,-.01102,.00184,0.0*
1,1,.006,-.01102,.00184*
20,1,.006,-.01102,.00184,-.00973,.00165,0.0*
1,1,.006,-.00973,.00165*
20,1,.006,-.00973,.00165,-.00845,.00073,0.0*
1,1,.006,-.00845,.00073*
20,1,.006,-.00845,.00073,-.0079,-.00055,0.0*
1,1,.006,-.0079,-.00055*
20,1,.006,-.0079,-.00055,-.00771,-.00184,0.0*
1,1,.006,-.00771,-.00184*
20,1,.006,-.00771,-.00184,-.0079,-.00312,0.0*
1,1,.006,-.0079,-.00312*
20,1,.006,-.0079,-.00312,-.00845,-.00441,0.0*
1,1,.006,-.00845,-.00441*
20,1,.006,-.00845,-.00441,-.00955,-.00514,0.0*
1,1,.006,-.00955,-.00514*
20,1,.006,-.00955,-.00514,-.01102,-.00551,0.0*
1,1,.006,-.01102,-.00551*
20,1,.006,-.01102,-.00551,-.01231,-.00533,0.0*
1,1,.006,-.01231,-.00533*
20,1,.006,-.01231,-.00533,-.01359,-.00478,0.0*
1,1,.006,-.01359,-.00478*
20,1,.006,-.01359,-.00478,-.01433,-.00404,0.0*
1,1,.006,-.01433,-.00404*
1,1,.006,-.00256,-.00551*
20,1,.006,-.00256,-.00551,-.00256,.00184,0.0*
1,1,.006,-.00256,.00184*
1,1,.006,-.00256,.00037*
20,1,.006,-.00256,.00037,-.00164,.0011,0.0*
1,1,.006,-.00164,.0011*
20,1,.006,-.00164,.0011,-.00072,.00165,0.0*
1,1,.006,-.00072,.00165*
20,1,.006,-.00072,.00165,.00056,.00184,0.0*
1,1,.006,.00056,.00184*
20,1,.006,.00056,.00184,.00148,.00165,0.0*
1,1,.006,.00148,.00165*
20,1,.006,.00148,.00165,.00258,.0011,0.0*
1,1,.006,.00258,.0011*
1,1,.006,.00847,-.00551*
20,1,.006,.00847,-.00551,.00847,.00184,0.0*
1,1,.006,.00847,.00184*
1,1,.006,.00847,.00037*
20,1,.006,.00847,.00037,.00939,.0011,0.0*
1,1,.006,.00939,.0011*
20,1,.006,.00939,.0011,.01031,.00165,0.0*
1,1,.006,.01031,.00165*
20,1,.006,.01031,.00165,.01159,.00184,0.0*
1,1,.006,.01159,.00184*
20,1,.006,.01159,.00184,.01251,.00165,0.0*
1,1,.006,.01251,.00165*
20,1,.006,.01251,.00165,.01361,.0011,0.0*
1,1,.006,.01361,.0011*
%
%ADD19MACRO19*%
%AMMACRO25*
1,1,.006,.075,0.0*
20,1,.006,.075,0.0,.0375,.064952,0.0*
1,1,.006,.0375,.064952*
20,1,.006,.0375,.064952,-.0375,.064952,0.0*
1,1,.006,-.0375,.064952*
20,1,.006,-.0375,.064952,-.075,0.0,0.0*
1,1,.006,-.075,0.0*
20,1,.006,-.075,0.0,-.0375,-.064952,0.0*
1,1,.006,-.0375,-.064952*
20,1,.006,-.0375,-.064952,.0375,-.064952,0.0*
1,1,.006,.0375,-.064952*
20,1,.006,.0375,-.064952,.075,0.0,0.0*
1,1,.006,.075,0.0*
1,1,.006,-.03675,-.01837*
20,1,.006,-.03675,-.01837,-.03675,.01838,0.0*
1,1,.006,-.03675,.01838*
20,1,.006,-.03675,.01838,-.0441,.01103,0.0*
1,1,.006,-.0441,.01103*
1,1,.006,-.0441,-.01837*
20,1,.006,-.0441,-.01837,-.0294,-.01837,0.0*
1,1,.006,-.0294,-.01837*
1,1,.006,-.01346,-.01286*
20,1,.006,-.01346,-.01286,-.00979,-.01592,0.0*
1,1,.006,-.00979,-.01592*
20,1,.006,-.00979,-.01592,-.0055,-.01776,0.0*
1,1,.006,-.0055,-.01776*
20,1,.006,-.0055,-.01776,.00001,-.01837,0.0*
1,1,.006,.00001,-.01837*
20,1,.006,.00001,-.01837,.00553,-.01715,0.0*
1,1,.006,.00553,-.01715*
20,1,.006,.00553,-.01715,.00981,-.0147,0.0*
1,1,.006,.00981,-.0147*
20,1,.006,.00981,-.0147,.01288,-.01041,0.0*
1,1,.006,.01288,-.01041*
20,1,.006,.01288,-.01041,.01349,-.00551,0.0*
1,1,.006,.01349,-.00551*
20,1,.006,.01349,-.00551,.01227,-.00061,0.0*
1,1,.006,.01227,-.00061*
20,1,.006,.01227,-.00061,.0092,.00246,0.0*
1,1,.006,.0092,.00246*
20,1,.006,.0092,.00246,.00491,.0049,0.0*
1,1,.006,.00491,.0049*
20,1,.006,.00491,.0049,.00063,.00552,0.0*
1,1,.006,.00063,.00552*
20,1,.006,.00063,.00552,-.00366,.0049,0.0*
1,1,.006,-.00366,.0049*
20,1,.006,-.00366,.0049,-.00917,.00246,0.0*
1,1,.006,-.00917,.00246*
20,1,.006,-.00917,.00246,-.00734,.01838,0.0*
1,1,.006,-.00734,.01838*
20,1,.006,-.00734,.01838,.0092,.01838,0.0*
1,1,.006,.0092,.01838*
1,1,.006,.03677,.01838*
20,1,.006,.03677,.01838,.03187,.01716,0.0*
1,1,.006,.03187,.01716*
20,1,.006,.03187,.01716,.0282,.01409,0.0*
1,1,.006,.0282,.01409*
20,1,.006,.0282,.01409,.02575,.01042,0.0*
1,1,.006,.02575,.01042*
20,1,.006,.02575,.01042,.02391,.00552,0.0*
1,1,.006,.02391,.00552*
20,1,.006,.02391,.00552,.0233,0.0,0.0*
1,1,.006,.0233,0.0*
20,1,.006,.0233,0.0,.02391,-.00551,0.0*
1,1,.006,.02391,-.00551*
20,1,.006,.02391,-.00551,.02575,-.01041,0.0*
1,1,.006,.02575,-.01041*
20,1,.006,.02575,-.01041,.0282,-.01408,0.0*
1,1,.006,.0282,-.01408*
20,1,.006,.0282,-.01408,.03187,-.01715,0.0*
1,1,.006,.03187,-.01715*
20,1,.006,.03187,-.01715,.03677,-.01837,0.0*
1,1,.006,.03677,-.01837*
20,1,.006,.03677,-.01837,.04167,-.01715,0.0*
1,1,.006,.04167,-.01715*
20,1,.006,.04167,-.01715,.04535,-.01408,0.0*
1,1,.006,.04535,-.01408*
20,1,.006,.04535,-.01408,.0478,-.01041,0.0*
1,1,.006,.0478,-.01041*
20,1,.006,.0478,-.01041,.04964,-.00551,0.0*
1,1,.006,.04964,-.00551*
20,1,.006,.04964,-.00551,.05025,0.0,0.0*
1,1,.006,.05025,0.0*
20,1,.006,.05025,0.0,.04964,.00552,0.0*
1,1,.006,.04964,.00552*
20,1,.006,.04964,.00552,.0478,.01042,0.0*
1,1,.006,.0478,.01042*
20,1,.006,.0478,.01042,.04535,.01409,0.0*
1,1,.006,.04535,.01409*
20,1,.006,.04535,.01409,.04167,.01716,0.0*
1,1,.006,.04167,.01716*
20,1,.006,.04167,.01716,.03677,.01838,0.0*
1,1,.006,.03677,.01838*
%
%ADD25MACRO25*%
%AMMACRO16*
1,1,.006,.0625,0.0*
20,1,.006,.0625,0.0,.03125,.054127,0.0*
1,1,.006,.03125,.054127*
20,1,.006,.03125,.054127,-.03125,.054127,0.0*
1,1,.006,-.03125,.054127*
20,1,.006,-.03125,.054127,-.0625,0.0,0.0*
1,1,.006,-.0625,0.0*
20,1,.006,-.0625,0.0,-.03125,-.054127,0.0*
1,1,.006,-.03125,-.054127*
20,1,.006,-.03125,-.054127,.03125,-.054127,0.0*
1,1,.006,.03125,-.054127*
20,1,.006,.03125,-.054127,.0625,0.0,0.0*
1,1,.006,.0625,0.0*
1,1,.006,-.02143,-.02552*
20,1,.006,-.02143,-.02552,-.02143,.0051,0.0*
1,1,.006,-.02143,.0051*
1,1,.006,-.02143,.00051*
20,1,.006,-.02143,.00051,-.02399,.00306,0.0*
1,1,.006,-.02399,.00306*
20,1,.006,-.02399,.00306,-.02705,.00459,0.0*
1,1,.006,-.02705,.00459*
20,1,.006,-.02705,.00459,-.03062,.0051,0.0*
1,1,.006,-.03062,.0051*
20,1,.006,-.03062,.0051,-.03368,.00459,0.0*
1,1,.006,-.03368,.00459*
20,1,.006,-.03368,.00459,-.03725,.00204,0.0*
1,1,.006,-.03725,.00204*
20,1,.006,-.03725,.00204,-.0393,-.00153,0.0*
1,1,.006,-.0393,-.00153*
20,1,.006,-.0393,-.00153,-.03981,-.0051,0.0*
1,1,.006,-.03981,-.0051*
20,1,.006,-.03981,-.0051,-.0393,-.00868,0.0*
1,1,.006,-.0393,-.00868*
20,1,.006,-.0393,-.00868,-.03725,-.01225,0.0*
1,1,.006,-.03725,-.01225*
20,1,.006,-.03725,-.01225,-.03368,-.0148,0.0*
1,1,.006,-.03368,-.0148*
20,1,.006,-.03368,-.0148,-.03062,-.01531,0.0*
1,1,.006,-.03062,-.01531*
20,1,.006,-.03062,-.01531,-.02705,-.0148,0.0*
1,1,.006,-.02705,-.0148*
20,1,.006,-.02705,-.0148,-.02399,-.01327,0.0*
1,1,.006,-.02399,-.01327*
20,1,.006,-.02399,-.01327,-.02143,-.01072,0.0*
1,1,.006,-.02143,-.01072*
1,1,.006,-.01275,.0051*
20,1,.006,-.01275,.0051,-.00662,-.01531,0.0*
1,1,.006,-.00662,-.01531*
20,1,.006,-.00662,-.01531,.00001,.0051,0.0*
1,1,.006,.00001,.0051*
20,1,.006,.00001,.0051,.00664,-.01531,0.0*
1,1,.006,.00664,-.01531*
20,1,.006,.00664,-.01531,.01277,.0051,0.0*
1,1,.006,.01277,.0051*
1,1,.006,.03064,.01531*
20,1,.006,.03064,.01531,.03064,-.01531,0.0*
1,1,.006,.03064,-.01531*
1,1,.006,.0235,.0051*
20,1,.006,.0235,.0051,.03778,.0051,0.0*
1,1,.006,.03778,.0051*
%
%ADD16MACRO16*%
%AMMACRO30*
1,1,.006,0.0,.035*
20,1,.006,0.0,.035,.030311,-.0175,0.0*
1,1,.006,.030311,-.0175*
20,1,.006,.030311,-.0175,-.030311,-.0175,0.0*
1,1,.006,-.030311,-.0175*
20,1,.006,-.030311,-.0175,0.0,.035,0.0*
1,1,.006,0.0,.035*
1,1,.006,-.01433,-.00918*
20,1,.006,-.01433,-.00918,-.01433,.00184,0.0*
1,1,.006,-.01433,.00184*
1,1,.006,-.01433,.00018*
20,1,.006,-.01433,.00018,-.01341,.0011,0.0*
1,1,.006,-.01341,.0011*
20,1,.006,-.01341,.0011,-.01249,.00165,0.0*
1,1,.006,-.01249,.00165*
20,1,.006,-.01249,.00165,-.01102,.00184,0.0*
1,1,.006,-.01102,.00184*
20,1,.006,-.01102,.00184,-.00973,.00165,0.0*
1,1,.006,-.00973,.00165*
20,1,.006,-.00973,.00165,-.00845,.00073,0.0*
1,1,.006,-.00845,.00073*
20,1,.006,-.00845,.00073,-.0079,-.00055,0.0*
1,1,.006,-.0079,-.00055*
20,1,.006,-.0079,-.00055,-.00771,-.00184,0.0*
1,1,.006,-.00771,-.00184*
20,1,.006,-.00771,-.00184,-.0079,-.00312,0.0*
1,1,.006,-.0079,-.00312*
20,1,.006,-.0079,-.00312,-.00845,-.00441,0.0*
1,1,.006,-.00845,-.00441*
20,1,.006,-.00845,-.00441,-.00955,-.00514,0.0*
1,1,.006,-.00955,-.00514*
20,1,.006,-.00955,-.00514,-.01102,-.00551,0.0*
1,1,.006,-.01102,-.00551*
20,1,.006,-.01102,-.00551,-.01231,-.00533,0.0*
1,1,.006,-.01231,-.00533*
20,1,.006,-.01231,-.00533,-.01359,-.00478,0.0*
1,1,.006,-.01359,-.00478*
20,1,.006,-.01359,-.00478,-.01433,-.00404,0.0*
1,1,.006,-.01433,-.00404*
1,1,.006,-.00256,-.00551*
20,1,.006,-.00256,-.00551,-.00256,.00184,0.0*
1,1,.006,-.00256,.00184*
1,1,.006,-.00256,.00037*
20,1,.006,-.00256,.00037,-.00164,.0011,0.0*
1,1,.006,-.00164,.0011*
20,1,.006,-.00164,.0011,-.00072,.00165,0.0*
1,1,.006,-.00072,.00165*
20,1,.006,-.00072,.00165,.00056,.00184,0.0*
1,1,.006,.00056,.00184*
20,1,.006,.00056,.00184,.00148,.00165,0.0*
1,1,.006,.00148,.00165*
20,1,.006,.00148,.00165,.00258,.0011,0.0*
1,1,.006,.00258,.0011*
1,1,.006,.00718,-.00882*
20,1,.006,.00718,-.00882,.00829,-.00918,0.0*
1,1,.006,.00829,-.00918*
20,1,.006,.00829,-.00918,.00975,-.00882,0.0*
1,1,.006,.00975,-.00882*
20,1,.006,.00975,-.00882,.01067,-.00808,0.0*
1,1,.006,.01067,-.00808*
20,1,.006,.01067,-.00808,.01141,-.00716,0.0*
1,1,.006,.01141,-.00716*
20,1,.006,.01141,-.00716,.01251,-.00422,0.0*
1,1,.006,.01251,-.00422*
20,1,.006,.01251,-.00422,.0149,.00184,0.0*
1,1,.006,.0149,.00184*
1,1,.006,.00902,.00184*
20,1,.006,.00902,.00184,.01251,-.00422,0.0*
1,1,.006,.01251,-.00422*
%
%ADD30MACRO30*%
%AMMACRO23*
1,1,.006,-.0315,.063*
20,1,.006,-.0315,.063,.0315,.063,0.0*
1,1,.006,.0315,.063*
20,1,.006,.0315,.063,.04244,.062043,0.0*
1,1,.006,.04244,.062043*
20,1,.006,.04244,.062043,.053047,.059201,0.0*
1,1,.006,.053047,.059201*
20,1,.006,.053047,.059201,.063,.05456,0.0*
1,1,.006,.063,.05456*
20,1,.006,.063,.05456,.071996,.048261,0.0*
1,1,.006,.071996,.048261*
20,1,.006,.071996,.048261,.079761,.040496,0.0*
1,1,.006,.079761,.040496*
20,1,.006,.079761,.040496,.08606,.0315,0.0*
1,1,.006,.08606,.0315*
20,1,.006,.08606,.0315,.090701,.021547,0.0*
1,1,.006,.090701,.021547*
20,1,.006,.090701,.021547,.093543,.01094,0.0*
1,1,.006,.093543,.01094*
20,1,.006,.093543,.01094,.0945,0.0,0.0*
1,1,.006,.0945,0.0*
20,1,.006,.0945,0.0,.093543,-.01094,0.0*
1,1,.006,.093543,-.01094*
20,1,.006,.093543,-.01094,.090701,-.021547,0.0*
1,1,.006,.090701,-.021547*
20,1,.006,.090701,-.021547,.08606,-.0315,0.0*
1,1,.006,.08606,-.0315*
20,1,.006,.08606,-.0315,.079761,-.040496,0.0*
1,1,.006,.079761,-.040496*
20,1,.006,.079761,-.040496,.071996,-.048261,0.0*
1,1,.006,.071996,-.048261*
20,1,.006,.071996,-.048261,.063,-.05456,0.0*
1,1,.006,.063,-.05456*
20,1,.006,.063,-.05456,.053047,-.059201,0.0*
1,1,.006,.053047,-.059201*
20,1,.006,.053047,-.059201,.04244,-.062043,0.0*
1,1,.006,.04244,-.062043*
20,1,.006,.04244,-.062043,.0315,-.063,0.0*
1,1,.006,.0315,-.063*
20,1,.006,.0315,-.063,-.0315,-.063,0.0*
1,1,.006,-.0315,-.063*
20,1,.006,-.0315,-.063,-.04244,-.062043,0.0*
1,1,.006,-.04244,-.062043*
20,1,.006,-.04244,-.062043,-.053047,-.059201,0.0*
1,1,.006,-.053047,-.059201*
20,1,.006,-.053047,-.059201,-.063,-.05456,0.0*
1,1,.006,-.063,-.05456*
20,1,.006,-.063,-.05456,-.071996,-.048261,0.0*
1,1,.006,-.071996,-.048261*
20,1,.006,-.071996,-.048261,-.079761,-.040496,0.0*
1,1,.006,-.079761,-.040496*
20,1,.006,-.079761,-.040496,-.08606,-.0315,0.0*
1,1,.006,-.08606,-.0315*
20,1,.006,-.08606,-.0315,-.090701,-.021547,0.0*
1,1,.006,-.090701,-.021547*
20,1,.006,-.090701,-.021547,-.093543,-.01094,0.0*
1,1,.006,-.093543,-.01094*
20,1,.006,-.093543,-.01094,-.0945,0.0,0.0*
1,1,.006,-.0945,0.0*
20,1,.006,-.0945,0.0,-.093543,.01094,0.0*
1,1,.006,-.093543,.01094*
20,1,.006,-.093543,.01094,-.090701,.021547,0.0*
1,1,.006,-.090701,.021547*
20,1,.006,-.090701,.021547,-.08606,.0315,0.0*
1,1,.006,-.08606,.0315*
20,1,.006,-.08606,.0315,-.079761,.040496,0.0*
1,1,.006,-.079761,.040496*
20,1,.006,-.079761,.040496,-.071996,.048261,0.0*
1,1,.006,-.071996,.048261*
20,1,.006,-.071996,.048261,-.063,.05456,0.0*
1,1,.006,-.063,.05456*
20,1,.006,-.063,.05456,-.053047,.059201,0.0*
1,1,.006,-.053047,.059201*
20,1,.006,-.053047,.059201,-.04244,.062043,0.0*
1,1,.006,-.04244,.062043*
20,1,.006,-.04244,.062043,-.0315,.063,0.0*
1,1,.006,-.0315,.063*
1,1,.006,-.0588,-.00735*
20,1,.006,-.0588,-.00735,-.0441,.02205,0.0*
1,1,.006,-.0441,.02205*
20,1,.006,-.0441,.02205,-.0294,-.00735,0.0*
1,1,.006,-.0294,-.00735*
1,1,.006,-.0441,.02205*
20,1,.006,-.0441,.02205,-.0441,-.03675,0.0*
1,1,.006,-.0441,-.03675*
1,1,.006,-.01616,-.02205*
20,1,.006,-.01616,-.02205,-.01616,.02205,0.0*
1,1,.006,-.01616,.02205*
20,1,.006,-.01616,.02205,-.00146,.02205,0.0*
1,1,.006,-.00146,.02205*
20,1,.006,-.00146,.02205,.00442,.01984,0.0*
1,1,.006,.00442,.01984*
20,1,.006,.00442,.01984,.00883,.0169,0.0*
1,1,.006,.00883,.0169*
20,1,.006,.00883,.0169,.01251,.0125,0.0*
1,1,.006,.01251,.0125*
20,1,.006,.01251,.0125,.01545,.00735,0.0*
1,1,.006,.01545,.00735*
20,1,.006,.01545,.00735,.01618,0.0,0.0*
1,1,.006,.01618,0.0*
20,1,.006,.01618,0.0,.01545,-.00735,0.0*
1,1,.006,.01545,-.00735*
20,1,.006,.01545,-.00735,.01251,-.0125,0.0*
1,1,.006,.01251,-.0125*
20,1,.006,.01251,-.0125,.00883,-.01691,0.0*
1,1,.006,.00883,-.01691*
20,1,.006,.00883,-.01691,.00442,-.01985,0.0*
1,1,.006,.00442,-.01985*
20,1,.006,.00442,-.01985,-.00146,-.02205,0.0*
1,1,.006,-.00146,-.02205*
20,1,.006,-.00146,-.02205,-.01616,-.02205,0.0*
1,1,.006,-.01616,-.02205*
1,1,.006,.02868,-.01617*
20,1,.006,.02868,-.01617,.03457,-.01985,0.0*
1,1,.006,.03457,-.01985*
20,1,.006,.03457,-.01985,.04118,-.02205,0.0*
1,1,.006,.04118,-.02205*
20,1,.006,.04118,-.02205,.04706,-.02205,0.0*
1,1,.006,.04706,-.02205*
20,1,.006,.04706,-.02205,.05294,-.01985,0.0*
1,1,.006,.05294,-.01985*
20,1,.006,.05294,-.01985,.05735,-.01617,0.0*
1,1,.006,.05735,-.01617*
20,1,.006,.05735,-.01617,.05956,-.01102,0.0*
1,1,.006,.05956,-.01102*
20,1,.006,.05956,-.01102,.05809,-.00588,0.0*
1,1,.006,.05809,-.00588*
20,1,.006,.05809,-.00588,.05441,-.00147,0.0*
1,1,.006,.05441,-.00147*
20,1,.006,.05441,-.00147,.04779,.00147,0.0*
1,1,.006,.04779,.00147*
20,1,.006,.04779,.00147,.03898,.00294,0.0*
1,1,.006,.03898,.00294*
20,1,.006,.03898,.00294,.03383,.00588,0.0*
1,1,.006,.03383,.00588*
20,1,.006,.03383,.00588,.03162,.01102,0.0*
1,1,.006,.03162,.01102*
20,1,.006,.03162,.01102,.0331,.01617,0.0*
1,1,.006,.0331,.01617*
20,1,.006,.0331,.01617,.03677,.01984,0.0*
1,1,.006,.03677,.01984*
20,1,.006,.03677,.01984,.04191,.02205,0.0*
1,1,.006,.04191,.02205*
20,1,.006,.04191,.02205,.04706,.02205,0.0*
1,1,.006,.04706,.02205*
20,1,.006,.04706,.02205,.05221,.02058,0.0*
1,1,.006,.05221,.02058*
20,1,.006,.05221,.02058,.05662,.0169,0.0*
1,1,.006,.05662,.0169*
%
%ADD23MACRO23*%
%AMMACRO29*
1,1,.006,0.0,.035*
20,1,.006,0.0,.035,.030311,-.0175,0.0*
1,1,.006,.030311,-.0175*
20,1,.006,.030311,-.0175,-.030311,-.0175,0.0*
1,1,.006,-.030311,-.0175*
20,1,.006,-.030311,-.0175,0.0,.035,0.0*
1,1,.006,0.0,.035*
1,1,.006,-.01433,-.00918*
20,1,.006,-.01433,-.00918,-.01433,.00184,0.0*
1,1,.006,-.01433,.00184*
1,1,.006,-.01433,.00018*
20,1,.006,-.01433,.00018,-.01341,.0011,0.0*
1,1,.006,-.01341,.0011*
20,1,.006,-.01341,.0011,-.01249,.00165,0.0*
1,1,.006,-.01249,.00165*
20,1,.006,-.01249,.00165,-.01102,.00184,0.0*
1,1,.006,-.01102,.00184*
20,1,.006,-.01102,.00184,-.00973,.00165,0.0*
1,1,.006,-.00973,.00165*
20,1,.006,-.00973,.00165,-.00845,.00073,0.0*
1,1,.006,-.00845,.00073*
20,1,.006,-.00845,.00073,-.0079,-.00055,0.0*
1,1,.006,-.0079,-.00055*
20,1,.006,-.0079,-.00055,-.00771,-.00184,0.0*
1,1,.006,-.00771,-.00184*
20,1,.006,-.00771,-.00184,-.0079,-.00312,0.0*
1,1,.006,-.0079,-.00312*
20,1,.006,-.0079,-.00312,-.00845,-.00441,0.0*
1,1,.006,-.00845,-.00441*
20,1,.006,-.00845,-.00441,-.00955,-.00514,0.0*
1,1,.006,-.00955,-.00514*
20,1,.006,-.00955,-.00514,-.01102,-.00551,0.0*
1,1,.006,-.01102,-.00551*
20,1,.006,-.01102,-.00551,-.01231,-.00533,0.0*
1,1,.006,-.01231,-.00533*
20,1,.006,-.01231,-.00533,-.01359,-.00478,0.0*
1,1,.006,-.01359,-.00478*
20,1,.006,-.01359,-.00478,-.01433,-.00404,0.0*
1,1,.006,-.01433,-.00404*
1,1,.006,-.00385,-.00882*
20,1,.006,-.00385,-.00882,-.00274,-.00918,0.0*
1,1,.006,-.00274,-.00918*
20,1,.006,-.00274,-.00918,-.00128,-.00882,0.0*
1,1,.006,-.00128,-.00882*
20,1,.006,-.00128,-.00882,-.00036,-.00808,0.0*
1,1,.006,-.00036,-.00808*
20,1,.006,-.00036,-.00808,.00038,-.00716,0.0*
1,1,.006,.00038,-.00716*
20,1,.006,.00038,-.00716,.00148,-.00422,0.0*
1,1,.006,.00148,-.00422*
20,1,.006,.00148,-.00422,.00387,.00184,0.0*
1,1,.006,.00387,.00184*
1,1,.006,-.00201,.00184*
20,1,.006,-.00201,.00184,.00148,-.00422,0.0*
1,1,.006,.00148,-.00422*
1,1,.006,.01104,.00551*
20,1,.006,.01104,.00551,.01104,-.00551,0.0*
1,1,.006,.01104,-.00551*
1,1,.006,.00847,.00184*
20,1,.006,.00847,.00184,.01361,.00184,0.0*
1,1,.006,.01361,.00184*
%
%ADD29MACRO29*%
%AMMACRO28*
1,1,.006,0.0,.035*
20,1,.006,0.0,.035,.030311,-.0175,0.0*
1,1,.006,.030311,-.0175*
20,1,.006,.030311,-.0175,-.030311,-.0175,0.0*
1,1,.006,-.030311,-.0175*
20,1,.006,-.030311,-.0175,0.0,.035,0.0*
1,1,.006,0.0,.035*
1,1,.006,-.01102,.00551*
20,1,.006,-.01102,.00551,-.01249,.00514,0.0*
1,1,.006,-.01249,.00514*
20,1,.006,-.01249,.00514,-.01359,.00422,0.0*
1,1,.006,-.01359,.00422*
20,1,.006,-.01359,.00422,-.01433,.00312,0.0*
1,1,.006,-.01433,.00312*
20,1,.006,-.01433,.00312,-.01488,.00165,0.0*
1,1,.006,-.01488,.00165*
20,1,.006,-.01488,.00165,-.01506,0.0,0.0*
1,1,.006,-.01506,0.0*
20,1,.006,-.01506,0.0,-.01488,-.00165,0.0*
1,1,.006,-.01488,-.00165*
20,1,.006,-.01488,-.00165,-.01433,-.00312,0.0*
1,1,.006,-.01433,-.00312*
20,1,.006,-.01433,-.00312,-.01359,-.00422,0.0*
1,1,.006,-.01359,-.00422*
20,1,.006,-.01359,-.00422,-.01249,-.00514,0.0*
1,1,.006,-.01249,-.00514*
20,1,.006,-.01249,-.00514,-.01102,-.00551,0.0*
1,1,.006,-.01102,-.00551*
20,1,.006,-.01102,-.00551,-.00955,-.00514,0.0*
1,1,.006,-.00955,-.00514*
20,1,.006,-.00955,-.00514,-.00845,-.00422,0.0*
1,1,.006,-.00845,-.00422*
20,1,.006,-.00845,-.00422,-.00771,-.00312,0.0*
1,1,.006,-.00771,-.00312*
20,1,.006,-.00771,-.00312,-.00716,-.00165,0.0*
1,1,.006,-.00716,-.00165*
20,1,.006,-.00716,-.00165,-.00698,0.0,0.0*
1,1,.006,-.00698,0.0*
20,1,.006,-.00698,0.0,-.00716,.00165,0.0*
1,1,.006,-.00716,.00165*
20,1,.006,-.00716,.00165,-.00771,.00312,0.0*
1,1,.006,-.00771,.00312*
20,1,.006,-.00771,.00312,-.00845,.00422,0.0*
1,1,.006,-.00845,.00422*
20,1,.006,-.00845,.00422,-.00955,.00514,0.0*
1,1,.006,-.00955,.00514*
20,1,.006,-.00955,.00514,-.01102,.00551,0.0*
1,1,.006,-.01102,.00551*
1,1,.006,.00221,-.00551*
20,1,.006,.00221,-.00551,.00221,.00551,0.0*
1,1,.006,.00221,.00551*
20,1,.006,.00221,.00551,-.00458,-.00239,0.0*
1,1,.006,-.00458,-.00239*
20,1,.006,-.00458,-.00239,.0046,-.00239,0.0*
1,1,.006,.0046,-.00239*
1,1,.006,.01104,-.00551*
20,1,.006,.01104,-.00551,.01104,.00551,0.0*
1,1,.006,.01104,.00551*
20,1,.006,.01104,.00551,.00884,.00331,0.0*
1,1,.006,.00884,.00331*
1,1,.006,.00884,-.00551*
20,1,.006,.00884,-.00551,.01324,-.00551,0.0*
1,1,.006,.01324,-.00551*
%
%ADD28MACRO28*%
%AMMACRO27*
1,1,.006,.063,0.0*
20,1,.006,.063,0.0,.0315,.05456,0.0*
1,1,.006,.0315,.05456*
20,1,.006,.0315,.05456,-.0315,.05456,0.0*
1,1,.006,-.0315,.05456*
20,1,.006,-.0315,.05456,-.063,0.0,0.0*
1,1,.006,-.063,0.0*
20,1,.006,-.063,0.0,-.0315,-.05456,0.0*
1,1,.006,-.0315,-.05456*
20,1,.006,-.0315,-.05456,.0315,-.05456,0.0*
1,1,.006,.0315,-.05456*
20,1,.006,.0315,-.05456,.063,0.0,0.0*
1,1,.006,.063,0.0*
1,1,.006,-.03087,-.01543*
20,1,.006,-.03087,-.01543,-.03087,.01544,0.0*
1,1,.006,-.03087,.01544*
20,1,.006,-.03087,.01544,-.03704,.00927,0.0*
1,1,.006,-.03704,.00927*
1,1,.006,-.03704,-.01543*
20,1,.006,-.03704,-.01543,-.02469,-.01543,0.0*
1,1,.006,-.02469,-.01543*
1,1,.006,-.00976,.0103*
20,1,.006,-.00976,.0103,-.00667,.01338,0.0*
1,1,.006,-.00667,.01338*
20,1,.006,-.00667,.01338,-.00307,.01493,0.0*
1,1,.006,-.00307,.01493*
20,1,.006,-.00307,.01493,.00104,.01544,0.0*
1,1,.006,.00104,.01544*
20,1,.006,.00104,.01544,.00619,.01441,0.0*
1,1,.006,.00619,.01441*
20,1,.006,.00619,.01441,.00979,.01184,0.0*
1,1,.006,.00979,.01184*
20,1,.006,.00979,.01184,.01082,.00875,0.0*
1,1,.006,.01082,.00875*
20,1,.006,.01082,.00875,.01031,.00566,0.0*
1,1,.006,.01031,.00566*
20,1,.006,.01031,.00566,.00825,.00309,0.0*
1,1,.006,.00825,.00309*
20,1,.006,.00825,.00309,-.00204,-.00205,0.0*
1,1,.006,-.00204,-.00205*
20,1,.006,-.00204,-.00205,-.00667,-.00565,0.0*
1,1,.006,-.00667,-.00565*
20,1,.006,-.00667,-.00565,-.00976,-.0108,0.0*
1,1,.006,-.00976,-.0108*
20,1,.006,-.00976,-.0108,-.01079,-.01543,0.0*
1,1,.006,-.01079,-.01543*
20,1,.006,-.01079,-.01543,.01082,-.01543,0.0*
1,1,.006,.01082,-.01543*
1,1,.006,.02112,-.00257*
20,1,.006,.02112,-.00257,.02472,.00103,0.0*
1,1,.006,.02472,.00103*
20,1,.006,.02472,.00103,.02781,.00309,0.0*
1,1,.006,.02781,.00309*
20,1,.006,.02781,.00309,.03192,.00412,0.0*
1,1,.006,.03192,.00412*
20,1,.006,.03192,.00412,.03553,.00309,0.0*
1,1,.006,.03553,.00309*
20,1,.006,.03553,.00309,.0381,.00103,0.0*
1,1,.006,.0381,.00103*
20,1,.006,.0381,.00103,.04016,-.00205,0.0*
1,1,.006,.04016,-.00205*
20,1,.006,.04016,-.00205,.04067,-.00565,0.0*
1,1,.006,.04067,-.00565*
20,1,.006,.04067,-.00565,.04016,-.00874,0.0*
1,1,.006,.04016,-.00874*
20,1,.006,.04016,-.00874,.0381,-.01183,0.0*
1,1,.006,.0381,-.01183*
20,1,.006,.0381,-.01183,.03501,-.0144,0.0*
1,1,.006,.03501,-.0144*
20,1,.006,.03501,-.0144,.03141,-.01543,0.0*
1,1,.006,.03141,-.01543*
20,1,.006,.03141,-.01543,.02729,-.0144,0.0*
1,1,.006,.02729,-.0144*
20,1,.006,.02729,-.0144,.02369,-.01131,0.0*
1,1,.006,.02369,-.01131*
20,1,.006,.02369,-.01131,.02163,-.00668,0.0*
1,1,.006,.02163,-.00668*
20,1,.006,.02163,-.00668,.02112,-.00154,0.0*
1,1,.006,.02112,-.00154*
20,1,.006,.02112,-.00154,.02215,.00515,0.0*
1,1,.006,.02215,.00515*
20,1,.006,.02215,.00515,.02369,.00875,0.0*
1,1,.006,.02369,.00875*
20,1,.006,.02369,.00875,.02626,.01235,0.0*
1,1,.006,.02626,.01235*
20,1,.006,.02626,.01235,.02987,.01493,0.0*
1,1,.006,.02987,.01493*
20,1,.006,.02987,.01493,.03347,.01544,0.0*
1,1,.006,.03347,.01544*
20,1,.006,.03347,.01544,.03707,.01441,0.0*
1,1,.006,.03707,.01441*
20,1,.006,.03707,.01441,.03964,.01184,0.0*
1,1,.006,.03964,.01184*
%
%ADD27MACRO27*%
%AMMACRO21*
1,1,.006,0.0,.035*
20,1,.006,0.0,.035,.030311,-.0175,0.0*
1,1,.006,.030311,-.0175*
20,1,.006,.030311,-.0175,-.030311,-.0175,0.0*
1,1,.006,-.030311,-.0175*
20,1,.006,-.030311,-.0175,0.0,.035,0.0*
1,1,.006,0.0,.035*
1,1,.006,-.01102,.00551*
20,1,.006,-.01102,.00551,-.01249,.00514,0.0*
1,1,.006,-.01249,.00514*
20,1,.006,-.01249,.00514,-.01359,.00422,0.0*
1,1,.006,-.01359,.00422*
20,1,.006,-.01359,.00422,-.01433,.00312,0.0*
1,1,.006,-.01433,.00312*
20,1,.006,-.01433,.00312,-.01488,.00165,0.0*
1,1,.006,-.01488,.00165*
20,1,.006,-.01488,.00165,-.01506,0.0,0.0*
1,1,.006,-.01506,0.0*
20,1,.006,-.01506,0.0,-.01488,-.00165,0.0*
1,1,.006,-.01488,-.00165*
20,1,.006,-.01488,-.00165,-.01433,-.00312,0.0*
1,1,.006,-.01433,-.00312*
20,1,.006,-.01433,-.00312,-.01359,-.00422,0.0*
1,1,.006,-.01359,-.00422*
20,1,.006,-.01359,-.00422,-.01249,-.00514,0.0*
1,1,.006,-.01249,-.00514*
20,1,.006,-.01249,-.00514,-.01102,-.00551,0.0*
1,1,.006,-.01102,-.00551*
20,1,.006,-.01102,-.00551,-.00955,-.00514,0.0*
1,1,.006,-.00955,-.00514*
20,1,.006,-.00955,-.00514,-.00845,-.00422,0.0*
1,1,.006,-.00845,-.00422*
20,1,.006,-.00845,-.00422,-.00771,-.00312,0.0*
1,1,.006,-.00771,-.00312*
20,1,.006,-.00771,-.00312,-.00716,-.00165,0.0*
1,1,.006,-.00716,-.00165*
20,1,.006,-.00716,-.00165,-.00698,0.0,0.0*
1,1,.006,-.00698,0.0*
20,1,.006,-.00698,0.0,-.00716,.00165,0.0*
1,1,.006,-.00716,.00165*
20,1,.006,-.00716,.00165,-.00771,.00312,0.0*
1,1,.006,-.00771,.00312*
20,1,.006,-.00771,.00312,-.00845,.00422,0.0*
1,1,.006,-.00845,.00422*
20,1,.006,-.00845,.00422,-.00955,.00514,0.0*
1,1,.006,-.00955,.00514*
20,1,.006,-.00955,.00514,-.01102,.00551,0.0*
1,1,.006,-.01102,.00551*
1,1,.006,.00221,-.00551*
20,1,.006,.00221,-.00551,.00221,.00551,0.0*
1,1,.006,.00221,.00551*
20,1,.006,.00221,.00551,-.00458,-.00239,0.0*
1,1,.006,-.00458,-.00239*
20,1,.006,-.00458,-.00239,.0046,-.00239,0.0*
1,1,.006,.0046,-.00239*
1,1,.006,.00755,.00367*
20,1,.006,.00755,.00367,.00865,.00478,0.0*
1,1,.006,.00865,.00478*
20,1,.006,.00865,.00478,.00994,.00533,0.0*
1,1,.006,.00994,.00533*
20,1,.006,.00994,.00533,.01141,.00551,0.0*
1,1,.006,.01141,.00551*
20,1,.006,.01141,.00551,.01324,.00514,0.0*
1,1,.006,.01324,.00514*
20,1,.006,.01324,.00514,.01453,.00422,0.0*
1,1,.006,.01453,.00422*
20,1,.006,.01453,.00422,.0149,.00312,0.0*
1,1,.006,.0149,.00312*
20,1,.006,.0149,.00312,.01471,.00202,0.0*
1,1,.006,.01471,.00202*
20,1,.006,.01471,.00202,.01398,.0011,0.0*
1,1,.006,.01398,.0011*
20,1,.006,.01398,.0011,.01031,-.00073,0.0*
1,1,.006,.01031,-.00073*
20,1,.006,.01031,-.00073,.00865,-.00202,0.0*
1,1,.006,.00865,-.00202*
20,1,.006,.00865,-.00202,.00755,-.00386,0.0*
1,1,.006,.00755,-.00386*
20,1,.006,.00755,-.00386,.00718,-.00551,0.0*
1,1,.006,.00718,-.00551*
20,1,.006,.00718,-.00551,.0149,-.00551,0.0*
1,1,.006,.0149,-.00551*
%
%ADD21MACRO21*%
%AMMACRO18*
1,1,.006,0.0,.035*
20,1,.006,0.0,.035,.030311,-.0175,0.0*
1,1,.006,.030311,-.0175*
20,1,.006,.030311,-.0175,-.030311,-.0175,0.0*
1,1,.006,-.030311,-.0175*
20,1,.006,-.030311,-.0175,0.0,.035,0.0*
1,1,.006,0.0,.035*
1,1,.006,-.01102,.00551*
20,1,.006,-.01102,.00551,-.01249,.00514,0.0*
1,1,.006,-.01249,.00514*
20,1,.006,-.01249,.00514,-.01359,.00422,0.0*
1,1,.006,-.01359,.00422*
20,1,.006,-.01359,.00422,-.01433,.00312,0.0*
1,1,.006,-.01433,.00312*
20,1,.006,-.01433,.00312,-.01488,.00165,0.0*
1,1,.006,-.01488,.00165*
20,1,.006,-.01488,.00165,-.01506,0.0,0.0*
1,1,.006,-.01506,0.0*
20,1,.006,-.01506,0.0,-.01488,-.00165,0.0*
1,1,.006,-.01488,-.00165*
20,1,.006,-.01488,-.00165,-.01433,-.00312,0.0*
1,1,.006,-.01433,-.00312*
20,1,.006,-.01433,-.00312,-.01359,-.00422,0.0*
1,1,.006,-.01359,-.00422*
20,1,.006,-.01359,-.00422,-.01249,-.00514,0.0*
1,1,.006,-.01249,-.00514*
20,1,.006,-.01249,-.00514,-.01102,-.00551,0.0*
1,1,.006,-.01102,-.00551*
20,1,.006,-.01102,-.00551,-.00955,-.00514,0.0*
1,1,.006,-.00955,-.00514*
20,1,.006,-.00955,-.00514,-.00845,-.00422,0.0*
1,1,.006,-.00845,-.00422*
20,1,.006,-.00845,-.00422,-.00771,-.00312,0.0*
1,1,.006,-.00771,-.00312*
20,1,.006,-.00771,-.00312,-.00716,-.00165,0.0*
1,1,.006,-.00716,-.00165*
20,1,.006,-.00716,-.00165,-.00698,0.0,0.0*
1,1,.006,-.00698,0.0*
20,1,.006,-.00698,0.0,-.00716,.00165,0.0*
1,1,.006,-.00716,.00165*
20,1,.006,-.00716,.00165,-.00771,.00312,0.0*
1,1,.006,-.00771,.00312*
20,1,.006,-.00771,.00312,-.00845,.00422,0.0*
1,1,.006,-.00845,.00422*
20,1,.006,-.00845,.00422,-.00955,.00514,0.0*
1,1,.006,-.00955,.00514*
20,1,.006,-.00955,.00514,-.01102,.00551,0.0*
1,1,.006,-.01102,.00551*
1,1,.006,.00221,-.00551*
20,1,.006,.00221,-.00551,.00221,.00551,0.0*
1,1,.006,.00221,.00551*
20,1,.006,.00221,.00551,-.00458,-.00239,0.0*
1,1,.006,-.00458,-.00239*
20,1,.006,-.00458,-.00239,.0046,-.00239,0.0*
1,1,.006,.0046,-.00239*
1,1,.006,.01324,-.00551*
20,1,.006,.01324,-.00551,.01324,.00551,0.0*
1,1,.006,.01324,.00551*
20,1,.006,.01324,.00551,.00645,-.00239,0.0*
1,1,.006,.00645,-.00239*
20,1,.006,.00645,-.00239,.01563,-.00239,0.0*
1,1,.006,.01563,-.00239*
%
%ADD18MACRO18*%
%AMMACRO37*
1,1,.006,-.0265,.022*
20,1,.006,-.0265,.022,.0265,.022,0.0*
1,1,.006,.0265,.022*
20,1,.006,.0265,.022,.03032,.021666,0.0*
1,1,.006,.03032,.021666*
20,1,.006,.03032,.021666,.034024,.020673,0.0*
1,1,.006,.034024,.020673*
20,1,.006,.034024,.020673,.0375,.019053,0.0*
1,1,.006,.0375,.019053*
20,1,.006,.0375,.019053,.040641,.016853,0.0*
1,1,.006,.040641,.016853*
20,1,.006,.040641,.016853,.043353,.014141,0.0*
1,1,.006,.043353,.014141*
20,1,.006,.043353,.014141,.045553,.011,0.0*
1,1,.006,.045553,.011*
20,1,.006,.045553,.011,.047173,.007524,0.0*
1,1,.006,.047173,.007524*
20,1,.006,.047173,.007524,.048166,.00382,0.0*
1,1,.006,.048166,.00382*
20,1,.006,.048166,.00382,.0485,0.0,0.0*
1,1,.006,.0485,0.0*
20,1,.006,.0485,0.0,.048166,-.00382,0.0*
1,1,.006,.048166,-.00382*
20,1,.006,.048166,-.00382,.047173,-.007524,0.0*
1,1,.006,.047173,-.007524*
20,1,.006,.047173,-.007524,.045553,-.011,0.0*
1,1,.006,.045553,-.011*
20,1,.006,.045553,-.011,.043353,-.014141,0.0*
1,1,.006,.043353,-.014141*
20,1,.006,.043353,-.014141,.040641,-.016853,0.0*
1,1,.006,.040641,-.016853*
20,1,.006,.040641,-.016853,.0375,-.019053,0.0*
1,1,.006,.0375,-.019053*
20,1,.006,.0375,-.019053,.034024,-.020673,0.0*
1,1,.006,.034024,-.020673*
20,1,.006,.034024,-.020673,.03032,-.021666,0.0*
1,1,.006,.03032,-.021666*
20,1,.006,.03032,-.021666,.0265,-.022,0.0*
1,1,.006,.0265,-.022*
20,1,.006,.0265,-.022,-.0265,-.022,0.0*
1,1,.006,-.0265,-.022*
20,1,.006,-.0265,-.022,-.03032,-.021666,0.0*
1,1,.006,-.03032,-.021666*
20,1,.006,-.03032,-.021666,-.034024,-.020673,0.0*
1,1,.006,-.034024,-.020673*
20,1,.006,-.034024,-.020673,-.0375,-.019053,0.0*
1,1,.006,-.0375,-.019053*
20,1,.006,-.0375,-.019053,-.040641,-.016853,0.0*
1,1,.006,-.040641,-.016853*
20,1,.006,-.040641,-.016853,-.043353,-.014141,0.0*
1,1,.006,-.043353,-.014141*
20,1,.006,-.043353,-.014141,-.045553,-.011,0.0*
1,1,.006,-.045553,-.011*
20,1,.006,-.045553,-.011,-.047173,-.007524,0.0*
1,1,.006,-.047173,-.007524*
20,1,.006,-.047173,-.007524,-.048166,-.00382,0.0*
1,1,.006,-.048166,-.00382*
20,1,.006,-.048166,-.00382,-.0485,0.0,0.0*
1,1,.006,-.0485,0.0*
20,1,.006,-.0485,0.0,-.048166,.00382,0.0*
1,1,.006,-.048166,.00382*
20,1,.006,-.048166,.00382,-.047173,.007524,0.0*
1,1,.006,-.047173,.007524*
20,1,.006,-.047173,.007524,-.045553,.011,0.0*
1,1,.006,-.045553,.011*
20,1,.006,-.045553,.011,-.043353,.014141,0.0*
1,1,.006,-.043353,.014141*
20,1,.006,-.043353,.014141,-.040641,.016853,0.0*
1,1,.006,-.040641,.016853*
20,1,.006,-.040641,.016853,-.0375,.019053,0.0*
1,1,.006,-.0375,.019053*
20,1,.006,-.0375,.019053,-.034024,.020673,0.0*
1,1,.006,-.034024,.020673*
20,1,.006,-.034024,.020673,-.03032,.021666,0.0*
1,1,.006,-.03032,.021666*
20,1,.006,-.03032,.021666,-.0265,.022,0.0*
1,1,.006,-.0265,.022*
1,1,.006,-.01232,-.0077*
20,1,.006,-.01232,-.0077,-.01232,.0077,0.0*
1,1,.006,-.01232,.0077*
20,1,.006,-.01232,.0077,-.02182,-.00334,0.0*
1,1,.006,-.02182,-.00334*
20,1,.006,-.02182,-.00334,-.00898,-.00334,0.0*
1,1,.006,-.00898,-.00334*
1,1,.006,-.00461,-.0077*
20,1,.006,-.00461,-.0077,-.00461,.0077,0.0*
1,1,.006,-.00461,.0077*
1,1,.006,-.00461,0.0*
20,1,.006,-.00461,0.0,-.00333,.00154,0.0*
1,1,.006,-.00333,.00154*
20,1,.006,-.00333,.00154,-.00179,.00231,0.0*
1,1,.006,-.00179,.00231*
20,1,.006,-.00179,.00231,-.00025,.00257,0.0*
1,1,.006,-.00025,.00257*
20,1,.006,-.00025,.00257,.00206,.00205,0.0*
1,1,.006,.00206,.00205*
20,1,.006,.00206,.00205,.0036,.00103,0.0*
1,1,.006,.0036,.00103*
20,1,.006,.0036,.00103,.00463,-.00077,0.0*
1,1,.006,.00463,-.00077*
20,1,.006,.00463,-.00077,.00463,-.00282,0.0*
1,1,.006,.00463,-.00282*
20,1,.006,.00463,-.00282,.00412,-.00488,0.0*
1,1,.006,.00412,-.00488*
20,1,.006,.00412,-.00488,.00309,-.00642,0.0*
1,1,.006,.00309,-.00642*
20,1,.006,.00309,-.00642,.00129,-.00744,0.0*
1,1,.006,.00129,-.00744*
20,1,.006,.00129,-.00744,-.00025,-.0077,0.0*
1,1,.006,-.00025,-.0077*
20,1,.006,-.00025,-.0077,-.00179,-.00744,0.0*
1,1,.006,-.00179,-.00744*
20,1,.006,-.00179,-.00744,-.00333,-.00667,0.0*
1,1,.006,-.00333,-.00667*
20,1,.006,-.00333,-.00667,-.00461,-.00539,0.0*
1,1,.006,-.00461,-.00539*
1,1,.006,.01183,-.01155*
20,1,.006,.01183,-.01155,.01362,-.01258,0.0*
1,1,.006,.01362,-.01258*
20,1,.006,.01362,-.01258,.01568,-.01283,0.0*
1,1,.006,.01568,-.01283*
20,1,.006,.01568,-.01283,.01747,-.01258,0.0*
1,1,.006,.01747,-.01258*
20,1,.006,.01747,-.01258,.01901,-.01129,0.0*
1,1,.006,.01901,-.01129*
20,1,.006,.01901,-.01129,.02004,-.0095,0.0*
1,1,.006,.02004,-.0095*
20,1,.006,.02004,-.0095,.02004,.00257,0.0*
1,1,.006,.02004,.00257*
1,1,.006,.02004,.00051*
20,1,.006,.02004,.00051,.01901,.00154,0.0*
1,1,.006,.01901,.00154*
20,1,.006,.01901,.00154,.01747,.00231,0.0*
1,1,.006,.01747,.00231*
20,1,.006,.01747,.00231,.01568,.00257,0.0*
1,1,.006,.01568,.00257*
20,1,.006,.01568,.00257,.01362,.00205,0.0*
1,1,.006,.01362,.00205*
20,1,.006,.01362,.00205,.01234,.00103,0.0*
1,1,.006,.01234,.00103*
20,1,.006,.01234,.00103,.01131,-.00077,0.0*
1,1,.006,.01131,-.00077*
20,1,.006,.01131,-.00077,.0108,-.00257,0.0*
1,1,.006,.0108,-.00257*
20,1,.006,.0108,-.00257,.01106,-.00411,0.0*
1,1,.006,.01106,-.00411*
20,1,.006,.01106,-.00411,.01208,-.0059,0.0*
1,1,.006,.01208,-.0059*
20,1,.006,.01208,-.0059,.01362,-.00719,0.0*
1,1,.006,.01362,-.00719*
20,1,.006,.01362,-.00719,.01568,-.0077,0.0*
1,1,.006,.01568,-.0077*
20,1,.006,.01568,-.0077,.01722,-.00744,0.0*
1,1,.006,.01722,-.00744*
20,1,.006,.01722,-.00744,.01901,-.00642,0.0*
1,1,.006,.01901,-.00642*
20,1,.006,.01901,-.00642,.02004,-.00539,0.0*
1,1,.006,.02004,-.00539*
%
%ADD37MACRO37*%
%AMMACRO43*
1,1,.006,0.0,.035*
20,1,.006,0.0,.035,.030311,-.0175,0.0*
1,1,.006,.030311,-.0175*
20,1,.006,.030311,-.0175,-.030311,-.0175,0.0*
1,1,.006,-.030311,-.0175*
20,1,.006,-.030311,-.0175,0.0,.035,0.0*
1,1,.006,0.0,.035*
1,1,.006,-.01102,.00551*
20,1,.006,-.01102,.00551,-.01249,.00514,0.0*
1,1,.006,-.01249,.00514*
20,1,.006,-.01249,.00514,-.01359,.00422,0.0*
1,1,.006,-.01359,.00422*
20,1,.006,-.01359,.00422,-.01433,.00312,0.0*
1,1,.006,-.01433,.00312*
20,1,.006,-.01433,.00312,-.01488,.00165,0.0*
1,1,.006,-.01488,.00165*
20,1,.006,-.01488,.00165,-.01506,0.0,0.0*
1,1,.006,-.01506,0.0*
20,1,.006,-.01506,0.0,-.01488,-.00165,0.0*
1,1,.006,-.01488,-.00165*
20,1,.006,-.01488,-.00165,-.01433,-.00312,0.0*
1,1,.006,-.01433,-.00312*
20,1,.006,-.01433,-.00312,-.01359,-.00422,0.0*
1,1,.006,-.01359,-.00422*
20,1,.006,-.01359,-.00422,-.01249,-.00514,0.0*
1,1,.006,-.01249,-.00514*
20,1,.006,-.01249,-.00514,-.01102,-.00551,0.0*
1,1,.006,-.01102,-.00551*
20,1,.006,-.01102,-.00551,-.00955,-.00514,0.0*
1,1,.006,-.00955,-.00514*
20,1,.006,-.00955,-.00514,-.00845,-.00422,0.0*
1,1,.006,-.00845,-.00422*
20,1,.006,-.00845,-.00422,-.00771,-.00312,0.0*
1,1,.006,-.00771,-.00312*
20,1,.006,-.00771,-.00312,-.00716,-.00165,0.0*
1,1,.006,-.00716,-.00165*
20,1,.006,-.00716,-.00165,-.00698,0.0,0.0*
1,1,.006,-.00698,0.0*
20,1,.006,-.00698,0.0,-.00716,.00165,0.0*
1,1,.006,-.00716,.00165*
20,1,.006,-.00716,.00165,-.00771,.00312,0.0*
1,1,.006,-.00771,.00312*
20,1,.006,-.00771,.00312,-.00845,.00422,0.0*
1,1,.006,-.00845,.00422*
20,1,.006,-.00845,.00422,-.00955,.00514,0.0*
1,1,.006,-.00955,.00514*
20,1,.006,-.00955,.00514,-.01102,.00551,0.0*
1,1,.006,-.01102,.00551*
1,1,.006,-.00348,-.00092*
20,1,.006,-.00348,-.00092,-.00219,.00037,0.0*
1,1,.006,-.00219,.00037*
20,1,.006,-.00219,.00037,-.00109,.0011,0.0*
1,1,.006,-.00109,.0011*
20,1,.006,-.00109,.0011,.00038,.00147,0.0*
1,1,.006,.00038,.00147*
20,1,.006,.00038,.00147,.00166,.0011,0.0*
1,1,.006,.00166,.0011*
20,1,.006,.00166,.0011,.00258,.00037,0.0*
1,1,.006,.00258,.00037*
20,1,.006,.00258,.00037,.00332,-.00073,0.0*
1,1,.006,.00332,-.00073*
20,1,.006,.00332,-.00073,.0035,-.00202,0.0*
1,1,.006,.0035,-.00202*
20,1,.006,.0035,-.00202,.00332,-.00312,0.0*
1,1,.006,.00332,-.00312*
20,1,.006,.00332,-.00312,.00258,-.00422,0.0*
1,1,.006,.00258,-.00422*
20,1,.006,.00258,-.00422,.00148,-.00514,0.0*
1,1,.006,.00148,-.00514*
20,1,.006,.00148,-.00514,.00019,-.00551,0.0*
1,1,.006,.00019,-.00551*
20,1,.006,.00019,-.00551,-.00128,-.00514,0.0*
1,1,.006,-.00128,-.00514*
20,1,.006,-.00128,-.00514,-.00256,-.00404,0.0*
1,1,.006,-.00256,-.00404*
20,1,.006,-.00256,-.00404,-.0033,-.00239,0.0*
1,1,.006,-.0033,-.00239*
20,1,.006,-.0033,-.00239,-.00348,-.00055,0.0*
1,1,.006,-.00348,-.00055*
20,1,.006,-.00348,-.00055,-.00311,.00184,0.0*
1,1,.006,-.00311,.00184*
20,1,.006,-.00311,.00184,-.00256,.00312,0.0*
1,1,.006,-.00256,.00312*
20,1,.006,-.00256,.00312,-.00164,.00441,0.0*
1,1,.006,-.00164,.00441*
20,1,.006,-.00164,.00441,-.00036,.00533,0.0*
1,1,.006,-.00036,.00533*
20,1,.006,-.00036,.00533,.00093,.00551,0.0*
1,1,.006,.00093,.00551*
20,1,.006,.00093,.00551,.00221,.00514,0.0*
1,1,.006,.00221,.00514*
20,1,.006,.00221,.00514,.00313,.00422,0.0*
1,1,.006,.00313,.00422*
1,1,.006,.01067,-.00551*
20,1,.006,.01067,-.00551,.01104,-.00312,0.0*
1,1,.006,.01104,-.00312*
20,1,.006,.01104,-.00312,.01159,-.0011,0.0*
1,1,.006,.01159,-.0011*
20,1,.006,.01159,-.0011,.01233,.00073,0.0*
1,1,.006,.01233,.00073*
20,1,.006,.01233,.00073,.01324,.00275,0.0*
1,1,.006,.01324,.00275*
20,1,.006,.01324,.00275,.01471,.00551,0.0*
1,1,.006,.01471,.00551*
20,1,.006,.01471,.00551,.00737,.00551,0.0*
1,1,.006,.00737,.00551*
%
%ADD43MACRO43*%
%AMMACRO17*
1,1,.006,-.0245,.0235*
20,1,.006,-.0245,.0235,.0245,.0235,0.0*
1,1,.006,.0245,.0235*
20,1,.006,.0245,.0235,.028581,.023143,0.0*
1,1,.006,.028581,.023143*
20,1,.006,.028581,.023143,.032537,.022083,0.0*
1,1,.006,.032537,.022083*
20,1,.006,.032537,.022083,.03625,.020352,0.0*
1,1,.006,.03625,.020352*
20,1,.006,.03625,.020352,.039606,.018002,0.0*
1,1,.006,.039606,.018002*
20,1,.006,.039606,.018002,.042502,.015106,0.0*
1,1,.006,.042502,.015106*
20,1,.006,.042502,.015106,.044852,.01175,0.0*
1,1,.006,.044852,.01175*
20,1,.006,.044852,.01175,.046583,.008037,0.0*
1,1,.006,.046583,.008037*
20,1,.006,.046583,.008037,.047643,.004081,0.0*
1,1,.006,.047643,.004081*
20,1,.006,.047643,.004081,.048,0.0,0.0*
1,1,.006,.048,0.0*
20,1,.006,.048,0.0,.047643,-.004081,0.0*
1,1,.006,.047643,-.004081*
20,1,.006,.047643,-.004081,.046583,-.008037,0.0*
1,1,.006,.046583,-.008037*
20,1,.006,.046583,-.008037,.044852,-.01175,0.0*
1,1,.006,.044852,-.01175*
20,1,.006,.044852,-.01175,.042502,-.015106,0.0*
1,1,.006,.042502,-.015106*
20,1,.006,.042502,-.015106,.039606,-.018002,0.0*
1,1,.006,.039606,-.018002*
20,1,.006,.039606,-.018002,.03625,-.020352,0.0*
1,1,.006,.03625,-.020352*
20,1,.006,.03625,-.020352,.032537,-.022083,0.0*
1,1,.006,.032537,-.022083*
20,1,.006,.032537,-.022083,.028581,-.023143,0.0*
1,1,.006,.028581,-.023143*
20,1,.006,.028581,-.023143,.0245,-.0235,0.0*
1,1,.006,.0245,-.0235*
20,1,.006,.0245,-.0235,-.0245,-.0235,0.0*
1,1,.006,-.0245,-.0235*
20,1,.006,-.0245,-.0235,-.028581,-.023143,0.0*
1,1,.006,-.028581,-.023143*
20,1,.006,-.028581,-.023143,-.032537,-.022083,0.0*
1,1,.006,-.032537,-.022083*
20,1,.006,-.032537,-.022083,-.03625,-.020352,0.0*
1,1,.006,-.03625,-.020352*
20,1,.006,-.03625,-.020352,-.039606,-.018002,0.0*
1,1,.006,-.039606,-.018002*
20,1,.006,-.039606,-.018002,-.042502,-.015106,0.0*
1,1,.006,-.042502,-.015106*
20,1,.006,-.042502,-.015106,-.044852,-.01175,0.0*
1,1,.006,-.044852,-.01175*
20,1,.006,-.044852,-.01175,-.046583,-.008037,0.0*
1,1,.006,-.046583,-.008037*
20,1,.006,-.046583,-.008037,-.047643,-.004081,0.0*
1,1,.006,-.047643,-.004081*
20,1,.006,-.047643,-.004081,-.048,0.0,0.0*
1,1,.006,-.048,0.0*
20,1,.006,-.048,0.0,-.047643,.004081,0.0*
1,1,.006,-.047643,.004081*
20,1,.006,-.047643,.004081,-.046583,.008037,0.0*
1,1,.006,-.046583,.008037*
20,1,.006,-.046583,.008037,-.044852,.01175,0.0*
1,1,.006,-.044852,.01175*
20,1,.006,-.044852,.01175,-.042502,.015106,0.0*
1,1,.006,-.042502,.015106*
20,1,.006,-.042502,.015106,-.039606,.018002,0.0*
1,1,.006,-.039606,.018002*
20,1,.006,-.039606,.018002,-.03625,.020352,0.0*
1,1,.006,-.03625,.020352*
20,1,.006,-.03625,.020352,-.032537,.022083,0.0*
1,1,.006,-.032537,.022083*
20,1,.006,-.032537,.022083,-.028581,.023143,0.0*
1,1,.006,-.028581,.023143*
20,1,.006,-.028581,.023143,-.0245,.0235,0.0*
1,1,.006,-.0245,.0235*
1,1,.006,-.01809,-.00822*
20,1,.006,-.01809,-.00822,-.01809,.00576,0.0*
1,1,.006,-.01809,.00576*
20,1,.006,-.01809,.00576,-.01754,.00713,0.0*
1,1,.006,-.01754,.00713*
20,1,.006,-.01754,.00713,-.01645,.00796,0.0*
1,1,.006,-.01645,.00796*
20,1,.006,-.01645,.00796,-.0148,.00823,0.0*
1,1,.006,-.0148,.00823*
20,1,.006,-.0148,.00823,-.01315,.00768,0.0*
1,1,.006,-.01315,.00768*
20,1,.006,-.01315,.00768,-.01233,.00631,0.0*
1,1,.006,-.01233,.00631*
1,1,.006,-.01562,.00165*
20,1,.006,-.01562,.00165,-.02111,.00165,0.0*
1,1,.006,-.02111,.00165*
1,1,.006,-.00492,-.00822*
20,1,.006,-.00492,-.00822,-.00492,.00823,0.0*
1,1,.006,-.00492,.00823*
1,1,.006,-.00492,0.0*
20,1,.006,-.00492,0.0,-.00355,.00165,0.0*
1,1,.006,-.00355,.00165*
20,1,.006,-.00355,.00165,-.0019,.00247,0.0*
1,1,.006,-.0019,.00247*
20,1,.006,-.0019,.00247,-.00026,.00275,0.0*
1,1,.006,-.00026,.00275*
20,1,.006,-.00026,.00275,.00221,.0022,0.0*
1,1,.006,.00221,.0022*
20,1,.006,.00221,.0022,.00385,.0011,0.0*
1,1,.006,.00385,.0011*
20,1,.006,.00385,.0011,.00495,-.00082,0.0*
1,1,.006,.00495,-.00082*
20,1,.006,.00495,-.00082,.00495,-.00301,0.0*
1,1,.006,.00495,-.00301*
20,1,.006,.00495,-.00301,.0044,-.0052,0.0*
1,1,.006,.0044,-.0052*
20,1,.006,.0044,-.0052,.00331,-.00685,0.0*
1,1,.006,.00331,-.00685*
20,1,.006,.00331,-.00685,.00139,-.00795,0.0*
1,1,.006,.00139,-.00795*
20,1,.006,.00139,-.00795,-.00026,-.00822,0.0*
1,1,.006,-.00026,-.00822*
20,1,.006,-.00026,-.00822,-.0019,-.00795,0.0*
1,1,.006,-.0019,-.00795*
20,1,.006,-.0019,-.00795,-.00355,-.00712,0.0*
1,1,.006,-.00355,-.00712*
20,1,.006,-.00355,-.00712,-.00492,-.00575,0.0*
1,1,.006,-.00492,-.00575*
1,1,.006,.01593,-.00822*
20,1,.006,.01593,-.00822,.01647,-.00466,0.0*
1,1,.006,.01647,-.00466*
20,1,.006,.01647,-.00466,.0173,-.00164,0.0*
1,1,.006,.0173,-.00164*
20,1,.006,.0173,-.00164,.01839,.0011,0.0*
1,1,.006,.01839,.0011*
20,1,.006,.01839,.0011,.01977,.00412,0.0*
1,1,.006,.01977,.00412*
20,1,.006,.01977,.00412,.02196,.00823,0.0*
1,1,.006,.02196,.00823*
20,1,.006,.02196,.00823,.01099,.00823,0.0*
1,1,.006,.01099,.00823*
%
%ADD17MACRO17*%
%ADD44C,.01*%
%ADD45C,.006*%
G75*
%LPD*%
G75*
G54D10*
X27559Y87795D03*
X40708Y631890D03*
Y1368897D03*
X51181Y1714961D03*
X373622Y87795D03*
X395670Y1714961D03*
X661023Y631890D03*
X707677Y1714961D03*
X800787Y87795D03*
X931692Y757874D03*
Y1072834D03*
Y1387795D03*
X1045865Y87795D03*
X1155708Y1714961D03*
X1271260Y631890D03*
X1461805Y1714961D03*
X1499606Y87795D03*
X1816771Y631890D03*
Y1368897D03*
X1806299Y1714961D03*
X1829921Y87795D03*
X2822321Y872529D03*
G54D11*
X3010Y63308D03*
Y123308D03*
Y163308D03*
Y183308D03*
Y203308D03*
Y223308D03*
Y243308D03*
Y263308D03*
Y283308D03*
Y303308D03*
X10884Y321693D03*
Y341693D03*
Y361693D03*
Y381693D03*
Y401693D03*
Y421693D03*
Y441693D03*
Y461693D03*
Y481693D03*
Y501693D03*
Y521693D03*
Y661693D03*
Y681693D03*
Y701693D03*
Y721693D03*
Y741693D03*
Y781693D03*
Y801693D03*
Y821693D03*
Y841693D03*
Y861693D03*
Y881693D03*
Y901693D03*
Y921693D03*
Y941693D03*
Y961693D03*
Y981693D03*
Y1001693D03*
Y1021693D03*
Y1041693D03*
Y1061693D03*
Y1081693D03*
Y1101693D03*
Y1121693D03*
Y1141693D03*
Y1161693D03*
Y1181693D03*
Y1201693D03*
Y1221693D03*
Y1241693D03*
Y1401693D03*
Y1421693D03*
Y1441693D03*
Y1461693D03*
Y1481693D03*
Y1501693D03*
Y1521693D03*
Y1541693D03*
Y1561693D03*
Y1581693D03*
X17371Y49388D03*
X26054Y195148D03*
X25752Y203274D03*
X24754Y220220D03*
X24814Y236472D03*
X22223Y388057D03*
X29509Y398132D03*
X16420Y420662D03*
X26615Y670036D03*
X26500Y672862D03*
Y675862D03*
X24700Y765600D03*
X27300Y764200D03*
X27520Y1245162D03*
X20188Y1599396D03*
X28601Y1617541D03*
Y1637541D03*
Y1657541D03*
Y1677541D03*
X37371Y49388D03*
X30795Y213358D03*
X35600Y227380D03*
X30795Y227366D03*
X41492Y290637D03*
X33105Y304972D03*
X42809Y360862D03*
X35740Y363337D03*
X39410Y384582D03*
X39226Y395346D03*
X33020Y382822D03*
X43020Y382942D03*
X41933Y395652D03*
X36524Y398013D03*
X45182Y426310D03*
X45960Y428806D03*
X30680Y438142D03*
X45812Y451602D03*
X45034Y449106D03*
X45812Y451602D03*
X38220Y589862D03*
Y592862D03*
Y595862D03*
X33020Y595232D03*
X32720Y598402D03*
X34790Y666595D03*
X31390D03*
X38470Y688122D03*
Y683122D03*
Y680622D03*
Y685622D03*
Y693122D03*
Y690622D03*
Y695622D03*
X34899Y711400D03*
X45700Y724100D03*
X45800Y726874D03*
X43841Y1248688D03*
X44833Y1659909D03*
Y1656759D03*
X54593Y19183D03*
X61157Y69340D03*
X64557D03*
X58379D03*
X60379Y66844D03*
Y71836D03*
X61157Y69340D03*
X61470Y84622D03*
X60692Y87118D03*
X61470Y84622D03*
X62731Y305426D03*
X46834Y360862D03*
X55190D03*
X59322Y360702D03*
X51114Y360862D03*
X61340Y384362D03*
X61250Y396142D03*
X49250Y396332D03*
X49400Y384392D03*
X62812Y412708D03*
X62813Y415750D03*
X47618Y413113D03*
X62833Y410047D03*
X62812Y412708D03*
X53406Y402862D03*
X47619Y421155D03*
X62808Y418425D03*
X50138Y426310D03*
X60393D03*
X62813Y415750D03*
X49360Y428806D03*
X61171D03*
X47619Y418655D03*
X47618Y415613D03*
X54762Y444993D03*
X53800Y435451D03*
X49212Y451602D03*
X49990Y449106D03*
X49212Y451602D03*
X48400Y586000D03*
X59500Y738700D03*
X58658Y754145D03*
X55177Y1322328D03*
X55277Y1326068D03*
X56799Y1520094D03*
Y1524094D03*
Y1528094D03*
Y1532094D03*
Y1536094D03*
Y1544094D03*
Y1548094D03*
Y1552094D03*
Y1540094D03*
Y1556094D03*
Y1560094D03*
X64410Y1599102D03*
Y1602502D03*
X54333Y1604359D03*
X59833D03*
X54333Y1613359D03*
X50333D03*
X46994Y1663165D03*
X50900Y1677775D03*
X57833Y1671809D03*
X69058Y3010D03*
X78269Y26474D03*
X74869D03*
X79047Y23978D03*
X74091D03*
X72091Y25974D03*
X73020Y37106D03*
Y28406D03*
X78269Y26474D03*
X74869D03*
X65937Y28403D03*
X73020Y48720D03*
Y40020D03*
X65937Y48720D03*
X67335Y69340D03*
X65335Y66844D03*
Y71836D03*
X64557Y69340D03*
X72157Y75340D03*
X75557D03*
X64870Y84622D03*
X65648Y87118D03*
X71379Y72844D03*
Y77836D03*
X76335Y72844D03*
Y77836D03*
X78335Y75340D03*
X69379D03*
X72157D03*
X75557D03*
X64870Y84622D03*
X77165Y278798D03*
Y295798D03*
Y286262D03*
Y303262D03*
X63429Y360702D03*
X67681D03*
X77220Y379022D03*
Y381522D03*
X68020Y395222D03*
X65349Y426310D03*
X75516Y420319D03*
Y424319D03*
X64571Y428806D03*
X75516Y436519D03*
X68365Y443677D03*
X64150Y434972D03*
X63540Y438802D03*
X72610Y441262D03*
Y444762D03*
X77000Y485362D03*
X74550Y487812D03*
X74340Y663422D03*
X76365Y699244D03*
X78080Y701832D03*
X72315Y717414D03*
X64325Y715674D03*
X63930Y739300D03*
X73759Y754726D03*
X73865Y763164D03*
X68315Y765664D03*
X73759Y759246D03*
X72485Y1304152D03*
X75485D03*
X78485D03*
X72485Y1307152D03*
X75485D03*
X69485Y1304152D03*
Y1307152D03*
X75485Y1316152D03*
X72485Y1313152D03*
Y1310152D03*
X75485Y1313152D03*
Y1310152D03*
X69485D03*
X69809Y1333918D03*
Y1331418D03*
Y1336418D03*
X72809Y1333918D03*
Y1331418D03*
Y1336418D03*
X75809Y1333918D03*
Y1331418D03*
Y1336418D03*
X72909Y1339938D03*
X79009Y1340238D03*
X75909Y1339938D03*
X73027Y1347925D03*
X73059Y1345138D03*
X72987Y1342535D03*
X75909Y1342438D03*
X79009Y1342738D03*
Y1345238D03*
X78977Y1348025D03*
X75859Y1348138D03*
Y1345138D03*
X76369Y1507456D03*
X78120Y1515436D03*
Y1518836D03*
X79769Y1507456D03*
X75564Y1509952D03*
X78120Y1512936D03*
Y1515436D03*
Y1518836D03*
X76369Y1507456D03*
X78120Y1521336D03*
X76680Y1530482D03*
X72774Y1549669D03*
Y1546519D03*
X75922Y1562374D03*
Y1558974D03*
Y1564874D03*
Y1556474D03*
Y1558974D03*
Y1562374D03*
X74218Y1572504D03*
X77618D03*
X73429Y1570008D03*
X78415D03*
X77618Y1572504D03*
X74218D03*
X66906Y1598324D03*
X64410Y1599102D03*
X66906Y1603280D03*
X64410Y1602502D03*
X73832Y1689362D03*
X77833Y1689162D03*
X89058Y3010D03*
X85374Y19538D03*
X81974D03*
X96147D03*
X81196Y17042D03*
Y22034D03*
X86152Y17042D03*
Y22034D03*
X95369Y17042D03*
Y22034D03*
X79196Y19538D03*
X88152D03*
X93369D03*
X85374D03*
X81974D03*
X92442Y26474D03*
X89042D03*
X88264Y23978D03*
X93220D03*
X86264Y25974D03*
X95220D03*
X81047D03*
X94279Y37106D03*
Y28406D03*
X87193Y37106D03*
Y28406D03*
X80106Y37106D03*
Y28406D03*
X92442Y26474D03*
X89042D03*
X94279Y48720D03*
Y40020D03*
X87193Y48720D03*
Y40020D03*
X80106Y48720D03*
Y40020D03*
X83157Y69340D03*
X86557D03*
X80379D03*
X89335D03*
X82379Y66844D03*
Y71836D03*
X87335Y66844D03*
Y71836D03*
X86557Y69340D03*
X83157D03*
X94157Y75340D03*
X91379D03*
X93379Y72844D03*
Y77836D03*
X94157Y75340D03*
X90700Y282762D03*
Y300262D03*
X87520Y395865D03*
Y391391D03*
Y382219D03*
X85826Y424319D03*
Y428319D03*
X83320Y445212D03*
X82661Y449604D03*
X94439Y450081D03*
X81505Y447377D03*
X79400Y482862D03*
X89859Y628246D03*
X86459D03*
X80460Y655672D03*
X83100Y649762D03*
X82961Y657111D03*
X87565Y670441D03*
X83250Y665428D03*
X84470Y668702D03*
X81285Y689804D03*
X84035Y697604D03*
X94473Y698926D03*
X79451Y699517D03*
X93547Y692260D03*
X82735Y717949D03*
X87865Y714394D03*
X85165D03*
X81225Y715854D03*
X79635Y717949D03*
X85835Y718049D03*
X85095Y722164D03*
X82357Y737803D03*
X84623Y741249D03*
X93295Y762019D03*
X81966Y759246D03*
X85877Y759275D03*
X93485Y1304152D03*
X87485D03*
X90485D03*
X93485Y1307152D03*
X84485Y1304152D03*
X81485D03*
X93485Y1318152D03*
Y1315652D03*
Y1310152D03*
Y1313152D03*
X94209Y1337738D03*
X81809Y1340238D03*
X84809D03*
X87809D03*
X90809D03*
X94209D03*
X84809Y1345238D03*
X81809Y1342738D03*
X84809D03*
X81809Y1348238D03*
Y1345238D03*
X84809Y1348238D03*
X87809D03*
Y1345238D03*
Y1342738D03*
X94209D03*
Y1348238D03*
Y1345238D03*
X90809Y1348238D03*
Y1345238D03*
Y1342738D03*
X88520Y1484482D03*
X92071Y1492888D03*
X88520Y1491482D03*
Y1487982D03*
Y1494982D03*
X90998Y1515537D03*
Y1518937D03*
X92664Y1507611D03*
X89264D03*
X80649Y1509944D03*
X84274Y1517619D03*
X93544Y1510099D03*
X88459Y1510107D03*
X90998Y1513037D03*
Y1518937D03*
Y1515537D03*
X89264Y1507611D03*
X92664D03*
X79769Y1507456D03*
X90998Y1521437D03*
X81038Y1536899D03*
X91538Y1539399D03*
X87500Y1567069D03*
X91500D03*
X84048Y1578008D03*
X90713Y1581852D03*
Y1585852D03*
Y1589852D03*
Y1593867D03*
Y1597867D03*
X81008Y1589872D03*
X90788Y1611821D03*
Y1605867D03*
Y1615821D03*
Y1601867D03*
Y1623821D03*
X84700Y1627000D03*
X90698Y1630362D03*
X90788Y1619821D03*
X90698Y1638362D03*
Y1634362D03*
Y1642362D03*
X90407Y1656672D03*
X88333Y1661334D03*
X86245Y1690362D03*
X81833Y1689162D03*
X94220Y1686622D03*
X86245Y1694362D03*
X86030Y1683092D03*
X92895Y1737108D03*
X109058Y3010D03*
X99547Y19538D03*
X110320D03*
X100325Y17042D03*
Y22034D03*
X109542Y17042D03*
Y22034D03*
X102325Y19538D03*
X107542D03*
X99547D03*
X110320D03*
X96147D03*
X103215Y26474D03*
X106615D03*
X102437Y23978D03*
X107393D03*
X100437Y25974D03*
X109393D03*
X108453Y37106D03*
Y28406D03*
X101366Y37106D03*
Y28406D03*
X106615Y26474D03*
X103215D03*
X108453Y48720D03*
Y40020D03*
X101366Y48720D03*
Y40020D03*
X108557Y69340D03*
X105157D03*
X102379D03*
X111335D03*
X104379Y66844D03*
Y71836D03*
X109335Y66844D03*
Y71836D03*
X108557Y69340D03*
X105157D03*
X97557Y75340D03*
X98335Y72844D03*
Y77836D03*
X100335Y75340D03*
X97557D03*
X110937Y285495D03*
Y302854D03*
X104220Y400862D03*
X101720D03*
X102060Y493578D03*
X104875Y490980D03*
X102152Y509374D03*
X102334Y500628D03*
X102359Y497374D03*
X102384Y505374D03*
X110464D03*
X102152Y513374D03*
X111087Y520052D03*
X101983Y518100D03*
X99880Y526300D03*
X110060Y515279D03*
X105587Y520727D03*
X106110Y633732D03*
X107489Y630917D03*
X110374Y630879D03*
X108909Y654926D03*
X102909Y648926D03*
Y642926D03*
Y655102D03*
X108909Y642926D03*
X102120Y688650D03*
X102060Y692100D03*
X102420Y697262D03*
X96626Y736187D03*
X110527Y758869D03*
X108465Y1304292D03*
Y1307292D03*
X105475Y1304222D03*
Y1307222D03*
X102485Y1304152D03*
X99485D03*
X96485D03*
X102485Y1307152D03*
X99485D03*
X96485D03*
X108465Y1318292D03*
Y1310292D03*
Y1313292D03*
Y1315792D03*
X105475Y1318222D03*
Y1310222D03*
Y1313222D03*
Y1315722D03*
X99485Y1318152D03*
X96485D03*
Y1315652D03*
Y1310152D03*
Y1313152D03*
X99485Y1310152D03*
Y1313152D03*
Y1315652D03*
X102485Y1318152D03*
Y1310152D03*
Y1313152D03*
Y1315652D03*
X96809Y1340238D03*
Y1345238D03*
Y1348238D03*
Y1342738D03*
X99274Y1526019D03*
Y1529169D03*
X96570Y1546187D03*
X99716Y1567878D03*
X99750Y1559478D03*
Y1565378D03*
Y1561978D03*
X102251Y1576504D03*
X105651D03*
X96251Y1577532D03*
X107451Y1574704D03*
X100451D03*
X102251Y1576504D03*
X105651D03*
X104318Y1592304D03*
Y1603690D03*
X110200Y1605200D03*
X101500Y1604400D03*
X98738Y1605867D03*
X104318Y1622380D03*
X104430Y1628012D03*
X104318Y1641075D03*
X99980Y1685362D03*
Y1696052D03*
Y1687921D03*
X113720Y19538D03*
X127894D03*
X124494D03*
X114498Y17042D03*
Y22034D03*
X123716Y17042D03*
Y22034D03*
X116498Y19538D03*
X121716D03*
X113720D03*
X127894D03*
X124494D03*
X117389Y26474D03*
X120789D03*
X121567Y23978D03*
X116611D03*
X114611Y25974D03*
X123567D03*
X122626Y37106D03*
Y28406D03*
X115539Y37106D03*
Y28406D03*
X120789Y26474D03*
X117389D03*
X122626Y48720D03*
Y40020D03*
X115539Y48720D03*
Y40020D03*
X127157Y69340D03*
X124379D03*
X126379Y66844D03*
Y71836D03*
X127157Y69340D03*
X119557Y75340D03*
X116157D03*
X115379Y72844D03*
Y77836D03*
X120335Y72844D03*
Y77836D03*
X122335Y75340D03*
X113379D03*
X116157D03*
X119557D03*
X119920Y379362D03*
X125007Y392071D03*
Y388071D03*
X119457D03*
X117597Y488434D03*
X127206Y480216D03*
X125013Y491829D03*
X116171Y485041D03*
X126225Y504368D03*
X120225D03*
Y510368D03*
X112483Y510637D03*
X116411Y497707D03*
X126225Y516368D03*
X120225D03*
X115793Y528188D03*
X112393D03*
X123257Y547506D03*
X119087D03*
X115060D03*
X111920Y632922D03*
X114540Y633032D03*
X117750Y633232D03*
X120440Y633347D03*
X127313Y649765D03*
X114909Y654926D03*
Y648926D03*
Y642926D03*
X125890Y644163D03*
X122329Y654660D03*
X122280Y651934D03*
X124431Y649570D03*
X118021Y669409D03*
X127738Y659226D03*
X118019Y661371D03*
X124737Y735726D03*
X118737D03*
X121737D03*
Y738726D03*
X118737D03*
X124737D03*
X120220Y1324662D03*
X120267Y1327697D03*
X127366Y1535855D03*
X112749Y1524594D03*
Y1532594D03*
Y1528594D03*
X127366Y1541874D03*
Y1547935D03*
X112749Y1540594D03*
Y1544594D03*
Y1548594D03*
Y1536594D03*
Y1552594D03*
Y1564594D03*
Y1560594D03*
Y1556594D03*
X117707Y1553759D03*
X116798Y1586288D03*
Y1598572D03*
X125033Y1589352D03*
X123230Y1597350D03*
X116798Y1617262D03*
Y1635303D03*
X117220Y1680287D03*
X127195Y1670362D03*
X117795Y1698862D03*
X127195Y1688362D03*
Y1692362D03*
X114645Y1698862D03*
X117220Y1683437D03*
X127195Y1708362D03*
Y1700362D03*
X117255Y1730422D03*
X125082Y1727092D03*
X123394Y1723472D03*
X112895Y1737108D03*
X129058Y3010D03*
X128672Y17042D03*
Y22034D03*
X130672Y19538D03*
X129713Y37106D03*
Y28406D03*
Y48720D03*
Y40020D03*
X130557Y69340D03*
X133335D03*
X131335Y66844D03*
Y71836D03*
X130557Y69340D03*
X141557Y75340D03*
X138157D03*
X137379Y72844D03*
Y77836D03*
X142335Y72844D03*
Y77836D03*
X135379Y75340D03*
X138157D03*
X141557D03*
X136301Y179095D03*
X141520Y181462D03*
X139720Y179162D03*
X143470Y184012D03*
X143340Y204622D03*
X133590Y212382D03*
X129394Y278875D03*
X129375Y274800D03*
X129394Y306236D03*
X140974Y396885D03*
X135220Y397071D03*
X140974Y401885D03*
Y399385D03*
X142166Y490835D03*
X135006Y487753D03*
X132225Y504368D03*
Y510368D03*
X141325Y503806D03*
X141462Y507600D03*
X141329Y510487D03*
X141220Y498810D03*
X132401Y516368D03*
X132600Y540472D03*
X130057Y636103D03*
X133467Y634531D03*
X130067Y650213D03*
X134205Y643603D03*
X128193Y662015D03*
X128275Y665515D03*
X129600Y669400D03*
X131330Y665740D03*
X142960Y690807D03*
X140460D03*
X142754Y698811D03*
X140254D03*
X142778Y706835D03*
X140278D03*
X140326Y721660D03*
X142826D03*
X132967Y760525D03*
X141470Y1359100D03*
X140142Y1392545D03*
Y1396275D03*
X145538Y1517374D03*
X129670Y1563160D03*
X140104Y1560136D03*
X129627Y1556360D03*
X129586Y1553759D03*
X129813Y1604367D03*
X130533Y1622321D03*
X129533Y1637862D03*
X138492Y1717592D03*
X139080Y1731398D03*
X141642Y1717592D03*
X132895Y1737108D03*
X149058Y3010D03*
X160360Y19538D03*
X159582Y17042D03*
Y22034D03*
X157582Y19538D03*
X160360D03*
X156655Y26474D03*
X153255D03*
X152477Y23978D03*
X157433D03*
X150477Y25974D03*
X159433D03*
X158492Y37106D03*
Y28406D03*
X151405Y37106D03*
Y28406D03*
X156655Y26474D03*
X153255D03*
X147924Y28258D03*
X158492Y48720D03*
Y40020D03*
X151405Y48720D03*
Y40020D03*
X148784Y48720D03*
X152557Y69340D03*
X149157D03*
X146379D03*
X155335D03*
X148379Y66844D03*
Y71836D03*
X153335Y66844D03*
Y71836D03*
X152557Y69340D03*
X149157D03*
X161361Y75340D03*
X158583D03*
X144335D03*
X147901Y188852D03*
X145720Y186462D03*
Y202862D03*
Y206362D03*
X156670Y344542D03*
X159170D03*
X158110Y376172D03*
X149371Y423383D03*
Y419383D03*
Y427383D03*
Y439383D03*
Y431383D03*
Y435383D03*
Y443383D03*
X159125Y448664D03*
X153360Y449112D03*
X152171Y490615D03*
X149557Y494353D03*
X150113Y488487D03*
X149472Y502810D03*
X149486Y498810D03*
X149472Y506810D03*
X160000Y510052D03*
X152470Y495383D03*
X149518Y522810D03*
X149512Y514810D03*
X150800Y512021D03*
X153737Y514893D03*
X149504Y519881D03*
X154647Y521783D03*
X147141Y698811D03*
X147435Y690807D03*
X149861Y698831D03*
X150155Y690807D03*
X156685Y706836D03*
X153965Y706816D03*
X153879Y721660D03*
X156469D03*
X147031Y706835D03*
X149621D03*
X149669Y721660D03*
X147079D03*
X150877Y757969D03*
X151277Y1339183D03*
X153877D03*
X156477D03*
X156417Y1336343D03*
X151217Y1336393D03*
X153817D03*
X156417Y1333843D03*
X151217Y1333893D03*
X153817D03*
X151277Y1346883D03*
X153877D03*
X151277Y1349383D03*
X153877D03*
X156477Y1346883D03*
Y1349383D03*
Y1344383D03*
X151277D03*
X153877D03*
X156477Y1341883D03*
X151277D03*
X153877D03*
X154477Y1360797D03*
X159898Y1360790D03*
X148663Y1378607D03*
X151163D03*
Y1383807D03*
Y1381207D03*
X158318Y1384286D03*
X155718D03*
X158318Y1387393D03*
X155718D03*
X148663Y1386407D03*
X151163D03*
X148663Y1383807D03*
Y1381207D03*
X160201Y1399732D03*
X157731D03*
Y1394132D03*
X160201D03*
X147307Y1404745D03*
X149568Y1397695D03*
X152806Y1414175D03*
X157490Y1421454D03*
X154990D03*
X159858Y1409361D03*
X155858Y1406669D03*
Y1409390D03*
X157530Y1432124D03*
X155030D03*
X157530Y1424124D03*
X155030D03*
X157530Y1429124D03*
X155030Y1426624D03*
Y1429124D03*
X157530Y1426624D03*
Y1435124D03*
X155030D03*
X157530Y1437754D03*
X155030D03*
X148938Y1517374D03*
X144748Y1514878D03*
X149728D03*
X146390Y1504240D03*
X145538Y1517374D03*
X148938D03*
X153600Y1505600D03*
X154581Y1520981D03*
X158570D03*
X153271Y1540961D03*
X153138Y1549032D03*
X147067Y1545985D03*
X149712Y1569525D03*
X146312D03*
X150502Y1572021D03*
X145522D03*
X159107Y1571364D03*
X157441Y1581932D03*
X146312Y1569525D03*
X149712D03*
X155180Y1619872D03*
X156070Y1695702D03*
X144854Y1702389D03*
X154803Y1708532D03*
X145745Y1712362D03*
X155145Y1713517D03*
X155100Y1723262D03*
X152895Y1737108D03*
X169058Y3010D03*
X163760Y19538D03*
X174533D03*
X177933D03*
X164538Y17042D03*
Y22034D03*
X173755Y17042D03*
Y22034D03*
X166538Y19538D03*
X171755D03*
X163760D03*
X174533D03*
X167428Y26474D03*
X170828D03*
X166650Y23978D03*
X171606D03*
X164650Y25974D03*
X173606D03*
X172665Y37106D03*
Y28406D03*
X165579Y37106D03*
Y28406D03*
X170828Y26474D03*
X167428D03*
X172665Y48720D03*
Y40020D03*
X165579Y48720D03*
Y40020D03*
X175761Y69340D03*
X172361D03*
X169583D03*
X171583Y66844D03*
Y71836D03*
X176539Y66844D03*
Y71836D03*
X175761Y69340D03*
X172361D03*
X164761Y75340D03*
X165539Y72844D03*
X160583D03*
Y77836D03*
X165539D03*
X167539Y75340D03*
X161361D03*
X164761D03*
X174327Y230928D03*
X164830Y344542D03*
X161670D03*
X171180Y401885D03*
X163900Y409362D03*
X172507Y417205D03*
X163926Y439397D03*
Y435383D03*
X175640Y453779D03*
X172632Y454095D03*
X163132Y493299D03*
X165176Y500782D03*
X162750Y512502D03*
X166986Y575918D03*
X176393Y575189D03*
X173793D03*
X176393Y572689D03*
X173793D03*
X171293D03*
Y575189D03*
X173793Y577790D03*
X171293D03*
X176393D03*
X176651Y596883D03*
Y594163D03*
X173878Y597027D03*
Y594307D03*
X176651Y599603D03*
X173878Y599747D03*
X161126Y721660D03*
X161078Y706835D03*
X163626Y721660D03*
X163578Y706835D03*
X170877Y1333783D03*
Y1336383D03*
X176077Y1333783D03*
X173477D03*
X176077Y1336383D03*
X173477D03*
X170907Y1339233D03*
X176107D03*
X173507D03*
X170877Y1341883D03*
X176077D03*
X173477D03*
Y1349383D03*
Y1346883D03*
Y1344383D03*
X176077D03*
Y1346883D03*
Y1349383D03*
X170877D03*
Y1346883D03*
Y1344383D03*
X162398Y1360790D03*
X164898D03*
X172807Y1360797D03*
X160918Y1384286D03*
X163518D03*
Y1387393D03*
X160918D03*
X169318Y1384286D03*
X166118D03*
X172262Y1384302D03*
Y1387409D03*
X174932Y1378797D03*
Y1381397D03*
X163718Y1390500D03*
X161118D03*
X162631Y1399732D03*
Y1394132D03*
X172231Y1390532D03*
X176358Y1403669D03*
X176258Y1400669D03*
X173892Y1402749D03*
Y1405649D03*
X170922Y1399255D03*
X166262D03*
X173252Y1400005D03*
X168592D03*
X162693Y1411529D03*
X160490Y1421454D03*
X164000Y1408862D03*
X162257Y1406594D03*
X160530Y1432124D03*
Y1424124D03*
Y1429124D03*
Y1426624D03*
Y1435124D03*
Y1437754D03*
X165500Y1440362D03*
X173727Y1452134D03*
Y1448734D03*
X168110Y1518014D03*
X164710D03*
X170570Y1509250D03*
X164710Y1518014D03*
X168110D03*
X168900Y1520510D03*
X163920D03*
X161321Y1540858D03*
X161374Y1549073D03*
X167266Y1569968D03*
X170666D03*
X166476Y1572464D03*
X171456D03*
X173331Y1579399D03*
X167266Y1569968D03*
X170666D03*
X172099Y1588141D03*
X166529Y1707678D03*
X166661Y1721211D03*
X172895Y1737108D03*
X166761Y1732967D03*
X189058Y3010D03*
X178711Y17042D03*
Y22034D03*
X180711Y19538D03*
X177933D03*
X179752Y37106D03*
Y28406D03*
X186120Y24162D03*
X188620D03*
X179752Y48720D03*
Y40020D03*
X194361Y69340D03*
X191583D03*
X178539D03*
X183361Y75340D03*
X186761D03*
X182583Y72844D03*
Y77836D03*
X187539Y72844D03*
Y77836D03*
X189539Y75340D03*
X180583D03*
X183361D03*
X186761D03*
X186457Y393071D03*
Y385071D03*
Y389071D03*
X190880Y383012D03*
Y387162D03*
Y391082D03*
X178375Y396571D03*
X186457Y405071D03*
X192220Y408662D03*
Y412162D03*
X184490Y402203D03*
X181845Y401071D03*
X177871Y421383D03*
Y425383D03*
X191305Y430216D03*
X187532Y421387D03*
X177871Y430883D03*
Y443383D03*
X187371D03*
X180740Y437562D03*
X184550Y435712D03*
X187371Y440742D03*
X188221Y454048D03*
X184147Y447078D03*
X187371Y447172D03*
X177871D03*
X181994Y453932D03*
X180640Y447172D03*
X185211Y453942D03*
X185191Y502439D03*
X187490Y568752D03*
X186793Y575189D03*
X184193D03*
X186793Y572689D03*
X184193D03*
X181593Y575189D03*
X178993D03*
X181593Y572689D03*
X178993D03*
X189293Y575189D03*
X186793Y577790D03*
X184193D03*
X189293D03*
X181593D03*
X178993D03*
X181651Y596883D03*
X179151D03*
X186796Y594195D03*
Y596915D03*
X184151Y596883D03*
X179151Y594163D03*
X181651D03*
X184151D03*
X181651Y599603D03*
X179151D03*
X186796Y599635D03*
X184151Y599603D03*
X190977Y669718D03*
X190800Y675662D03*
X191976Y684326D03*
X189800Y705062D03*
X186720Y737862D03*
X180720D03*
X183720D03*
Y734862D03*
X180720D03*
X186720D03*
X185835Y757057D03*
X188978Y756855D03*
X191602Y756839D03*
X189377Y1333783D03*
X191977D03*
X189377Y1336383D03*
X191977D03*
X191947Y1339263D03*
X189347D03*
X189377Y1349383D03*
X191977D03*
X189377Y1346883D03*
X191977D03*
Y1344383D03*
X189377D03*
X191977Y1341883D03*
X189377D03*
X184215Y1361072D03*
X181403Y1361115D03*
X192620Y1360797D03*
X188233Y1387027D03*
Y1379227D03*
Y1381827D03*
Y1384427D03*
X183283Y1387987D03*
X185633Y1387027D03*
X180672Y1387987D03*
X185633Y1379227D03*
X180672Y1380187D03*
X183283D03*
X177532Y1378797D03*
X185633Y1384427D03*
Y1381827D03*
X180672Y1382787D03*
Y1385387D03*
X183283Y1382787D03*
Y1385387D03*
X177421Y1383997D03*
X177532Y1381397D03*
X182653Y1404535D03*
X187711Y1395170D03*
Y1397670D03*
X180977Y1396173D03*
X178458Y1399269D03*
Y1402169D03*
Y1405069D03*
X192767Y1413725D03*
X185643Y1413945D03*
X188211Y1406691D03*
X186165Y1422589D03*
X183135Y1419784D03*
X180510Y1420258D03*
X177510D03*
X186135Y1419784D03*
X183165Y1422589D03*
X177510Y1423278D03*
X180510D03*
X183075Y1430424D03*
Y1425424D03*
Y1427924D03*
X186075Y1430424D03*
Y1425424D03*
Y1427924D03*
X183075Y1432924D03*
X186075D03*
X185895Y1535462D03*
Y1539723D03*
Y1544029D03*
Y1548487D03*
Y1552875D03*
X192600Y1557360D03*
X185895Y1557875D03*
X189600Y1566300D03*
X187400Y1568132D03*
X188897Y1578182D03*
X192297D03*
X176793Y1585173D03*
X188119Y1580678D03*
Y1575686D03*
X188897Y1578182D03*
X192297D03*
Y1590094D03*
X188897D03*
X194197Y1602380D03*
X188119Y1592590D03*
Y1587598D03*
X188897Y1590094D03*
X192297D03*
X194197Y1614292D03*
X192529Y1728947D03*
X183822Y1720517D03*
X187542Y1729092D03*
X192895Y1737108D03*
X209058Y3010D03*
X207894Y19538D03*
X204494D03*
X203716Y17042D03*
Y22034D03*
X208672Y17042D03*
Y22034D03*
X201716Y19538D03*
X207894D03*
X204494D03*
X197389Y26474D03*
X200789D03*
X201567Y23978D03*
X196611D03*
X194611Y25974D03*
X203567D03*
X208784D03*
X202626Y28406D03*
Y37106D03*
X195539Y28406D03*
Y37106D03*
X200789Y26474D03*
X197389D03*
X202626Y40020D03*
Y48720D03*
X195539Y40020D03*
Y48720D03*
X197761Y69340D03*
X200539D03*
X193583Y66844D03*
Y71836D03*
X198539Y66844D03*
Y71836D03*
X197761Y69340D03*
X194361D03*
X205495Y75340D03*
X208895D03*
X204717Y72844D03*
Y77836D03*
X202717Y75340D03*
X205495D03*
X208895D03*
X195050Y412055D03*
X199047Y428626D03*
X199139Y422882D03*
X199149Y425755D03*
Y420255D03*
Y414755D03*
X195050Y417465D03*
X199149Y436755D03*
Y442255D03*
Y431255D03*
X196215Y447565D03*
X199149Y453255D03*
Y447755D03*
X197650Y455712D03*
X199149Y468255D03*
X208200Y493510D03*
X208312Y576125D03*
X196526Y567825D03*
X202338Y568746D03*
X201392Y574271D03*
X198336D03*
X195888Y581071D03*
X194515Y583433D03*
X208312Y581085D03*
Y578605D03*
X199164Y582481D03*
X200654Y578271D03*
X201622Y581009D03*
X208056Y591665D03*
X208806Y589335D03*
X208056Y587005D03*
X208806Y584675D03*
X202262Y592305D03*
X205162D03*
X197423Y601496D03*
X194059Y604901D03*
X202338Y602746D03*
X201392Y608271D03*
X203892Y594471D03*
X202492Y596571D03*
X208292D03*
X206892Y594371D03*
X205392Y596571D03*
X195888Y615071D03*
X194515Y617433D03*
X208312Y615085D03*
Y610125D03*
Y612605D03*
X200654Y612271D03*
X201622Y615009D03*
X208806Y618675D03*
X208056Y621005D03*
X208806Y623335D03*
X194059Y638901D03*
X197423Y635496D03*
X202338Y636746D03*
X208056Y625665D03*
X203892Y628471D03*
X202492Y630571D03*
X202262Y626305D03*
X208292Y630571D03*
X206892Y628371D03*
X205162Y626305D03*
X205392Y630571D03*
X194515Y651433D03*
X195888Y649071D03*
X208312Y649085D03*
Y644125D03*
Y646605D03*
X201392Y642271D03*
X199164Y650481D03*
X201622Y649009D03*
X198336Y642271D03*
X208056Y655005D03*
X208806Y657335D03*
Y652675D03*
X205320Y667562D03*
X207620Y671262D03*
X198420Y672662D03*
X198495Y669487D03*
X208056Y659665D03*
X205392Y664571D03*
X205162Y660305D03*
X206892Y662371D03*
X202262Y660305D03*
X202492Y664571D03*
X203892Y662471D03*
X208292Y664571D03*
X194858Y684348D03*
X207856Y686443D03*
X203043Y686483D03*
X207824Y681560D03*
X203044Y684036D03*
X207834Y684006D03*
X203237Y681549D03*
X196049Y678195D03*
X194196Y687061D03*
X193332Y678195D03*
X207129Y690027D03*
X203199Y690006D03*
X197086Y686326D03*
X203179Y693626D03*
X207140Y693636D03*
X195735Y696469D03*
X198235Y698969D03*
Y696469D03*
X200735Y698969D03*
Y696469D03*
X207140Y738462D03*
X205220Y736562D03*
X201220Y736662D03*
X203660Y731802D03*
X199720Y732862D03*
X206720Y731862D03*
X199220Y739362D03*
X207602Y756855D03*
X199602D03*
X195602Y756839D03*
X203602Y756855D03*
X208977Y1336383D03*
Y1333783D03*
X194577D03*
Y1336383D03*
X209007Y1339263D03*
X194547D03*
X208977Y1341883D03*
X194577Y1349383D03*
Y1346883D03*
Y1344383D03*
X208977D03*
Y1346883D03*
Y1349383D03*
X194577Y1341883D03*
X203441Y1360790D03*
X198041D03*
X200941D03*
X201661Y1384286D03*
X193861D03*
X196461D03*
X199061D03*
X201661Y1387393D03*
X193861D03*
X196461D03*
X199061D03*
X204261Y1384286D03*
X207461D03*
X201861Y1390500D03*
X199261D03*
X195874Y1399732D03*
X198344D03*
X200774D03*
X195874Y1394132D03*
X198344D03*
X200774D03*
X206735Y1400005D03*
X209065Y1399255D03*
X204405D03*
X201071Y1412173D03*
X198001Y1409361D03*
X193941Y1407029D03*
X200797Y1409605D03*
X200492Y1406686D03*
X193941Y1409750D03*
X195966Y1542863D03*
X204357Y1578182D03*
X200957D03*
X193075Y1580678D03*
Y1575686D03*
X200179D03*
X205135D03*
X200179Y1580678D03*
X205135D03*
X200957Y1578182D03*
X204357D03*
X200957Y1590094D03*
X204357D03*
X197597Y1602380D03*
X206257D03*
X209657D03*
X193075Y1592590D03*
Y1587598D03*
X200179Y1592590D03*
X205135D03*
X200179Y1587598D03*
X205135D03*
X198375Y1599884D03*
X193419D03*
X205479D03*
X200957Y1590094D03*
X204357D03*
X197597Y1614292D03*
X206257D03*
X209657D03*
X193419Y1616788D03*
Y1611796D03*
X198375D03*
X193419Y1604876D03*
X198375D03*
Y1616788D03*
X205479Y1611796D03*
Y1604876D03*
Y1616788D03*
X194197Y1614292D03*
X197597D03*
X206257D03*
X194197Y1602380D03*
X197597D03*
X206257D03*
X207229Y1631181D03*
X193410Y1711606D03*
X205582Y1700867D03*
X196443Y1722197D03*
X204600Y1733022D03*
X222067Y19538D03*
X218667D03*
X217889Y17042D03*
Y22034D03*
X222845Y17042D03*
Y22034D03*
X210672Y19538D03*
X215889D03*
X224845D03*
X222067D03*
X218667D03*
X214962Y26474D03*
X211562D03*
X215740Y23978D03*
X210784D03*
X217740Y25974D03*
X223886Y28406D03*
Y37106D03*
X216799Y28406D03*
Y37106D03*
X209713Y28406D03*
Y37106D03*
X214962Y26474D03*
X211562D03*
X223886Y40020D03*
Y48720D03*
X216799Y40020D03*
Y48720D03*
X209713Y40020D03*
Y48720D03*
X219895Y69340D03*
X216495D03*
X215717Y66844D03*
Y71836D03*
X220673Y66844D03*
Y71836D03*
X213717Y69340D03*
X222673D03*
X219895D03*
X216495D03*
X227495Y75340D03*
X209673Y72844D03*
Y77836D03*
X211673Y75340D03*
X224717D03*
X225407Y321831D03*
X223330Y426467D03*
X220843Y430004D03*
X209530Y426192D03*
X217770Y428262D03*
X220874Y442079D03*
X209579Y457222D03*
Y462235D03*
X213912Y576125D03*
X220668Y574131D03*
X223775D03*
X224064Y568113D03*
X221464D03*
X210391Y567981D03*
X213912Y578605D03*
Y581085D03*
X217556Y590575D03*
X217561Y582131D03*
Y579531D03*
X223775Y587731D03*
X223759Y590675D03*
X220652D03*
X223775Y584531D03*
X220668Y576731D03*
Y579331D03*
X223775Y581931D03*
Y579331D03*
Y576731D03*
X220668Y581931D03*
Y608131D03*
X223775D03*
X224064Y602113D03*
X221464D03*
X223403Y596820D03*
Y594220D03*
X212891Y601981D03*
X210391D03*
X213912Y612605D03*
Y615085D03*
Y610125D03*
X217561Y616131D03*
Y613531D03*
X217556Y624575D03*
X223759Y624675D03*
X220652D03*
X223775Y618531D03*
X220668Y610731D03*
Y613331D03*
X223775Y615931D03*
Y613331D03*
Y610731D03*
X220668Y615931D03*
X223775Y621731D03*
X223403Y630820D03*
Y628220D03*
X224064Y636113D03*
X221464D03*
X210391Y635981D03*
X212891D03*
X213912Y646605D03*
Y649085D03*
Y644125D03*
X217561Y650131D03*
Y647531D03*
X223775Y655731D03*
Y652531D03*
X220668Y644731D03*
Y647331D03*
Y642131D03*
X223775Y649931D03*
Y647331D03*
Y644731D03*
Y642131D03*
X220668Y649931D03*
X217556Y658575D03*
X223403Y664820D03*
X223759Y658675D03*
X220652D03*
X217510Y668712D03*
X225167Y672006D03*
X222567D03*
X219967D03*
X217367D03*
X210320Y671262D03*
X211348Y688087D03*
Y685287D03*
X214100Y687376D03*
Y690376D03*
Y684376D03*
Y681376D03*
Y678376D03*
X211348Y690787D03*
Y693587D03*
X214100Y693576D03*
X224506Y698138D03*
Y700738D03*
X221906Y698138D03*
Y700738D03*
X219306D03*
Y698138D03*
X224900Y713293D03*
X209720Y731862D03*
X211220Y740362D03*
X220033Y756844D03*
X211602Y756855D03*
X216842Y756865D03*
X214177Y1336383D03*
X211577D03*
X214177Y1333783D03*
X211577D03*
X214207Y1339263D03*
X211607D03*
X214177Y1341883D03*
X211577D03*
X214177Y1349383D03*
Y1346883D03*
Y1344383D03*
X211577D03*
Y1346883D03*
Y1349383D03*
X215824Y1361199D03*
X211350Y1360797D03*
X218960Y1388312D03*
X210405Y1384302D03*
Y1387409D03*
X213075Y1381558D03*
X217133Y1384055D03*
X214425Y1384058D03*
X215675Y1381558D03*
X218175D03*
X213075Y1378958D03*
X215675D03*
X218175D03*
X219752Y1405499D03*
Y1401999D03*
Y1398599D03*
X210374Y1390532D03*
X211395Y1400005D03*
X214201Y1404169D03*
X212035Y1402899D03*
X214101Y1401169D03*
X216554Y1399264D03*
Y1402164D03*
Y1405064D03*
X212035Y1405799D03*
X224137Y1414345D03*
X224077Y1416975D03*
X224350Y1432032D03*
X219587Y1435402D03*
X217469Y1454725D03*
X219587Y1443402D03*
Y1439402D03*
X220869Y1454725D03*
X213017Y1578182D03*
X216417D03*
X225077D03*
X212239Y1580678D03*
X217195D03*
Y1575686D03*
X212239D03*
X224299D03*
Y1580678D03*
X225077Y1578182D03*
X213017D03*
X216417D03*
X225077Y1590094D03*
X216417D03*
X213017D03*
X218317Y1602380D03*
X221717D03*
X212239Y1587598D03*
X217195D03*
X212239Y1592590D03*
X217195D03*
X224299Y1587598D03*
Y1592590D03*
X210435Y1599884D03*
X222495D03*
X217539D03*
X225077Y1590094D03*
X213017D03*
X216417D03*
X221717Y1614292D03*
X218317D03*
X210435Y1611796D03*
Y1604876D03*
Y1616788D03*
X222495D03*
X217539D03*
X222495Y1604876D03*
Y1611796D03*
X217539Y1604876D03*
Y1611796D03*
X209657Y1614292D03*
X218317D03*
X221717D03*
X209657Y1602380D03*
X218317D03*
X221717D03*
X209820Y1631142D03*
X210593Y1714017D03*
X212120Y1703062D03*
X212684Y1720307D03*
X212895Y1737108D03*
X229058Y3010D03*
X233339Y17662D03*
X238063Y37162D03*
X230972Y28406D03*
Y37106D03*
X229135Y26474D03*
X225735D03*
X235701Y39570D03*
X230972Y48720D03*
Y40020D03*
X229131Y50646D03*
X225731D03*
X230895Y75340D03*
X226717Y72844D03*
Y77836D03*
X231673Y72844D03*
Y77836D03*
X233673Y75340D03*
X227495D03*
X230895D03*
X238297Y129703D03*
X233800Y162692D03*
X237539Y174266D03*
X234902Y174047D03*
X226800Y359464D03*
X228550Y420412D03*
X231864Y568113D03*
X229264D03*
X226664D03*
X238393Y570490D03*
X240993D03*
X229264Y602113D03*
X226664D03*
X226003Y594220D03*
Y596820D03*
X228603Y594220D03*
Y596820D03*
X231864Y602113D03*
X233803Y594220D03*
Y596820D03*
X231203Y594220D03*
Y596820D03*
X238393Y604490D03*
X240993D03*
Y596820D03*
X238393D03*
X240993Y594220D03*
X238393D03*
X226003Y628220D03*
Y630820D03*
X228603Y628220D03*
Y630820D03*
X231864Y636113D03*
X233803Y628220D03*
Y630820D03*
X231203Y628220D03*
Y630820D03*
X229264Y636113D03*
X226664D03*
X238393Y638490D03*
X240993D03*
Y630820D03*
X238393D03*
X240993Y628220D03*
X238393D03*
X228603Y664820D03*
X233803D03*
X231203D03*
X226003D03*
X230367Y672006D03*
X227767D03*
X227106Y698138D03*
Y700738D03*
X227430Y719772D03*
X238940Y716652D03*
X230864Y1254295D03*
X228477Y1578182D03*
X240537D03*
X237137D03*
X229255Y1575686D03*
Y1580678D03*
X236359D03*
Y1575686D03*
X241315Y1580678D03*
Y1575686D03*
X237137Y1578182D03*
X240537D03*
X228477D03*
X240537Y1590094D03*
X228477D03*
X237137D03*
X233777Y1602380D03*
X230377D03*
X242437D03*
X229255Y1587598D03*
Y1592590D03*
X236359D03*
Y1587598D03*
X241315Y1592590D03*
Y1587598D03*
X229599Y1599884D03*
X234555D03*
X237137Y1590094D03*
X240537D03*
X228477D03*
X233777Y1614292D03*
X230377D03*
X242437D03*
X229599Y1604876D03*
Y1611796D03*
X234555Y1604876D03*
Y1611796D03*
X229599Y1616788D03*
X234555D03*
X230377Y1614292D03*
X233777D03*
X230377Y1602380D03*
X233777D03*
X249058Y3010D03*
X243490Y23002D03*
X253000Y28362D03*
X256500D03*
X249500D03*
X242220Y39362D03*
X246220D03*
X250220D03*
X254050Y39422D03*
X248820Y48962D03*
X252320D03*
X255820D03*
X257520Y51562D03*
X254020D03*
X250520D03*
X247720Y71862D03*
X244300Y59762D03*
X247720Y75862D03*
X251797Y100843D03*
X248097Y92143D03*
X247897Y100543D03*
X244822Y115543D03*
Y111543D03*
X253878Y111771D03*
X252195Y144320D03*
X243892Y140912D03*
X242255Y162512D03*
X257256Y156727D03*
X252000Y395400D03*
X257434Y415896D03*
X256695Y461117D03*
X249300Y510362D03*
X253800Y515362D03*
X249860Y518222D03*
X254713Y518465D03*
X245700Y513262D03*
X250100Y521783D03*
X246400Y563162D03*
X256885Y574805D03*
X254385D03*
X256855Y571995D03*
X251885Y574805D03*
X249800Y563262D03*
X254355Y589235D03*
X256855D03*
X251855D03*
X256855Y605995D03*
X251885Y608805D03*
X257643Y594220D03*
X255043D03*
Y596820D03*
X257643D03*
X256885Y608805D03*
X254385D03*
X256855Y603495D03*
X251855Y623265D03*
X254355D03*
X256855D03*
Y639995D03*
Y637495D03*
X257643Y628220D03*
X255043D03*
Y630820D03*
X257643D03*
X256885Y642805D03*
X254385D03*
X251855Y657265D03*
X251885Y642805D03*
X254355Y657265D03*
X256855D03*
X257643Y662220D03*
X255043D03*
Y664820D03*
X257643D03*
X253819Y675567D03*
X253849Y678077D03*
X256419Y675567D03*
X256449Y678077D03*
X251219Y675567D03*
X251249Y678077D03*
X248649D03*
X248989Y698827D03*
X249019Y693767D03*
X251589Y698827D03*
X251649Y696277D03*
X254189Y698827D03*
X251619Y693767D03*
X256849Y696277D03*
X256789Y698827D03*
X256819Y693767D03*
X254249Y696277D03*
X254219Y693767D03*
X248300Y703862D03*
X242460Y716652D03*
X253057Y755345D03*
X245487Y755435D03*
X251187Y1255025D03*
X252597Y1578182D03*
X249197D03*
X248419Y1575686D03*
X253375D03*
X248419Y1580678D03*
X253375D03*
X249197Y1578182D03*
X252597D03*
Y1590094D03*
X249197D03*
X245837Y1602380D03*
X254497D03*
X257897D03*
X248419Y1587598D03*
X253375D03*
X248419Y1592590D03*
X253375D03*
X246615Y1599884D03*
X241659D03*
X253719D03*
X249197Y1590094D03*
X252597D03*
X245837Y1614292D03*
X254497D03*
X257897D03*
X241659Y1616788D03*
X246615D03*
Y1604876D03*
X241659D03*
X246615Y1611796D03*
X241659D03*
X253719Y1604876D03*
Y1611796D03*
Y1616788D03*
X242437Y1614292D03*
X254497D03*
X245837D03*
X242437Y1602380D03*
X254497D03*
X245837D03*
X252895Y1737108D03*
X269058Y3010D03*
X260000Y28362D03*
X263280Y35312D03*
X272600Y27182D03*
X271600Y40162D03*
X259320Y48962D03*
X261020Y51562D03*
X263520D03*
X261820Y48962D03*
X264740Y49182D03*
X266497Y69536D03*
Y72036D03*
X264720Y56362D03*
Y60362D03*
Y64362D03*
X266597Y77526D03*
Y80026D03*
X261420Y100662D03*
X264920D03*
X268420D03*
X262920Y97962D03*
X266420D03*
X269920D03*
X272361Y120243D03*
X270364Y118415D03*
X272529Y111053D03*
X265442D03*
X261899D03*
Y108553D03*
X265442D03*
X268985Y111053D03*
Y108553D03*
X272529D03*
X261387Y133783D03*
X258257D03*
X266975Y140107D03*
X272800Y140162D03*
X264578Y151203D03*
Y155203D03*
X260100Y159562D03*
X260700Y218662D03*
X268940Y217982D03*
X263580Y218627D03*
X270745Y207562D03*
X265500Y227862D03*
X263000D03*
X260500Y227362D03*
Y224862D03*
X265343Y244460D03*
X270240Y245332D03*
X271821Y251962D03*
X267759D03*
X258746Y407842D03*
X260807Y424403D03*
X259224Y419532D03*
X272029Y443735D03*
X259869Y431039D03*
X264055Y574505D03*
X264025Y571995D03*
X261555Y574505D03*
X261525Y571995D03*
X264055Y566935D03*
X263995Y569485D03*
X261495D03*
X261555Y566935D03*
X266555Y574505D03*
X266525Y571995D03*
X266495Y569485D03*
X266555Y566935D03*
X269055Y574505D03*
X269025Y571995D03*
X268995Y569485D03*
X269055Y566935D03*
X261465Y592115D03*
X261525Y589565D03*
X264025D03*
X263965Y592115D03*
X266525Y589565D03*
X266465Y592115D03*
X269025Y589565D03*
X268965Y592115D03*
X264025Y605995D03*
X261525D03*
X264055Y608505D03*
X261555D03*
X261435Y597175D03*
X261495Y594625D03*
X263995D03*
X263935Y597175D03*
X266525Y605995D03*
X266555Y608505D03*
X266435Y597175D03*
X266495Y594625D03*
X261525Y603495D03*
X264025D03*
X266525D03*
X269025Y605995D03*
X269055Y608505D03*
X268935Y597175D03*
X268995Y594625D03*
X269025Y603495D03*
X261495Y621055D03*
X263995D03*
X261525Y623565D03*
X264025D03*
X263995Y611055D03*
X261495D03*
X266495Y621055D03*
X266525Y623565D03*
X266495Y611055D03*
X268995Y621055D03*
X269025Y623565D03*
X268995Y611055D03*
X261525Y639995D03*
X264025D03*
X261525Y637495D03*
X266525Y639995D03*
X269025D03*
X264025Y637495D03*
X266525D03*
X269025D03*
X263965Y626115D03*
X261465D03*
X266465D03*
X268965D03*
X261495Y655055D03*
X263995D03*
X261525Y657565D03*
X264025D03*
X263995Y645055D03*
X264055Y642505D03*
X261495Y645055D03*
X261555Y642505D03*
X266495Y655055D03*
X266525Y657565D03*
X266495Y645055D03*
X266555Y642505D03*
X268995Y655055D03*
X269025Y657565D03*
X268995Y645055D03*
X269055Y642505D03*
X261465Y660115D03*
X263965D03*
X266465D03*
X268965D03*
X259049Y678077D03*
X259019Y675567D03*
X259419Y693767D03*
X259389Y698827D03*
X259449Y696277D03*
X269600Y715792D03*
X274247Y727165D03*
X273046Y735662D03*
X270100Y727262D03*
X264000Y726262D03*
X266700Y730962D03*
X270322Y740207D03*
X274270Y746602D03*
X271570Y746422D03*
X265997Y747535D03*
X271057Y765525D03*
X261257Y1578182D03*
X264657D03*
X273317D03*
X260479Y1580678D03*
X265435D03*
X260479Y1575592D03*
X265435D03*
X272539Y1575686D03*
Y1580678D03*
X273317Y1578182D03*
X261257D03*
X264657D03*
X273317Y1590094D03*
X264657D03*
X261257D03*
X269957Y1602380D03*
X266557D03*
X260479Y1592590D03*
X265435D03*
X260479Y1587598D03*
X265435D03*
X272539D03*
Y1592590D03*
X258675Y1599884D03*
X270735Y1599790D03*
X265779D03*
X273317Y1590094D03*
X261257D03*
X264657D03*
X269957Y1614292D03*
X266557D03*
X258675Y1604876D03*
Y1611796D03*
Y1616788D03*
X270735D03*
X265779D03*
X270735Y1611796D03*
Y1604876D03*
X265779D03*
Y1611796D03*
X266557Y1614292D03*
X257897D03*
X269957D03*
X266557Y1602380D03*
X257897D03*
X269957D03*
X272895Y1737108D03*
X289058Y3010D03*
X285900Y23962D03*
X286071Y28406D03*
X278984D03*
X284233Y26474D03*
X280833D03*
X287952Y39984D03*
X286071Y48720D03*
X286500Y52462D03*
X278984Y48720D03*
X284230Y50646D03*
X280830D03*
X287800Y60062D03*
X279277Y99183D03*
X285357Y105003D03*
X288557D03*
X280857Y107303D03*
X285857Y115603D03*
X282857D03*
X280857Y109903D03*
X289557Y121803D03*
X275797Y129592D03*
X283953Y152503D03*
X280687Y140746D03*
X283053Y139728D03*
X288520Y157062D03*
X282640Y214102D03*
X279740Y205962D03*
X276890Y249022D03*
X289920Y248652D03*
X286920D03*
X282420D03*
X286481Y251962D03*
X281077D03*
X276491D03*
X289274Y290662D03*
X284515D03*
X276500Y444862D03*
X274850Y442562D03*
X279500Y455362D03*
X277578Y509039D03*
X284482Y569548D03*
Y566022D03*
X286582Y630757D03*
Y637809D03*
Y634283D03*
X287819Y691097D03*
X284287Y716015D03*
X277046Y725709D03*
X284358Y732562D03*
X287820Y727962D03*
X278520Y738072D03*
X279507Y727025D03*
X281046Y737938D03*
X275210Y738102D03*
X290077Y739735D03*
X287607Y754962D03*
X277046Y746702D03*
X281046D03*
X285046D03*
X289047Y760245D03*
X276717Y1578182D03*
X285377D03*
X288777D03*
X277495Y1575686D03*
Y1580678D03*
X284599D03*
X289555D03*
Y1575686D03*
X284599D03*
X285377Y1578182D03*
X288777D03*
X276717D03*
X288777Y1590094D03*
X276717D03*
X285377D03*
X278617Y1602380D03*
X282017D03*
X290677D03*
X277495Y1587598D03*
Y1592590D03*
X284599D03*
X289555D03*
X284599Y1587598D03*
X289555D03*
X282795Y1599884D03*
X277839D03*
X289899D03*
X285377Y1590094D03*
X288777D03*
X276717D03*
X278617Y1614292D03*
X282017D03*
X290677D03*
X282795Y1604876D03*
Y1611796D03*
X277839D03*
Y1604876D03*
X282795Y1616788D03*
X277839D03*
X289899D03*
Y1604876D03*
Y1611796D03*
X278617Y1614292D03*
X282017D03*
X278617Y1602380D03*
X282017D03*
X291520Y12762D03*
X291660Y21642D03*
X295520Y12762D03*
X302610Y26362D03*
X292060Y24472D03*
X304927Y24654D03*
X304972Y28362D03*
X298720Y40017D03*
X306720Y39982D03*
X292590Y53982D03*
X306570Y50222D03*
X290720Y40017D03*
X294720D03*
X295524Y52092D03*
X301310Y52482D03*
X292942Y67513D03*
Y71499D03*
X305747Y64013D03*
Y61113D03*
X293447Y78573D03*
X293452Y82483D03*
Y85983D03*
X303047Y79373D03*
X299947Y79273D03*
X299657Y92503D03*
X301183Y107103D03*
Y110003D03*
Y112803D03*
X301751Y127466D03*
Y124466D03*
Y121466D03*
X302891Y141811D03*
X296478Y149203D03*
X296800Y139762D03*
X294553Y153819D03*
X306000Y165662D03*
X296478Y158703D03*
X306730Y173842D03*
X304651Y251962D03*
X291759D03*
X306736Y290662D03*
X302765D03*
X298184D03*
X293763D03*
X298587Y508074D03*
X306087Y569718D03*
X293805Y569397D03*
X305612Y622530D03*
Y625030D03*
X294658Y637809D03*
X305612Y627530D03*
X296405Y630732D03*
Y634132D03*
X295962Y679374D03*
X294679Y688446D03*
X291600Y705162D03*
X298273Y715400D03*
X297087Y721249D03*
X304602Y727968D03*
X290680Y745312D03*
X299427Y768265D03*
X303647Y1307981D03*
X303831Y1318566D03*
X303807Y1342225D03*
X303831Y1344866D03*
X303723Y1353316D03*
Y1355853D03*
X304047Y1368565D03*
X304051Y1365453D03*
X302805Y1379941D03*
Y1376541D03*
X297437Y1578182D03*
X300837D03*
X296659Y1575686D03*
X301615D03*
X296659Y1580678D03*
X301615D03*
X297437Y1578182D03*
X300837D03*
X297437Y1590094D03*
X300837D03*
X294077Y1602380D03*
X302737D03*
X306137D03*
X296659Y1587598D03*
X301615D03*
X296659Y1592590D03*
X301615D03*
X294855Y1599884D03*
X301959D03*
X297437Y1590094D03*
X300837D03*
X294077Y1614292D03*
X302737D03*
X306137D03*
X294855Y1616788D03*
Y1604876D03*
Y1611796D03*
X301959Y1604876D03*
Y1611796D03*
Y1616788D03*
X290677Y1614292D03*
X302737D03*
X294077D03*
X306137D03*
X290677Y1602380D03*
X302737D03*
X294077D03*
X306137D03*
X296170Y1622852D03*
X292895Y1737108D03*
X309058Y3010D03*
X318651Y22921D03*
X314657Y71803D03*
Y68903D03*
X320057Y85803D03*
X323117Y81168D03*
Y76938D03*
X320057Y88803D03*
X313357Y89503D03*
X313457Y96803D03*
X311057Y107103D03*
Y110003D03*
Y112803D03*
X311758Y124469D03*
Y121469D03*
Y127469D03*
X308175Y144202D03*
X320825Y159062D03*
X308500Y165662D03*
X311200Y165562D03*
X309230Y173842D03*
X309756Y181449D03*
X310970Y195362D03*
X308790Y197622D03*
X319370Y214492D03*
X316370D03*
X319370Y217492D03*
X316370D03*
X306910Y228162D03*
X309910D03*
X306910Y225162D03*
X309910D03*
X313995Y237724D03*
X317981D03*
X320940Y238372D03*
X317129Y251962D03*
X316463Y290662D03*
X314200Y585282D03*
X316080Y578262D03*
X320691Y602448D03*
X321276Y599298D03*
X308605Y629525D03*
Y627025D03*
X319557Y736225D03*
X317967Y746985D03*
X316397Y776125D03*
X320578Y1290197D03*
X323028Y1297967D03*
X320428D03*
Y1295467D03*
X323028D03*
Y1292967D03*
X320428D03*
X321119Y1313108D03*
X317119D03*
X313119D03*
X312301Y1345539D03*
Y1342432D03*
X309701Y1345539D03*
Y1342432D03*
X316655Y1352295D03*
X314175D03*
X311695D03*
X320101Y1342432D03*
X317701Y1348646D03*
X315101D03*
X314901Y1345539D03*
X317501D03*
X314901Y1342432D03*
X317501D03*
X320245Y1357401D03*
X316655Y1357895D03*
X311695D03*
X314175D03*
X317979Y1371248D03*
X315221Y1372445D03*
X313841Y1365553D03*
X309841Y1364815D03*
X318051Y1367043D03*
X316579Y1364585D03*
X309841Y1367871D03*
X322575Y1358151D03*
X309497Y1578182D03*
X312897D03*
X321557D03*
X324957D03*
X308719Y1580678D03*
X313675D03*
X308719Y1575686D03*
X313675D03*
X320779D03*
Y1580678D03*
X321557Y1578182D03*
X309497D03*
X312897D03*
X321557Y1590094D03*
X324957D03*
X309497D03*
X312897D03*
X318197Y1602380D03*
X314797D03*
X308719Y1592590D03*
X313675D03*
X308719Y1587598D03*
X313675D03*
X320779D03*
Y1592590D03*
X306915Y1599884D03*
X318975D03*
X314019D03*
X321557Y1590094D03*
X309497D03*
X312897D03*
X318197Y1614292D03*
X314797D03*
X306915Y1604876D03*
Y1611796D03*
Y1616788D03*
X318975D03*
X314019D03*
X318975Y1604876D03*
Y1611796D03*
X314019Y1604876D03*
Y1611796D03*
X314797Y1614292D03*
X318197D03*
X314797Y1602380D03*
X318197D03*
X329535Y49388D03*
X336240Y150738D03*
X332500D03*
X326216Y138787D03*
X326900Y162287D03*
X335285Y210609D03*
X332285D03*
X323420Y207549D03*
X326168Y207580D03*
X334485Y216809D03*
X337000Y216862D03*
X325755Y230719D03*
X338985Y229509D03*
X325855Y227619D03*
X334500Y219362D03*
X337000D03*
X325055Y237219D03*
X328965Y237214D03*
X332465D03*
X329648Y252202D03*
X329002Y290662D03*
X330417Y380482D03*
X330674Y368261D03*
Y365702D03*
X328167Y379073D03*
X336370Y406302D03*
X331760Y705882D03*
X331339Y709313D03*
X328120Y710862D03*
X335677Y715215D03*
X327107Y732665D03*
X335467Y725335D03*
X338097Y736235D03*
X335126Y728323D03*
X327096Y736005D03*
X336446Y746486D03*
X339148Y1269717D03*
X339088Y1272287D03*
X339028Y1274887D03*
X325688Y1290167D03*
X325718Y1287587D03*
X328078Y1288747D03*
X323178Y1290197D03*
X323208Y1287617D03*
X328168Y1280967D03*
X325748Y1284987D03*
X328108Y1286147D03*
X328138Y1283567D03*
X328018Y1291317D03*
X339035Y1280218D03*
X339040Y1277594D03*
X328065Y1299248D03*
X325538Y1297937D03*
Y1292937D03*
Y1295437D03*
X328058Y1293917D03*
X328070Y1296624D03*
X325119Y1313108D03*
X328915Y1337104D03*
X331515D03*
X328915Y1331904D03*
X331515D03*
X328915Y1329304D03*
X331515D03*
X328915Y1334504D03*
X331515D03*
X328915Y1326704D03*
X331515D03*
X328915Y1339704D03*
X335679Y1330518D03*
X334973Y1333353D03*
X338795Y1338799D03*
X326145Y1348651D03*
X326245Y1345555D03*
Y1342448D03*
X323301Y1342432D03*
X338917Y1349488D03*
X336347Y1348353D03*
X336179Y1342753D03*
X324905Y1357401D03*
X327235Y1358151D03*
X332475Y1357945D03*
X327875Y1363945D03*
Y1361045D03*
X330041Y1362315D03*
X329941Y1359315D03*
X332475Y1363345D03*
Y1360445D03*
X333617Y1578182D03*
X337017D03*
X325735Y1575686D03*
Y1580678D03*
X332839D03*
X337795D03*
X332839Y1575686D03*
X337795D03*
X333617Y1578182D03*
X337017D03*
X324957D03*
X337017Y1590094D03*
X333617D03*
X330257Y1602380D03*
X326857D03*
X338917D03*
X325735Y1587598D03*
Y1592590D03*
X332839D03*
X337795D03*
X332839Y1587598D03*
X337795D03*
X326079Y1599884D03*
X331035D03*
X338139D03*
X333617Y1590094D03*
X337017D03*
X324957D03*
X330257Y1614292D03*
X326857D03*
X338917D03*
X326079Y1604876D03*
Y1611796D03*
X331035Y1604876D03*
Y1611796D03*
X326079Y1616788D03*
X331035D03*
X338139D03*
Y1604876D03*
Y1611796D03*
X330257Y1614292D03*
X338917D03*
X326857D03*
X330257Y1602380D03*
X338917D03*
X326857D03*
X332895Y1737108D03*
X349535Y49388D03*
X340440Y120552D03*
X344776Y148462D03*
X342700Y139662D03*
X348100Y185162D03*
X345869Y192716D03*
X345600Y188162D03*
X353145Y219362D03*
X342000Y252612D03*
X354672Y252693D03*
X345164Y314234D03*
X343411Y363143D03*
X345411Y364702D03*
X343411Y375364D03*
X345411Y376923D03*
X343354Y387988D03*
X343720Y400628D03*
X347340Y407462D03*
X348880Y703442D03*
X349187Y715485D03*
X352879Y728657D03*
X348037Y728735D03*
X348730Y731698D03*
X344446Y739434D03*
X348000Y755362D03*
X344264Y1272455D03*
X341754Y1272485D03*
X344252Y1269948D03*
X341742Y1269978D03*
X344258Y1267117D03*
X341748Y1267147D03*
X341754Y1274985D03*
X344264Y1274955D03*
X355036Y1272433D03*
Y1269933D03*
X355378Y1262027D03*
X355318Y1264597D03*
X355258Y1267197D03*
X355036Y1274933D03*
X341605Y1280248D03*
X344115Y1280218D03*
X344264Y1277455D03*
X341754Y1277485D03*
X355048Y1277440D03*
X355025Y1280248D03*
X339769Y1299868D03*
X342769D03*
X344429Y1322741D03*
X347029D03*
X341829D03*
X347029Y1319634D03*
X344429D03*
X341829D03*
X349629Y1322741D03*
Y1319634D03*
X352229D03*
X355429D03*
X346303Y1335097D03*
X343823D03*
Y1329497D03*
X346303D03*
X347229Y1325848D03*
X348783Y1329497D03*
X349829Y1325848D03*
X348783Y1335097D03*
X352373Y1334603D03*
X354703Y1335353D03*
X348804Y1346877D03*
X350470Y1349030D03*
X345969Y1342755D03*
X341969Y1342017D03*
X350179Y1344245D03*
X348707Y1341787D03*
X341969Y1345073D03*
X354850Y1371908D03*
X351850D03*
X349260Y1373418D03*
X351850Y1375408D03*
X354850D03*
X351850Y1378408D03*
X354850D03*
X351850Y1381408D03*
X354850D03*
X349260Y1376918D03*
Y1379918D03*
X349636Y1399601D03*
X352713Y1399336D03*
X355513Y1402306D03*
X352513D03*
X349513D03*
X355325Y1405386D03*
X349463Y1405286D03*
X352463D03*
X355325Y1408386D03*
X346426Y1414401D03*
X352401Y1414432D03*
X355325Y1414386D03*
Y1417386D03*
X352401Y1411432D03*
X355325Y1411386D03*
X352401Y1408432D03*
X349123Y1411376D03*
X349323Y1408406D03*
X349073Y1414356D03*
X346256Y1417301D03*
X352231Y1417332D03*
X348903Y1417256D03*
X349077Y1578182D03*
X345677D03*
X344899Y1575686D03*
X349855D03*
X344899Y1580678D03*
X349855D03*
X345677Y1578182D03*
X349077D03*
Y1590094D03*
X345677D03*
X342317Y1602380D03*
X350977D03*
X354377D03*
X344899Y1587598D03*
X349855D03*
X344899Y1592590D03*
X349855D03*
X343095Y1599884D03*
X355155D03*
X350199D03*
X345677Y1590094D03*
X349077D03*
X342317Y1614292D03*
X350977D03*
X354377D03*
X343095Y1616788D03*
Y1604876D03*
Y1611796D03*
X355155Y1604876D03*
Y1611796D03*
X350199Y1604876D03*
Y1611796D03*
X355155Y1616788D03*
X350199D03*
X350977Y1614292D03*
X342317D03*
X354377D03*
X350977Y1602380D03*
X342317D03*
X354377D03*
X352895Y1737108D03*
X363625Y127662D03*
X361800Y122522D03*
X366060Y133912D03*
X363525Y158702D03*
X356250Y216342D03*
X358209Y208169D03*
X361190Y210762D03*
X357303Y213159D03*
X371551Y224862D03*
X367306Y252811D03*
X366498Y290264D03*
X357764Y314234D03*
X357660Y318850D03*
X363750Y369362D03*
X364014Y382304D03*
X364179Y394596D03*
Y392037D03*
X371066Y400628D03*
X369690Y431812D03*
X365970Y444662D03*
X365771Y449480D03*
X360470Y705965D03*
X363101Y697348D03*
X359930Y732985D03*
X358902Y736225D03*
X355946Y728800D03*
X359790Y729835D03*
X358902Y743035D03*
Y754945D03*
Y746405D03*
X360927Y757665D03*
X371578Y1248967D03*
X371458Y1254137D03*
X371330Y1256687D03*
X371518Y1251537D03*
X371278Y1259257D03*
X360198Y1269777D03*
X357546Y1272403D03*
Y1269903D03*
X360138Y1272347D03*
X357828Y1264567D03*
X357888Y1261997D03*
X360378Y1264627D03*
X360438Y1262057D03*
X357768Y1267167D03*
X360318Y1267227D03*
X357546Y1274903D03*
X360128Y1274957D03*
X371218Y1261857D03*
X371225Y1267188D03*
X371230Y1264564D03*
X357558Y1277410D03*
X357535Y1280218D03*
X360120Y1277654D03*
X361043Y1306506D03*
X361769Y1300008D03*
X363643Y1306506D03*
X364769Y1300008D03*
X367939Y1303319D03*
Y1305919D03*
Y1308519D03*
X358373Y1322757D03*
Y1319650D03*
X361043Y1314306D03*
Y1316906D03*
X362393Y1319406D03*
X361043Y1309106D03*
Y1311706D03*
X363643Y1316906D03*
Y1314306D03*
Y1309106D03*
Y1311706D03*
X367694Y1317092D03*
X367807Y1319592D03*
X358273Y1325853D03*
X370874Y1335876D03*
X367490Y1332568D03*
X368391Y1328161D03*
X370923Y1325373D03*
X357033Y1334603D03*
X359363Y1335353D03*
X362147Y1336553D03*
X360003Y1338247D03*
X364269Y1338017D03*
X364073Y1334903D03*
X360003Y1341147D03*
X362147Y1339653D03*
X364347Y1340853D03*
X364647Y1371990D03*
X361647D03*
X358647D03*
X367647D03*
X370552Y1372073D03*
X364647Y1375490D03*
X361647D03*
X358647D03*
Y1378490D03*
X370552Y1375573D03*
X367647Y1375490D03*
X355713Y1399336D03*
X361703Y1399386D03*
X364703D03*
X367703D03*
X370703D03*
X358703Y1402386D03*
X361703D03*
X364703D03*
X367703D03*
X370703D03*
X358713Y1399336D03*
X358573Y1405336D03*
X361573D03*
X364573D03*
X367573D03*
X370573D03*
X358703Y1414606D03*
X361703D03*
X364703D03*
X361703Y1417386D03*
X358703D03*
X364703D03*
X367703D03*
Y1414606D03*
X358217Y1411405D03*
X370517Y1414615D03*
X370717Y1417405D03*
X357917Y1408205D03*
X367948Y1531529D03*
X368600Y1543200D03*
X357737Y1578182D03*
X361137D03*
X369797D03*
X373197D03*
X356959Y1580678D03*
X361915D03*
X356959Y1575592D03*
X361915D03*
X369019Y1575686D03*
Y1580678D03*
X369797Y1578182D03*
X357737D03*
X361137D03*
X369797Y1590094D03*
X373197D03*
X357737D03*
X361137D03*
X363037Y1602380D03*
X366437D03*
X356959Y1592590D03*
X361915D03*
X356959Y1587598D03*
X361915D03*
X367215Y1599790D03*
X362259D03*
X369019Y1587598D03*
Y1592590D03*
X369797Y1590094D03*
X357737D03*
X361137D03*
X363037Y1614292D03*
X366437D03*
X367215Y1616788D03*
X362259D03*
X367215Y1604876D03*
Y1611796D03*
X362259Y1604876D03*
Y1611796D03*
X363037Y1614292D03*
X366437D03*
X363037Y1602380D03*
X366437D03*
X367140Y1645390D03*
X366700Y1649000D03*
X370500Y1654362D03*
X370635Y1675820D03*
X369300Y1680400D03*
Y1682900D03*
X383140Y119822D03*
X375330Y121182D03*
X374981Y131433D03*
X383160Y124322D03*
X383060Y128491D03*
X372530Y122972D03*
X373200Y126052D03*
X376245Y212862D03*
Y217362D03*
Y221362D03*
Y225362D03*
X386120Y220322D03*
X379860Y252162D03*
X379112Y290386D03*
X385720Y323761D03*
X376500Y362736D03*
X377136Y390307D03*
X383060Y403542D03*
X385520Y429262D03*
X373190Y438342D03*
X384510Y438662D03*
X379220Y436362D03*
X376220D03*
X382220D03*
X385730Y460922D03*
X382860Y471122D03*
X379220Y470962D03*
X371970Y683892D03*
X376638Y1248997D03*
X374088Y1248937D03*
X374028Y1251507D03*
X373823Y1256896D03*
X376333Y1256866D03*
X376518Y1254167D03*
X376578Y1251567D03*
X373968Y1254107D03*
X373835Y1259403D03*
X376345Y1259373D03*
X387478Y1248967D03*
X387358Y1254137D03*
X387117Y1256851D03*
X387418Y1251537D03*
X387117Y1259351D03*
X373835Y1261903D03*
Y1264403D03*
X376345Y1261873D03*
Y1264373D03*
X376285Y1267218D03*
X373735Y1267158D03*
X387117Y1261851D03*
X387129Y1264358D03*
X387125Y1267188D03*
X383239Y1286578D03*
X378069Y1286568D03*
X375069D03*
X386239Y1286578D03*
X373957Y1306208D03*
X381757D03*
X379157D03*
X376557D03*
X384357D03*
X387557D03*
X375951Y1321671D03*
X380911Y1316071D03*
X378431D03*
Y1321671D03*
X380911D03*
X373957Y1309315D03*
X381957Y1312422D03*
X381757Y1309315D03*
X379357Y1312422D03*
X379157Y1309315D03*
X376557D03*
X375951Y1316071D03*
X384501Y1321177D03*
X386831Y1321927D03*
X380842Y1334095D03*
X383549Y1333998D03*
X378097Y1329329D03*
X374097Y1328591D03*
X382307Y1330819D03*
X380835Y1328361D03*
X374097Y1331647D03*
X373552Y1372073D03*
X377025Y1371990D03*
X380025D03*
X373532Y1378598D03*
X373552Y1375573D03*
X380025Y1378490D03*
X377025D03*
X380025Y1375490D03*
X377025D03*
Y1381490D03*
X380025D03*
X383127Y1395610D03*
X376825Y1399386D03*
X379825D03*
X373703D03*
X379825Y1402386D03*
X376825D03*
X373703D03*
X376825Y1405386D03*
X379825D03*
X373573Y1405336D03*
X374027Y1411365D03*
X373703Y1414606D03*
X376825Y1414386D03*
X379825D03*
X376825Y1417386D03*
Y1411386D03*
X379825D03*
X373703Y1417386D03*
X376825Y1408386D03*
X379825D03*
X374307Y1408135D03*
X381060Y1433622D03*
X382489Y1428478D03*
X385667Y1433425D03*
X380930Y1531402D03*
X384210Y1534152D03*
X377830Y1534342D03*
X381120Y1534102D03*
X377720Y1539862D03*
X374720D03*
X374800Y1546400D03*
X385100Y1539700D03*
X381800Y1539600D03*
X381000Y1546500D03*
X384000D03*
X378000Y1546400D03*
X387152Y1582659D03*
X373975Y1575686D03*
Y1580678D03*
X373197Y1578182D03*
X387930Y1585155D03*
X375097Y1602380D03*
X378497D03*
X373975Y1587598D03*
Y1592590D03*
X379275Y1599884D03*
X374319D03*
X373197Y1590094D03*
X382220Y1591870D03*
X378497Y1614292D03*
X375097D03*
X379275Y1604876D03*
Y1611796D03*
X374319Y1604876D03*
Y1611796D03*
X379275Y1616788D03*
X374319D03*
X375097Y1614292D03*
X378497D03*
X375097Y1602380D03*
X378497D03*
X374690Y1631700D03*
X374391Y1648476D03*
X385123Y1639732D03*
X378547D03*
X375550Y1662052D03*
X380170Y1660002D03*
X372640Y1662112D03*
X380077Y1654049D03*
X381068Y1674824D03*
X386824Y1682866D03*
X387760Y1671092D03*
X372009Y1682584D03*
X373320Y1688202D03*
X376610Y1688252D03*
X372895Y1737108D03*
X393830Y62062D03*
X399800Y59662D03*
X403800D03*
X396380Y62742D03*
X402100Y62632D03*
X388735Y117322D03*
X395980Y148272D03*
X390830Y155833D03*
X388965Y215067D03*
Y209949D03*
X388720Y218362D03*
X394720Y206362D03*
X392616Y252162D03*
X392083Y290954D03*
X404215Y291140D03*
X398720Y318643D03*
Y321202D03*
X398661Y323761D03*
X403675Y363081D03*
X390876Y365640D03*
X391195Y368199D03*
X391101Y380939D03*
X403581Y375880D03*
X390843Y378439D03*
X403875Y365640D03*
X404120Y378439D03*
X390730Y394852D03*
X403570Y388874D03*
X404291Y391433D03*
X403700Y402422D03*
X390892Y406863D03*
X391149Y404304D03*
X403720Y405552D03*
X403260Y439352D03*
X391150Y445302D03*
X388720Y430862D03*
X403220Y436362D03*
X396570Y472602D03*
X400080Y472652D03*
X391360Y495712D03*
X402780Y499372D03*
X394860Y518812D03*
X403200Y572622D03*
X398796Y1161570D03*
Y1153070D03*
Y1170070D03*
X403738Y1249027D03*
X403618Y1254197D03*
X403498Y1256747D03*
X403678Y1251597D03*
X392538Y1248997D03*
X389928Y1251507D03*
X389988Y1248937D03*
X389868Y1254107D03*
X392298Y1256717D03*
X392418Y1254167D03*
X389627Y1256821D03*
X392478Y1251567D03*
X392238Y1259287D03*
X389627Y1259321D03*
X403438Y1259317D03*
X392220Y1264594D03*
X392228Y1261897D03*
X389627Y1261821D03*
X389639Y1264328D03*
X389635Y1267158D03*
X392185Y1267218D03*
X403385Y1267248D03*
X403378Y1261917D03*
X403390Y1264624D03*
X396139Y1286708D03*
X399139D03*
X395771Y1303480D03*
X393171D03*
X395771Y1300880D03*
X393171D03*
X395771Y1295680D03*
X393171D03*
X395771Y1298280D03*
X393171D03*
X394521Y1305980D03*
X390501Y1306224D03*
X400067Y1303319D03*
Y1300719D03*
Y1295519D03*
Y1298119D03*
Y1305919D03*
Y1308519D03*
X390401Y1312427D03*
X390501Y1309331D03*
X399935Y1317092D03*
Y1319592D03*
X389161Y1321177D03*
X391491Y1321927D03*
X392131Y1324821D03*
X396397Y1324591D03*
X394197Y1323091D03*
X396397Y1321691D03*
X399673Y1332653D03*
X403130Y1335963D03*
X400073Y1327653D03*
X403051Y1325373D03*
X394297Y1326091D03*
X392131Y1327721D03*
X396397Y1327491D03*
X400926Y1402207D03*
X391249Y1401048D03*
X390934Y1404085D03*
X401079Y1399208D03*
X400926Y1404707D03*
X400919Y1411231D03*
X392517Y1419015D03*
X400991Y1417264D03*
X390934Y1407605D03*
X390914Y1412991D03*
X391370Y1424782D03*
X403125Y1425008D03*
X390687Y1431713D03*
X394067Y1435323D03*
X401244Y1440773D03*
X396822Y1439340D03*
X396921Y1549810D03*
X396768Y1541810D03*
X396946Y1560810D03*
Y1556810D03*
X392108Y1582659D03*
X391330Y1585155D03*
X404030Y1595390D03*
Y1591990D03*
X402590Y1618952D03*
X405990D03*
X401812Y1616456D03*
X388220Y1631404D03*
X394910Y1632364D03*
X392550Y1618650D03*
X397406Y1633142D03*
X402590Y1618952D03*
X394910Y1637320D03*
X401740Y1648082D03*
X404240D03*
X404320Y1645452D03*
X401820D03*
X391563Y1640244D03*
X397406Y1636542D03*
X397400Y1641000D03*
X402246Y1671745D03*
X390180Y1668212D03*
X409535Y49388D03*
X412930Y62572D03*
X407970Y59612D03*
X407790Y62652D03*
X415800Y62665D03*
Y67465D03*
X419901Y117491D03*
X411434Y163662D03*
X408284D03*
X407490Y216912D03*
X410996Y218834D03*
X412820Y231922D03*
X405478Y236726D03*
X410090Y241932D03*
X420710Y242482D03*
X405139Y239908D03*
X417765Y252162D03*
X404985D03*
X417218Y291274D03*
X419920Y338162D03*
X416220Y364062D03*
X419012Y368762D03*
X418704Y379201D03*
X416762Y367353D03*
X418602Y394722D03*
X419023Y381760D03*
X418540Y392163D03*
X418982Y407847D03*
X416514Y407028D03*
X417010Y439352D03*
X415130Y480202D03*
X410532Y1153341D03*
X407948Y1153370D03*
Y1161570D03*
X410532Y1161541D03*
X419460Y1161570D03*
Y1153370D03*
X407948Y1169597D03*
X410532D03*
X419460D03*
X406248Y1248997D03*
X408798Y1249057D03*
X408511Y1256866D03*
X406001Y1256896D03*
X406128Y1254167D03*
X408678Y1254227D03*
X406188Y1251567D03*
X419638Y1248967D03*
X419295Y1256851D03*
X419518Y1254137D03*
X419578Y1251537D03*
X419295Y1259351D03*
X408738Y1251627D03*
X408523Y1259373D03*
X406013Y1259403D03*
X419295Y1261851D03*
X419307Y1264358D03*
X419285Y1267188D03*
X408523Y1264373D03*
X406013Y1264403D03*
Y1261903D03*
X408523Y1261873D03*
X405895Y1267218D03*
X408445Y1267278D03*
X416485Y1306208D03*
X419685D03*
X413885D03*
X406085D03*
X411285D03*
X408685D03*
X414085Y1312422D03*
X413885Y1309315D03*
X411485Y1312422D03*
X408685Y1309315D03*
X406085D03*
X411285D03*
X413039Y1316071D03*
X408079D03*
X410559D03*
X413039Y1321671D03*
X408079D03*
X410559D03*
X416629Y1321177D03*
X418959Y1321927D03*
X416099Y1335568D03*
X414617Y1333473D03*
X410225Y1329329D03*
X406225Y1328591D03*
X414435Y1330819D03*
X412963Y1328361D03*
X406225Y1331647D03*
X412465Y1393878D03*
X419974Y1405289D03*
Y1412789D03*
X420474Y1420289D03*
X410912Y1418177D03*
X408968Y1410427D03*
X407125Y1424978D03*
X404475Y1552452D03*
X407625Y1552572D03*
X419820Y1555862D03*
X405000Y1566670D03*
X419780Y1602802D03*
X419002Y1600306D03*
X406526Y1591212D03*
Y1596168D03*
X412600Y1601000D03*
X406768Y1616456D03*
X408700Y1603500D03*
Y1614300D03*
X408600Y1607400D03*
X419780Y1602802D03*
X411910Y1629170D03*
Y1624214D03*
X414406Y1624992D03*
Y1628392D03*
X405990Y1618952D03*
X410700Y1658460D03*
Y1655310D03*
X410232Y1670244D03*
X409857Y1682767D03*
X429535Y49388D03*
X430655Y58677D03*
X429050Y117491D03*
X430980Y132672D03*
X435340Y122196D03*
X428889Y121515D03*
X428883Y131015D03*
X429780Y157466D03*
Y161466D03*
X433695Y214862D03*
X429395Y232562D03*
X426295Y227862D03*
X422210Y221452D03*
X421200Y232562D03*
X423145Y227862D03*
X429395Y240562D03*
X429702Y290763D03*
X425720Y319492D03*
X425249Y338061D03*
X432380Y346522D03*
X422420Y338162D03*
X432006Y363644D03*
X431503Y376642D03*
X431781Y379201D03*
X434006Y365203D03*
X431596Y389604D03*
X433596Y391163D03*
X431920Y405288D03*
X431462Y402729D03*
X424980Y439462D03*
X431570Y435512D03*
X427790Y500862D03*
X427880Y506442D03*
X434343Y504233D03*
Y509733D03*
Y498733D03*
X428510Y515842D03*
X434343Y515233D03*
Y526233D03*
Y520733D03*
X431220Y518133D03*
Y523362D03*
X434620Y535762D03*
X434343Y542733D03*
X434320Y540153D03*
X434343Y547769D03*
Y552769D03*
X436822Y1161570D03*
Y1153370D03*
X431722D03*
Y1161570D03*
X434272Y1153370D03*
Y1161570D03*
X421960D03*
Y1153370D03*
X436822Y1170070D03*
X431722D03*
X434272D03*
X421960Y1169597D03*
X422148Y1248937D03*
X424698Y1248997D03*
X422088Y1251507D03*
X421805Y1256821D03*
X422028Y1254107D03*
X424458Y1256717D03*
X424578Y1254167D03*
X424638Y1251567D03*
X421805Y1259321D03*
X424398Y1259287D03*
X436068Y1248967D03*
X435828Y1256687D03*
X435948Y1254137D03*
X436008Y1251537D03*
X435768Y1259257D03*
X421805Y1261821D03*
X421817Y1264328D03*
X421795Y1267158D03*
X424345Y1267218D03*
X424380Y1264594D03*
X424388Y1261897D03*
X435715Y1267188D03*
X435720Y1264564D03*
X435708Y1261857D03*
X430999Y1286758D03*
X423229D03*
X426229D03*
X433999D03*
X422629Y1306224D03*
X432195Y1303319D03*
Y1305919D03*
X425299Y1303480D03*
X426649Y1305980D03*
X427899Y1303480D03*
X425299Y1295680D03*
X427899D03*
X432195Y1295519D03*
Y1298119D03*
X427899Y1298280D03*
X425299D03*
X432195Y1300719D03*
X427899Y1300880D03*
X425299D03*
X432195Y1308519D03*
X422529Y1312427D03*
X422629Y1309331D03*
X432063Y1317092D03*
Y1319592D03*
X421289Y1321177D03*
X423619Y1321927D03*
X428525Y1321691D03*
X426325Y1323091D03*
X424259Y1324821D03*
X428525Y1324591D03*
X434983Y1335924D03*
X431578Y1332560D03*
X432628Y1327845D03*
X435179Y1325373D03*
X424259Y1327721D03*
X426425Y1326091D03*
X428525Y1327491D03*
X436780Y1387387D03*
X427474Y1405289D03*
X434974D03*
Y1412789D03*
X427474Y1420289D03*
X434974D03*
X433539Y1430613D03*
X427546Y1443411D03*
X433954Y1439029D03*
X424146Y1443411D03*
X436920Y1541562D03*
X422566Y1550046D03*
X435396Y1551810D03*
X432996Y1558322D03*
X434430Y1567562D03*
X424570Y1579466D03*
X423180Y1602802D03*
X423958Y1600306D03*
X428099Y1586282D03*
X435240Y1609200D03*
X433383Y1602629D03*
X428941Y1606441D03*
X424800Y1616600D03*
X423180Y1602802D03*
X436840Y1632682D03*
X436880Y1622442D03*
X430015Y1626608D03*
X433670Y1639562D03*
X432895Y1737108D03*
X449535Y49388D03*
X451418Y78782D03*
X450380Y104647D03*
X453028Y154864D03*
X452500Y213362D03*
Y222362D03*
X442265Y290939D03*
X445964Y314234D03*
X439120Y314562D03*
X448220Y319862D03*
X446000Y339362D03*
X450400Y338812D03*
X445944Y359053D03*
X451062Y397262D03*
X447490Y409052D03*
X449420Y424162D03*
X443744Y452462D03*
X451520Y475837D03*
X437520Y484837D03*
X447520D03*
X442853Y542519D03*
X451320Y533562D03*
X442853Y547519D03*
X448276Y1161570D03*
X445776D03*
X443276D03*
X445776Y1153370D03*
X448276D03*
X443276D03*
X448276Y1170069D03*
X445776D03*
X443276D03*
X441128Y1248997D03*
X438578Y1248937D03*
X438518Y1251507D03*
X440858Y1256866D03*
X438348Y1256896D03*
X441008Y1254167D03*
X438458Y1254107D03*
X441068Y1251567D03*
X440870Y1259373D03*
X438360Y1259403D03*
X451642Y1256851D03*
X451878Y1254107D03*
X451642Y1259351D03*
X451938Y1251507D03*
X451998Y1248937D03*
X438360Y1261903D03*
X440870Y1261873D03*
Y1264373D03*
X438360Y1264403D03*
X438225Y1267158D03*
X440775Y1267218D03*
X451642Y1261851D03*
X451654Y1264358D03*
X451645Y1267158D03*
X448613Y1306208D03*
X446013D03*
X443413D03*
X440813D03*
X438213D03*
X451813D03*
X443613Y1312422D03*
X443413Y1309315D03*
X440813D03*
X438213D03*
X446213Y1312422D03*
X446013Y1309315D03*
X440207Y1316071D03*
X445167D03*
X442687D03*
X440207Y1321671D03*
X445167D03*
X442687D03*
X448757Y1321177D03*
X451087Y1321927D03*
X446944Y1335928D03*
X445153Y1334095D03*
X442353Y1329329D03*
X438353Y1328591D03*
X446563Y1330819D03*
X445091Y1328361D03*
X438353Y1331647D03*
X439391Y1398266D03*
X451048Y1404914D03*
X447110Y1403812D03*
X446230Y1407722D03*
X451080Y1433740D03*
X440164Y1433982D03*
X443715Y1436052D03*
X446258Y1441606D03*
X448079Y1562177D03*
X443910Y1555602D03*
X440019Y1576809D03*
X442128Y1574879D03*
X450020Y1570412D03*
X448328Y1582476D03*
X446020Y1570412D03*
X452020Y1580412D03*
X448740Y1574862D03*
X441308Y1602654D03*
X444458D03*
X437383Y1602629D03*
X442974Y1615615D03*
X447100Y1622562D03*
X447020Y1632632D03*
X451910Y1643282D03*
X437562Y1649770D03*
X442518D03*
X449940Y1647412D03*
X447090Y1647472D03*
X438340Y1652266D03*
X441740D03*
X452895Y1737108D03*
X469535Y49388D03*
X454568Y78782D03*
X462620Y120948D03*
X453346Y149864D03*
X468323Y254562D03*
X465236Y293823D03*
Y296973D03*
X467736Y312938D03*
X460300Y303662D03*
X468490Y340572D03*
X453621Y359053D03*
X460800Y358962D03*
X467211Y371902D03*
X459220Y393762D03*
X463500Y383562D03*
X462720Y404762D03*
X465421Y424928D03*
Y428078D03*
X456520Y476337D03*
X461520D03*
X456520Y484837D03*
X460323Y510183D03*
X455326Y520389D03*
X453727Y518036D03*
X457196Y1161570D03*
X459696D03*
X462196D03*
X459696Y1153370D03*
X457196D03*
X462196D03*
X459696Y1170070D03*
X462196D03*
X457196D03*
X456818Y1256687D03*
X454388Y1254077D03*
X454152Y1256821D03*
X456998Y1251537D03*
X456758Y1259257D03*
X454152Y1259321D03*
X468258Y1249107D03*
X468018Y1256827D03*
X468138Y1254277D03*
X468198Y1251677D03*
X467958Y1259397D03*
X457058Y1248967D03*
X454508Y1248907D03*
X454448Y1251477D03*
X456938Y1254137D03*
X456705Y1267188D03*
X454155Y1267128D03*
X456748Y1261867D03*
X456740Y1264564D03*
X454152Y1261821D03*
X454164Y1264328D03*
X467905Y1267328D03*
X467910Y1264704D03*
X467898Y1261997D03*
X460049Y1286978D03*
X463049D03*
X469019Y1286718D03*
X458327Y1303980D03*
X460927D03*
X464427Y1305380D03*
X454757Y1306224D03*
X460927Y1306580D03*
X458327D03*
Y1301380D03*
X460927D03*
X464427Y1300180D03*
Y1302780D03*
X458327Y1296180D03*
X460927D03*
X464427D03*
X458327Y1298780D03*
X460927D03*
X464423Y1308519D03*
X454657Y1312427D03*
X454757Y1309331D03*
X464191Y1317092D03*
Y1319592D03*
X453417Y1321177D03*
X455747Y1321927D03*
X458453Y1323091D03*
X460653Y1321691D03*
Y1324591D03*
X456387Y1324821D03*
X464738Y1333085D03*
X467644Y1335981D03*
X464191Y1327793D03*
X467307Y1325373D03*
X458553Y1326091D03*
X460653Y1327491D03*
X456387Y1327721D03*
X465749Y1401238D03*
X459550Y1401348D03*
X465947Y1398355D03*
X459321Y1393009D03*
X455576Y1409125D03*
Y1417125D03*
X455602Y1412334D03*
X455576Y1420625D03*
Y1427632D03*
Y1424125D03*
X454450Y1433580D03*
X456619Y1431189D03*
X463140Y1451562D03*
X463207Y1547543D03*
X453595Y1551470D03*
X459520Y1546962D03*
X466905Y1567847D03*
X456961Y1559697D03*
X456020Y1580412D03*
X464020D03*
X462079Y1572177D03*
X460020Y1580412D03*
X457220Y1584020D03*
X454661Y1596755D03*
X464160Y1587122D03*
X460200Y1589900D03*
X459779Y1609235D03*
X456510Y1614472D03*
X469488Y1607362D03*
X458414Y1624994D03*
Y1629950D03*
X460910Y1629172D03*
Y1625772D03*
X468040Y1654807D03*
Y1651657D03*
X478240Y55935D03*
Y66575D03*
Y61129D03*
X481880Y147069D03*
X481246Y161364D03*
X475500Y212685D03*
X470900Y234787D03*
X472800Y299462D03*
X478995Y293787D03*
X484800Y307362D03*
X476740Y309272D03*
X479740Y300202D03*
X482720Y360862D03*
X475508Y359266D03*
X476585Y370727D03*
X472720Y391362D03*
X479379Y452445D03*
X479169Y484696D03*
X474169D03*
X484169D03*
X474044Y503725D03*
X473870Y506622D03*
X474220Y572782D03*
X471940Y597532D03*
X478510Y602942D03*
X483030Y1153370D03*
Y1161570D03*
X473698D03*
X471198D03*
X473698Y1153370D03*
X471198D03*
X483030Y1170070D03*
X473698D03*
X471198D03*
X473318Y1249137D03*
X470768Y1249077D03*
X473035Y1256866D03*
X470525Y1256896D03*
X473198Y1254307D03*
X470648Y1254247D03*
X473258Y1251707D03*
X470708Y1251647D03*
X473047Y1259373D03*
X470537Y1259403D03*
X484098Y1248997D03*
X483819Y1256851D03*
X483978Y1254167D03*
X484038Y1251567D03*
X483819Y1259351D03*
X472965Y1267358D03*
X470415Y1267298D03*
X470537Y1261903D03*
X473047Y1261873D03*
Y1264373D03*
X470537Y1264403D03*
X483819Y1261851D03*
X483831Y1264358D03*
X483745Y1267218D03*
X474509Y1286848D03*
X481509D03*
X477509D03*
X484509D03*
X480741Y1306208D03*
X478141D03*
X475541D03*
X472941D03*
X470341D03*
X483941D03*
X472941Y1309315D03*
X478141D03*
X470341D03*
X478341Y1312422D03*
X475741D03*
X475541Y1309315D03*
X472335Y1316071D03*
X477295D03*
X474815D03*
X472335Y1321671D03*
X477295D03*
X474815D03*
X480885Y1321177D03*
X485545D03*
X483215Y1321927D03*
X477162Y1334095D03*
X478909Y1336038D03*
X474481Y1329329D03*
X470481Y1328591D03*
X478691Y1330819D03*
X477219Y1328361D03*
X470481Y1331647D03*
X483560Y1401712D03*
X475285Y1395402D03*
X474983Y1400385D03*
X485236Y1417844D03*
X481997Y1409955D03*
X470987Y1409965D03*
X484921Y1413246D03*
X470890Y1435838D03*
X482741Y1438698D03*
X478308Y1439986D03*
X482742Y1441312D03*
X478449Y1448158D03*
X482633Y1449091D03*
Y1446091D03*
X470111Y1548269D03*
X483348Y1548062D03*
X475110Y1548112D03*
X480848Y1548120D03*
X485111Y1578182D03*
X476451D03*
X473051D03*
X484333Y1575686D03*
Y1580678D03*
X477229D03*
X472273D03*
Y1575686D03*
X477229D03*
X476451Y1578182D03*
X485111D03*
X473051D03*
X485111Y1590094D03*
X476451D03*
X473051D03*
X478351Y1602380D03*
X481751D03*
X482529Y1599884D03*
X477573D03*
X484333Y1587598D03*
Y1592590D03*
X472273D03*
X477229D03*
Y1587598D03*
X472273D03*
X476451Y1590094D03*
X485111D03*
X473051D03*
X478351Y1614292D03*
X481751D03*
X482529Y1616788D03*
X477573D03*
Y1611796D03*
X482529D03*
X477573Y1604876D03*
X482529D03*
X478351Y1614292D03*
X481751D03*
X478351Y1602380D03*
X481751D03*
X472220Y1626732D03*
X472210Y1618626D03*
X485150Y1624942D03*
X472210Y1622735D03*
X477905Y1663242D03*
X477835Y1673462D03*
X477905Y1667242D03*
X477835Y1677462D03*
Y1685462D03*
X472895Y1737108D03*
X489535Y49347D03*
X488748Y72264D03*
X497002Y88167D03*
X499580Y78442D03*
X489730Y76132D03*
X498330Y96112D03*
X501540Y105152D03*
X498730Y128592D03*
X498630Y140492D03*
X500925Y231262D03*
X489980Y250512D03*
X499096Y252462D03*
X498636Y293123D03*
X489091Y293787D03*
X498636Y296273D03*
X495136Y305398D03*
X501136Y312238D03*
X486861Y309398D03*
X492074Y300306D03*
X486861Y305398D03*
X486710Y313582D03*
X490720Y360862D03*
Y368862D03*
X502070Y427937D03*
X488169Y475696D03*
X498169Y484696D03*
X488169D03*
X494193Y550447D03*
X486500Y556212D03*
X491043Y550447D03*
X486608Y1248967D03*
X489158Y1249027D03*
X486329Y1256821D03*
X486488Y1254137D03*
X488918Y1256747D03*
X489038Y1254197D03*
X486548Y1251537D03*
X489098Y1251597D03*
X486329Y1259321D03*
X488858Y1259317D03*
X500228Y1259237D03*
X486329Y1261821D03*
X486341Y1264328D03*
X488840Y1264624D03*
X488848Y1261927D03*
X488805Y1267248D03*
X486255Y1267188D03*
X500138Y1269637D03*
X500150Y1272344D03*
X500198Y1267037D03*
Y1264467D03*
X500168Y1261807D03*
X500150Y1275224D03*
X490759Y1291978D03*
X500150Y1278104D03*
X486885Y1306224D03*
X496451Y1306345D03*
X489555Y1303480D03*
X492155D03*
X490905Y1305980D03*
X492155Y1300880D03*
X489555D03*
X495309Y1300058D03*
X498309D03*
X486785Y1312427D03*
X486885Y1309331D03*
X496220Y1322440D03*
X496451Y1316745D03*
Y1308945D03*
Y1314145D03*
Y1311545D03*
X487875Y1321927D03*
X492878Y1322618D03*
X490678Y1324018D03*
X496319Y1330493D03*
Y1333043D03*
X499435Y1338799D03*
X488539Y1325772D03*
X492878Y1325518D03*
X488539Y1328672D03*
X490778Y1327018D03*
X492878Y1328418D03*
X499458Y1349468D03*
X496319Y1341264D03*
X499818Y1385027D03*
X499859Y1393027D03*
X491156Y1438713D03*
X499541Y1438698D03*
X491142Y1441312D03*
X499542D03*
X491089Y1446091D03*
Y1449091D03*
X499489D03*
Y1446091D03*
X500571Y1578182D03*
X497171D03*
X488511D03*
X501349Y1580678D03*
X496393D03*
Y1575686D03*
X501349D03*
X489289D03*
Y1580678D03*
X500571Y1578182D03*
X488511D03*
X497171D03*
X500571Y1590094D03*
X497171D03*
X488511D03*
X493811Y1602380D03*
X490411D03*
X502471D03*
X501693Y1599884D03*
X494589D03*
X489633D03*
X501349Y1592590D03*
X496393D03*
X501349Y1587598D03*
X496393D03*
X489289D03*
Y1592590D03*
X500571Y1590094D03*
X488511D03*
X497171D03*
X493811Y1614292D03*
X490411D03*
X502471D03*
X501693Y1611796D03*
Y1604876D03*
Y1616788D03*
X489633Y1611796D03*
X494589Y1604876D03*
X489633D03*
X494589Y1611796D03*
X489633Y1616788D03*
X494589D03*
X490411Y1614292D03*
X493811D03*
X490411Y1602380D03*
X493811D03*
X487340Y1641352D03*
X489230Y1643592D03*
X492895Y1737108D03*
X519764Y40328D03*
X517914Y42257D03*
X517902Y49194D03*
X510815D03*
X519742Y71436D03*
X517902Y69508D03*
X510815D03*
X503100Y78402D03*
X510030Y78412D03*
X504980Y101752D03*
X516236Y92948D03*
X513586Y92799D03*
X517290Y104252D03*
X503270Y128592D03*
X507320D03*
X503290Y140492D03*
X507360D03*
X515690Y147852D03*
X512500Y209862D03*
X504075Y231262D03*
X512500Y223362D03*
X508000Y237862D03*
Y241862D03*
X503040Y287928D03*
X505900Y311562D03*
X502239Y315404D03*
X510740Y332592D03*
X510720Y360862D03*
X502720D03*
X506720Y368862D03*
X509720Y390362D03*
X505720Y398362D03*
X502260Y397742D03*
X511320Y437962D03*
X513444Y457522D03*
Y473281D03*
X503169Y475671D03*
X514425Y489112D03*
Y495112D03*
X509493Y539819D03*
X516970Y592942D03*
X513025Y615742D03*
X504135Y615612D03*
X505398Y1259377D03*
X502858Y1259257D03*
X502718Y1271417D03*
X505218Y1271447D03*
X505290Y1267254D03*
X505338Y1261947D03*
X505278Y1264547D03*
X502750Y1267134D03*
X502798Y1261827D03*
X502738Y1264427D03*
X502718Y1274114D03*
X505218Y1274144D03*
X515898Y1271447D03*
X515950Y1274144D03*
X505220Y1280054D03*
X502718Y1276994D03*
X505218Y1277024D03*
X502680Y1280054D03*
X515960D03*
X515950Y1277024D03*
X517989Y1300108D03*
X514989D03*
X516069Y1319634D03*
X502469D03*
Y1322741D03*
X512869Y1319634D03*
X510269D03*
X507669D03*
X505069D03*
X507669Y1322741D03*
X505069D03*
X510269D03*
X504463Y1329497D03*
Y1335097D03*
X509423Y1329497D03*
X506943D03*
X509423Y1335097D03*
X506943D03*
X510469Y1325848D03*
X507869D03*
X513013Y1334603D03*
X517673D03*
X515343Y1335353D03*
X509382Y1347521D03*
X511149Y1349468D03*
X506609Y1342755D03*
X502609Y1342017D03*
X510819Y1344245D03*
X509347Y1341787D03*
X502609Y1345073D03*
X505055Y1387601D03*
Y1382301D03*
X505018Y1385027D03*
X502418D03*
X505055Y1396001D03*
Y1398601D03*
Y1390201D03*
X508881Y1404880D03*
X506181D03*
X505059Y1393027D03*
X502459D03*
X503559Y1405025D03*
X508775Y1409889D03*
X508828Y1407385D03*
X508802Y1412420D03*
X506075Y1409889D03*
X506128Y1407385D03*
X503572Y1407539D03*
Y1415039D03*
Y1412539D03*
X506102Y1412420D03*
X503572Y1410039D03*
X509246Y1420002D03*
X508001Y1438669D03*
X507942Y1441312D03*
X507964Y1448979D03*
Y1445979D03*
X509231Y1578182D03*
X512631D03*
X508453Y1575686D03*
X513409D03*
X508453Y1580678D03*
X513409D03*
X512631Y1578182D03*
X509231D03*
Y1590094D03*
X512631D03*
X517931Y1602380D03*
X514531D03*
X505871D03*
X513753Y1599884D03*
X506649D03*
X508453Y1587598D03*
X513409D03*
X508453Y1592590D03*
X513409D03*
X512631Y1590094D03*
X509231D03*
X517931Y1614292D03*
X514531D03*
X505871D03*
X513753Y1616788D03*
Y1604876D03*
Y1611796D03*
X506649D03*
Y1604876D03*
Y1616788D03*
X514531Y1614292D03*
X502471D03*
X517931D03*
X505871D03*
X514531Y1602380D03*
X502471D03*
X517931D03*
X505871D03*
X512895Y1737108D03*
X523164Y40328D03*
X518606Y23797D03*
X529720Y30792D03*
X525000Y42257D03*
X524988Y49194D03*
X519764Y40328D03*
X523164D03*
X523142Y71436D03*
X532075Y69508D03*
Y57894D03*
X524988Y69508D03*
X533915Y59822D03*
X519742Y71436D03*
X523142D03*
X527520Y69633D03*
X528590Y72922D03*
X529239Y99997D03*
Y92911D03*
X528400Y104225D03*
X518450Y101602D03*
X527310Y98147D03*
Y94747D03*
X528400Y114275D03*
X527823Y131802D03*
X527160Y129243D03*
X527823Y149802D03*
X527278Y164726D03*
X529507Y202448D03*
X522337Y202404D03*
X532533Y299500D03*
X529533D03*
X523682Y307541D03*
Y304541D03*
X523660Y323222D03*
X527720Y360862D03*
X523670Y368892D03*
X529720Y390362D03*
X521720Y398362D03*
X532650Y446396D03*
X518735Y452442D03*
X521885D03*
X533410Y475932D03*
X525820Y473662D03*
X524425Y489112D03*
Y495112D03*
X519520Y484027D03*
X522805Y482155D03*
X531258Y505473D03*
X526852Y511331D03*
X527042Y505830D03*
X521561Y505969D03*
Y500469D03*
Y511469D03*
X524220Y505862D03*
Y500362D03*
Y511362D03*
X526853Y516817D03*
X521561Y516969D03*
Y522469D03*
X524220Y516862D03*
X524720Y525293D03*
Y519743D03*
X521561Y527969D03*
Y539819D03*
X524920D03*
X521561Y550819D03*
X523699Y571545D03*
X526280Y569122D03*
X528500Y566722D03*
X523890Y592387D03*
X520710Y592552D03*
X531472Y579750D03*
X521118Y1273097D03*
X518488Y1271477D03*
X521058Y1275667D03*
X518490Y1274144D03*
X521058Y1278277D03*
X521020Y1280974D03*
X518500Y1280054D03*
X518490Y1277024D03*
X530398Y1288557D03*
X530548Y1283377D03*
X530428Y1285947D03*
X530410Y1291254D03*
X532558Y1289967D03*
X532618Y1287367D03*
X532678Y1284797D03*
X530450Y1297014D03*
Y1294134D03*
X532570Y1295554D03*
Y1298434D03*
Y1292674D03*
X523033Y1319406D03*
X519013Y1319650D03*
Y1322757D03*
X527645Y1326076D03*
X528579Y1329143D03*
X528377Y1335982D03*
X518913Y1325853D03*
X525008Y1336287D03*
X520643Y1338247D03*
X522809Y1339517D03*
X522783Y1334882D03*
X520643Y1341147D03*
X520003Y1335353D03*
X528579Y1342143D03*
Y1344743D03*
X534597Y1345539D03*
Y1342432D03*
X528447Y1353316D03*
Y1355816D03*
X524892Y1341462D03*
X522818Y1342930D03*
X528929Y1364212D03*
X531563Y1361597D03*
X533351Y1578182D03*
X524691D03*
X521291D03*
X532573Y1575686D03*
Y1580678D03*
X520513D03*
X525469D03*
X520513Y1575686D03*
X525469D03*
X524691Y1578182D03*
X533351D03*
X521291D03*
X533351Y1590094D03*
X524691D03*
X521291D03*
X526591Y1602380D03*
X529991D03*
X525813Y1599884D03*
X530769D03*
X518709D03*
X532573Y1587598D03*
Y1592590D03*
X525469D03*
X520513D03*
Y1587598D03*
X525469D03*
X524691Y1590094D03*
X533351D03*
X521291D03*
X526591Y1614292D03*
X529991D03*
X525813Y1611796D03*
X530769D03*
X525813Y1604876D03*
X530769D03*
Y1616788D03*
X525813D03*
X518709D03*
Y1604876D03*
Y1611796D03*
X526591Y1614292D03*
X529991D03*
X526591Y1602380D03*
X529991D03*
X532895Y1737108D03*
X548609Y32500D03*
X539720Y30792D03*
X534720D03*
X546248Y69508D03*
X539161D03*
Y57894D03*
X537315Y59822D03*
X541002Y71436D03*
X544402D03*
X546234Y77443D03*
X548070Y79372D03*
X542620Y103352D03*
X542460Y99172D03*
X549610Y120682D03*
X537360Y120522D03*
X539475Y118772D03*
X550545Y147302D03*
X547395D03*
X540460Y200392D03*
X542798Y202646D03*
X539639Y271972D03*
X535630Y306602D03*
X547420Y306862D03*
X544920D03*
X535720Y360862D03*
X547810Y414472D03*
X549670Y419892D03*
X543035Y441005D03*
X542870Y438320D03*
X548464Y456534D03*
X548780Y475932D03*
X538120Y463137D03*
X548550Y480382D03*
X546210Y519642D03*
X535290Y572932D03*
X541820Y575130D03*
X541722Y568054D03*
X543450Y590262D03*
X537730Y577440D03*
X547020Y590332D03*
X550320Y583362D03*
X536626Y590500D03*
X537560Y598102D03*
X537648Y1290037D03*
X535058Y1290007D03*
X535148Y1287397D03*
X543660Y1302934D03*
X541100D03*
X538560D03*
X535110Y1292704D03*
Y1295584D03*
Y1298464D03*
X537650Y1292704D03*
X540210D03*
X537650Y1298464D03*
Y1295584D03*
X540210Y1298464D03*
Y1295584D03*
X536020Y1302904D03*
X544813Y1322668D03*
X542213D03*
X538293D03*
X535693D03*
X548197Y1342432D03*
X539997Y1348646D03*
X542397Y1345539D03*
X542597Y1348646D03*
X537197Y1342432D03*
X539797D03*
X542397D03*
X544997D03*
X537197Y1345539D03*
X539797D03*
X539071Y1352295D03*
X536591D03*
X541551D03*
X545141Y1357401D03*
X549801D03*
X541551Y1357895D03*
X542256Y1369935D03*
X536591Y1357895D03*
X539071D03*
X538737Y1365553D03*
X534737Y1364815D03*
X542947Y1367043D03*
X541475Y1364585D03*
X534737Y1367871D03*
X547471Y1358151D03*
X545411Y1578182D03*
X548811D03*
X536751D03*
X549589Y1580678D03*
X544633D03*
X549589Y1575592D03*
X544633D03*
X537529Y1575686D03*
Y1580678D03*
X536751Y1578182D03*
X548811D03*
X545411D03*
X548811Y1590094D03*
X545411D03*
X536751D03*
X542051Y1602380D03*
X538651D03*
X550711D03*
X549933Y1599790D03*
X537873Y1599884D03*
X542829D03*
X549589Y1592590D03*
X544633D03*
X549589Y1587598D03*
X544633D03*
X537529D03*
Y1592590D03*
X536751Y1590094D03*
X548811D03*
X545411D03*
X542051Y1614292D03*
X538651D03*
X550711D03*
X549933Y1611796D03*
Y1604876D03*
Y1616788D03*
X542829D03*
X537873D03*
Y1604876D03*
X542829D03*
X537873Y1611796D03*
X542829D03*
X538651Y1614292D03*
X542051D03*
X538651Y1602380D03*
X542051D03*
X562780Y32842D03*
X554720Y32862D03*
X564430Y45132D03*
X554983Y45312D03*
X558575Y71436D03*
X555175D03*
X560421Y69508D03*
X553335D03*
X555175Y71436D03*
X558575D03*
X553320Y77443D03*
X551470Y79372D03*
X559000Y102862D03*
X561000Y98862D03*
X564988Y118670D03*
X555545Y134340D03*
X552395D03*
X566500Y125097D03*
X551231Y122671D03*
X565500Y145252D03*
X555220Y164787D03*
X555545Y156462D03*
X555195Y184862D03*
Y171862D03*
X553657Y193862D03*
X554872Y196635D03*
X559400Y201162D03*
X557248Y198909D03*
X564600Y202662D03*
X552489Y212022D03*
X553402Y231292D03*
X564944Y252173D03*
X552089Y253202D03*
Y257202D03*
X562461Y272161D03*
X553536Y307527D03*
X566730Y300992D03*
X563790Y331846D03*
X561290D03*
X558790D03*
X562200Y419412D03*
X559300Y414112D03*
X559730Y434772D03*
X557829Y454479D03*
X558220Y459362D03*
X563281Y543113D03*
X560640Y540613D03*
X566140Y554972D03*
Y551472D03*
X559927Y548457D03*
X556820Y570462D03*
X557430Y583572D03*
X558933Y1323658D03*
X563634Y1334315D03*
X561034D03*
X558933Y1326258D03*
X556563Y1337918D03*
X553963D03*
X558933Y1328938D03*
X556563Y1335318D03*
Y1332718D03*
X558933Y1331538D03*
X553963Y1335318D03*
Y1332718D03*
X555313Y1340418D03*
X551141Y1345555D03*
X551041Y1348651D03*
X551141Y1342448D03*
X555372Y1343037D03*
X561070Y1346174D03*
X554837Y1359315D03*
X557037Y1363715D03*
Y1357915D03*
Y1360815D03*
X554937Y1362315D03*
X552771Y1361045D03*
Y1363945D03*
X552131Y1358151D03*
X555057Y1449395D03*
X557471Y1578182D03*
X560871D03*
X556693Y1575686D03*
X561649D03*
X556693Y1580678D03*
X561649D03*
X560871Y1578182D03*
X557471D03*
Y1590094D03*
X560871D03*
X566171Y1602380D03*
X562771D03*
X554111D03*
X561993Y1599884D03*
X554889Y1599790D03*
X556693Y1587598D03*
X561649D03*
Y1592590D03*
X556693D03*
X560871Y1590094D03*
X557471D03*
X566171Y1614292D03*
X562771D03*
X554111D03*
X561993Y1616788D03*
Y1604876D03*
Y1611796D03*
X554889D03*
Y1604876D03*
Y1616788D03*
X562771Y1614292D03*
X550711D03*
X566171D03*
X554111D03*
X562771Y1602380D03*
X550711D03*
X566171D03*
X554111D03*
X552895Y1737108D03*
X572500Y32862D03*
X568500D03*
X578620Y45112D03*
X581500Y41862D03*
X567507Y45869D03*
X577300Y66682D03*
X577880Y75442D03*
X579080Y119402D03*
X567673Y130542D03*
X573115Y161232D03*
X581120Y155062D03*
X568245Y167112D03*
X579481Y202378D03*
Y198378D03*
X579170Y190092D03*
X579481Y210378D03*
X568149Y217916D03*
X580712Y215877D03*
X579481Y206378D03*
X581645Y233362D03*
X569668Y229812D03*
X578711Y230109D03*
X579245Y221362D03*
X567730Y225362D03*
Y221362D03*
X581755Y236978D03*
X578509Y265132D03*
X575359D03*
X582510Y296657D03*
X569880Y300992D03*
X580400Y302402D03*
X577480Y303822D03*
X582510Y304052D03*
Y311571D03*
X567630Y331958D03*
X574800Y322462D03*
X582436Y361032D03*
X572360Y351962D03*
X580370Y383670D03*
X569490Y437600D03*
X570760Y451710D03*
X567320Y454962D03*
Y459962D03*
Y457462D03*
X578920Y466462D03*
X583045Y488212D03*
X571990Y501046D03*
X568840D03*
X568520Y504162D03*
Y506662D03*
X578925Y516846D03*
X571700Y552200D03*
X571627Y548124D03*
X569050Y578292D03*
X572057Y577242D03*
X573849Y1346968D03*
X569849D03*
X571555Y1352487D03*
X570645Y1361358D03*
X576220Y1423862D03*
X571620Y1424492D03*
X581591Y1578182D03*
X569531D03*
X572931D03*
X584991D03*
X580813Y1575686D03*
Y1580678D03*
X573709D03*
X568753D03*
Y1575686D03*
X573709D03*
X572931Y1578182D03*
X581591D03*
X569531D03*
X581591Y1590094D03*
X584991D03*
X569531D03*
X572931D03*
X574831Y1602380D03*
X578231D03*
X579009Y1599884D03*
X574053D03*
X566949D03*
X580813Y1587598D03*
Y1592590D03*
X573709D03*
X568753D03*
X573709Y1587598D03*
X568753D03*
X572931Y1590094D03*
X581591D03*
X569531D03*
X574831Y1614292D03*
X578231D03*
X574053Y1616788D03*
X579009D03*
Y1611796D03*
X574053D03*
X579009Y1604876D03*
X574053D03*
X566949Y1616788D03*
Y1604876D03*
Y1611796D03*
X574831Y1614292D03*
X578231D03*
X574831Y1602380D03*
X578231D03*
X572895Y1737108D03*
X584950Y54842D03*
X596840Y45152D03*
X593925Y49193D03*
X586600Y60602D03*
X592307Y94262D03*
X597287D03*
X594720Y97220D03*
X591395Y132142D03*
X588245D03*
X598410Y124102D03*
X598390Y126802D03*
X595220Y140922D03*
X588000D03*
X592710Y156342D03*
X593248Y159480D03*
X589690Y161732D03*
X596581Y184849D03*
X590337Y177604D03*
X592220Y173862D03*
X596795Y179287D03*
X590281Y180698D03*
X598760Y203712D03*
X593966Y229965D03*
X584795Y233362D03*
X591310Y219582D03*
X592220Y249362D03*
X592039Y252202D03*
X588577Y285862D03*
X590350Y294402D03*
X591727Y285862D03*
X586820Y314662D03*
X599620Y314762D03*
X595520Y314862D03*
X583820Y314662D03*
X597820Y317062D03*
X592920Y326362D03*
X590820Y330962D03*
X590720Y327862D03*
Y324582D03*
X590470Y319192D03*
X583685Y363271D03*
X586185D03*
X591839Y426112D03*
X591720Y433937D03*
X595520Y439762D03*
X599080Y448062D03*
X584100Y477952D03*
X592520Y467662D03*
X593545Y488212D03*
X599645Y479862D03*
X598661Y486922D03*
X587100Y493842D03*
X592400Y479162D03*
X591070Y504900D03*
X594090Y505107D03*
Y501957D03*
X587100Y496342D03*
X594240Y511953D03*
X591425Y522337D03*
X591500Y516862D03*
X593675Y534702D03*
X596880Y534812D03*
X589989Y745475D03*
X592340Y744624D03*
X598693Y742072D03*
X593651Y1578182D03*
X597051D03*
X597829Y1580678D03*
X592873D03*
X597829Y1575686D03*
X592873D03*
X585769D03*
Y1580678D03*
X597051Y1578182D03*
X584991D03*
X593651D03*
X597051Y1590094D03*
X593651D03*
X598951Y1602380D03*
X590291D03*
X586891D03*
X598173Y1599884D03*
X586113D03*
X591069D03*
X597829Y1592590D03*
X592873D03*
X597829Y1587598D03*
X592873D03*
X585769D03*
Y1592590D03*
X597051Y1590094D03*
X584991D03*
X593651D03*
X598951Y1614292D03*
X586891D03*
X590291D03*
X598173Y1616788D03*
Y1611796D03*
Y1604876D03*
X586113D03*
X591069D03*
X586113Y1611796D03*
X591069D03*
Y1616788D03*
X586113D03*
X598951Y1614292D03*
X586891D03*
X590291D03*
X598951Y1602380D03*
X586891D03*
X590291D03*
X607890Y34389D03*
X615420Y42342D03*
X605060Y42402D03*
X615185Y49193D03*
X612822Y43232D03*
X615185Y69508D03*
X603374D03*
X615220Y76862D03*
X615170Y73812D03*
X601220Y73862D03*
Y76862D03*
X601050Y100008D03*
X600220Y96862D03*
X610104Y119342D03*
X614384D03*
X602306Y143077D03*
X612670Y142872D03*
X606040Y153432D03*
X606190Y144002D03*
X602430Y153862D03*
X612520Y154812D03*
X615572Y173942D03*
X615573Y181984D03*
Y179484D03*
X615572Y176442D03*
X617370Y188752D03*
X613970D03*
X614531Y200378D03*
X611030Y188372D03*
X611381Y200378D03*
X613970Y188752D03*
X603340Y208142D03*
X614531Y209878D03*
X609456Y204994D03*
X611381Y209878D03*
X606719Y254966D03*
X611310Y266272D03*
X614200Y265792D03*
X609844Y330407D03*
X609040Y317282D03*
X615635Y317637D03*
X608830Y374302D03*
X605830Y402782D03*
X605220Y416362D03*
X610720Y436362D03*
X600800Y430900D03*
X614220Y436362D03*
X610720Y442862D03*
X614220D03*
X600351Y461862D03*
X614220Y452862D03*
Y447862D03*
X602910Y461862D03*
X610720Y457862D03*
X614220D03*
X610720Y452862D03*
X614220Y467862D03*
Y472862D03*
Y477862D03*
X610820Y472862D03*
X605469Y467562D03*
X610720Y462862D03*
X614220D03*
X603779Y486922D03*
X601220D03*
X600645Y504362D03*
X606200Y510862D03*
Y514862D03*
X611870Y512560D03*
X606220Y517762D03*
X614086Y537624D03*
X607328Y537481D03*
X610797Y537528D03*
X614000Y550800D03*
X607720Y550862D03*
X610720D03*
X603317Y738415D03*
X614660Y739553D03*
X600460Y744912D03*
X613047Y741492D03*
X602027Y761445D03*
X612407Y769485D03*
X605711Y1578182D03*
X609111D03*
X617771D03*
X609889Y1575686D03*
X604933D03*
X609889Y1580678D03*
X604933D03*
X609111Y1578182D03*
X605711D03*
X617771Y1590094D03*
X605711D03*
X609111D03*
X614411Y1602380D03*
X611011D03*
X602351D03*
X615189Y1599884D03*
X610233D03*
X603129D03*
X609889Y1587598D03*
X604933D03*
X609889Y1592590D03*
X604933D03*
X609111Y1590094D03*
X605711D03*
X614411Y1614292D03*
X611011D03*
X602351D03*
X615189Y1604876D03*
X610233D03*
X615189Y1611796D03*
X610233D03*
X615189Y1616788D03*
X610233D03*
X603129D03*
Y1611796D03*
Y1604876D03*
X611011Y1614292D03*
X614411D03*
X602351D03*
X611011Y1602380D03*
X614411D03*
X602351D03*
X612895Y1737108D03*
X616675Y31777D03*
X624633Y49193D03*
X629820Y42562D03*
Y45062D03*
X619562Y49193D03*
X624140Y46672D03*
X622271Y44782D03*
X629000Y67362D03*
X628590Y58622D03*
X622271Y57952D03*
X631546Y85024D03*
X618460Y119342D03*
X626699Y119182D03*
X630951D03*
X624610Y142842D03*
X624520Y154622D03*
X631300Y167872D03*
X631290Y153702D03*
X615970Y161522D03*
X628195Y178414D03*
X628194Y170372D03*
X628195Y175914D03*
X628194Y172872D03*
X630040Y188752D03*
X626640D03*
X630818Y191248D03*
X625862D03*
X620030Y188782D03*
X617370Y188752D03*
X630040D03*
X626640D03*
X628730Y216472D03*
X631730D03*
X628730Y220472D03*
Y224472D03*
X631730Y220472D03*
Y224472D03*
X630795Y236862D03*
X621740Y265952D03*
X618470Y265732D03*
X629564Y253127D03*
X623150Y273172D03*
X621060Y271066D03*
X625800Y311912D03*
X630220Y314362D03*
X628294Y317007D03*
X623365Y316742D03*
X631146Y317768D03*
X623580Y336429D03*
X619100Y374638D03*
X621720Y373362D03*
X628500Y402362D03*
X624220Y411362D03*
X629220D03*
X625500Y421362D03*
X629220D03*
Y426362D03*
X629248Y436972D03*
X628900Y431050D03*
X625900D03*
X629220Y442862D03*
X622220D03*
X617220Y436362D03*
X622220Y452862D03*
Y447862D03*
X629220Y457862D03*
X622220D03*
X629220Y452862D03*
Y447862D03*
X626390Y467882D03*
X626210Y478002D03*
X626310Y472902D03*
X629220Y472862D03*
Y477862D03*
Y467862D03*
Y462862D03*
X622220D03*
X622520Y467862D03*
X629220Y487310D03*
Y482862D03*
X626720Y482880D03*
X629480Y508862D03*
X629920Y516652D03*
X623000Y546900D03*
X629220Y643462D03*
X626720D03*
X617252Y739354D03*
X626207Y747585D03*
X623497Y748235D03*
X626017Y745083D03*
X620870Y762072D03*
X617940Y763552D03*
X630417Y757135D03*
X618114Y1258470D03*
X629831Y1578182D03*
X621171D03*
X633231D03*
X629053Y1575686D03*
Y1580678D03*
X621949D03*
X616993D03*
X621949Y1575686D03*
X616993D03*
X621171Y1578182D03*
X629831D03*
X617771D03*
X629831Y1590094D03*
X633231D03*
X621171D03*
X623071Y1602380D03*
X626471D03*
X622293Y1599884D03*
X627249D03*
X629053Y1587598D03*
Y1592590D03*
X621949D03*
X616993D03*
X621949Y1587598D03*
X616993D03*
X621171Y1590094D03*
X629831D03*
X617771D03*
X623071Y1614292D03*
X626471D03*
X627249Y1616788D03*
X622293D03*
Y1611796D03*
X627249D03*
X622293Y1604876D03*
X627249D03*
X623071Y1614292D03*
X626471D03*
X623071Y1602380D03*
X626471D03*
X637220Y31462D03*
X646440Y43632D03*
X632463Y43302D03*
X645150Y69508D03*
X645350Y60612D03*
X638500Y57362D03*
X635000D03*
X645330Y72972D03*
X647220Y96929D03*
X632640Y107532D03*
X637500Y110362D03*
X640130Y166362D03*
X642480Y184862D03*
X643170Y171362D03*
X645109Y249202D03*
Y260202D03*
X645876Y296231D03*
X633138Y296766D03*
X643800Y294327D03*
Y298297D03*
X645528Y308623D03*
X645807Y304291D03*
X643800Y306547D03*
Y302247D03*
X645990Y314482D03*
X643800Y310962D03*
X633350Y314362D03*
X647200Y354300D03*
X647100Y357372D03*
X632620Y389862D03*
X645925Y389937D03*
X647700Y399162D03*
X643500Y400962D03*
X643940Y411482D03*
X644220Y426362D03*
X640720Y418862D03*
X644220Y421362D03*
X637195D03*
X647420Y434162D03*
X640720Y431362D03*
X644000Y438862D03*
X644220Y431362D03*
X638250Y439250D03*
X637220Y431362D03*
X643736Y457214D03*
X644220Y452862D03*
X640820Y457902D03*
X637220Y452862D03*
X640920Y447862D03*
X644220D03*
X637195Y457862D03*
X637220Y467862D03*
Y472862D03*
Y477862D03*
X644245Y472862D03*
X644220Y467862D03*
Y477862D03*
Y462862D03*
X640798Y472934D03*
X637220Y462862D03*
X640820Y467862D03*
X644245Y482862D03*
X645220Y504362D03*
X646815Y517974D03*
X637020Y522362D03*
X642630Y517870D03*
X640130D03*
X633147Y758595D03*
X645291Y1578182D03*
X641891D03*
X646069Y1580678D03*
X641113D03*
X646069Y1575592D03*
X641113D03*
X634009Y1575686D03*
Y1580678D03*
X645291Y1578182D03*
X633231D03*
X641891D03*
Y1590094D03*
X645291D03*
X647191Y1602380D03*
X635131D03*
X638531D03*
X646413Y1599790D03*
X639309Y1599884D03*
X634353D03*
X646069Y1592590D03*
X641113D03*
X646069Y1587598D03*
X641113D03*
X634009D03*
Y1592590D03*
X645291Y1590094D03*
X633231D03*
X641891D03*
X647191Y1614292D03*
X635131D03*
X638531D03*
X646413Y1616788D03*
Y1611796D03*
Y1604876D03*
X639309D03*
X634353D03*
X639309Y1611796D03*
X634353D03*
Y1616788D03*
X639309D03*
X647191Y1614292D03*
X635131D03*
X638531D03*
X647191Y1602380D03*
X635131D03*
X638531D03*
X641057Y1648659D03*
X647725Y1643719D03*
X645407Y1660425D03*
X636702Y1677610D03*
X641386Y1687283D03*
X639745Y1714362D03*
X646225Y1708169D03*
X648290Y1720052D03*
X639745Y1726362D03*
Y1722362D03*
Y1718362D03*
X632895Y1737108D03*
X651943Y33535D03*
X659839Y47264D03*
X656439D03*
X661534Y41748D03*
X661550Y45133D03*
X654464D03*
X661681Y49193D03*
X654595D03*
X656439Y47264D03*
X659839D03*
X663543Y43328D03*
X656950Y59012D03*
X652153Y98105D03*
X652680Y89712D03*
X651579Y102703D03*
X659000Y89262D03*
X651980Y133822D03*
X662498Y124960D03*
X650790Y144982D03*
Y149871D03*
Y140699D03*
X662880Y149912D03*
Y146912D03*
X662560Y214152D03*
X662780Y210362D03*
Y205362D03*
Y207862D03*
X659880Y210762D03*
Y205762D03*
Y208262D03*
X650705Y270947D03*
X662891Y357442D03*
X662680Y354362D03*
X651520Y378662D03*
X660690Y408162D03*
X660720Y404362D03*
X658720Y399862D03*
X652195Y457862D03*
X655820Y467662D03*
X663000Y489500D03*
X663014Y493860D03*
X655220Y486862D03*
X653800Y498740D03*
X663720Y523806D03*
X661743Y521166D03*
X657734Y528255D03*
X652577Y1000775D03*
X662282Y1386432D03*
X653690Y1392362D03*
X653761Y1396300D03*
X663187Y1397720D03*
X663687Y1407279D03*
X654606Y1431203D03*
X654540Y1427605D03*
Y1424205D03*
X661100Y1451012D03*
X662660Y1548120D03*
X663410Y1553982D03*
X657351Y1578182D03*
X653951D03*
X653173Y1575686D03*
X658129D03*
X653173Y1580678D03*
X658129D03*
X657351Y1578182D03*
X653951D03*
X657351Y1590094D03*
X653951D03*
X662651Y1602380D03*
X659251D03*
X650591D03*
X663429Y1599884D03*
X658473D03*
X651369Y1599790D03*
X653173Y1587598D03*
X658129D03*
X653173Y1592590D03*
X658129D03*
X657351Y1590094D03*
X653951D03*
X662651Y1614292D03*
X659251D03*
X650591D03*
X663429Y1604876D03*
X658473D03*
X663429Y1611796D03*
X658473D03*
Y1616788D03*
X663429D03*
X651369D03*
Y1611796D03*
Y1604876D03*
X662651Y1614292D03*
X659251D03*
X650591D03*
X662651Y1602380D03*
X659251D03*
X650591D03*
X664590Y1631620D03*
X663043Y1647557D03*
X655307Y1647436D03*
X663097Y1642667D03*
X663118Y1659557D03*
X663145Y1664862D03*
X656725Y1657619D03*
Y1660769D03*
X663118Y1655557D03*
X663043Y1651557D03*
X663145Y1676862D03*
Y1672862D03*
Y1668862D03*
X656973Y1698727D03*
X652712Y1686275D03*
X653420Y1698662D03*
X663645Y1722862D03*
X652895Y1737108D03*
X680200Y39062D03*
X675854Y49193D03*
X672005Y44119D03*
X669004Y41698D03*
X668800Y45262D03*
X668768Y49193D03*
X666943Y43328D03*
X670612Y47264D03*
X674012D03*
X666406Y69508D03*
X675225Y58108D03*
X678050Y58157D03*
X673750Y77692D03*
X677790Y104880D03*
X674145Y113487D03*
X677978Y119668D03*
Y115668D03*
X675560Y117120D03*
X665650Y147692D03*
X673690Y200672D03*
X673300Y211332D03*
X667020Y225762D03*
X674731Y359924D03*
X680600Y364282D03*
Y375462D03*
X673220Y388362D03*
X668329Y411714D03*
X677295Y404362D03*
X677195Y408262D03*
X675295Y399862D03*
X670720D03*
X668695Y408362D03*
Y404262D03*
X674628Y424313D03*
X671479Y421163D03*
X667660Y429037D03*
X674628Y427462D03*
Y414864D03*
X677778D03*
Y424313D03*
X671479Y414864D03*
X674628Y421163D03*
Y418013D03*
X677778D03*
Y421163D03*
X668329D03*
X677778Y427462D03*
Y430612D03*
X674628Y436911D03*
Y443210D03*
X671479Y430612D03*
Y436911D03*
X677778Y433761D03*
X668329Y436911D03*
X677778Y440061D03*
X674628D03*
X677778Y436911D03*
Y443210D03*
X674628Y430612D03*
X665870Y433942D03*
X671479Y462108D03*
X677778Y449510D03*
X668329Y452659D03*
X674628D03*
X671479D03*
X677778D03*
X668329Y455809D03*
X671479Y458959D03*
X674628D03*
X668329D03*
X677778D03*
Y455809D03*
X674628D03*
X668067Y462090D03*
X677778Y462108D03*
X671479Y455809D03*
X674628Y449510D03*
Y462108D03*
X677778Y477856D03*
Y471557D03*
Y474707D03*
X671479Y465258D03*
X674628D03*
X668329D03*
X677778D03*
X674628Y484006D03*
X668329Y481006D03*
X680220Y495887D03*
X670220Y503837D03*
X675220D03*
X680220D03*
X675220Y521862D03*
Y516852D03*
X670720Y521862D03*
Y516862D03*
X680220Y530362D03*
X671607Y742835D03*
X673617Y744735D03*
X669700Y746626D03*
X677887Y742121D03*
X669778Y759929D03*
X670037Y1336396D03*
X664987D03*
X667487D03*
X664987Y1338896D03*
X667487D03*
X670037D03*
Y1333896D03*
X664987D03*
X667487D03*
X664987Y1348896D03*
X667487D03*
X664987Y1346396D03*
X667487D03*
X664987Y1343896D03*
Y1341396D03*
X667487D03*
Y1343896D03*
X670037Y1341396D03*
Y1343896D03*
Y1346396D03*
Y1348896D03*
X673517Y1360815D03*
X676017D03*
X668096Y1360822D03*
X678517Y1360815D03*
X677137Y1384311D03*
X674537D03*
X671937D03*
X669337D03*
X677137Y1387418D03*
X674537D03*
X671937D03*
X669337D03*
X664782Y1383832D03*
Y1381232D03*
Y1378632D03*
Y1386432D03*
X679737Y1384311D03*
X677337Y1390525D03*
X674737D03*
X676250Y1399757D03*
X673820D03*
X671350D03*
X676250Y1394157D03*
X673820D03*
X671350D03*
X679881Y1399280D03*
X666425Y1414200D03*
X676312Y1411554D03*
X673477Y1409386D03*
X669477Y1406694D03*
X677619Y1408887D03*
X675876Y1406619D03*
X669477Y1409415D03*
X674149Y1434149D03*
X671149D03*
X668649D03*
X674149Y1426149D03*
Y1431149D03*
Y1428649D03*
X671149Y1426149D03*
X668649D03*
X671149Y1431149D03*
X668649Y1428649D03*
Y1431149D03*
X671149Y1428649D03*
X677319Y1428359D03*
Y1433359D03*
Y1430859D03*
X667926Y1547018D03*
X665410Y1548180D03*
X679192Y1564252D03*
X679207Y1560482D03*
X678877Y1566798D03*
X678610Y1582154D03*
X666560Y1581000D03*
X678515Y1573910D03*
X666600Y1584900D03*
X678900Y1595400D03*
X678771Y1585945D03*
X666700Y1595500D03*
X678900Y1589800D03*
X666700Y1591900D03*
X678900Y1592600D03*
X666700Y1588500D03*
X679640Y1617520D03*
Y1614000D03*
X679270Y1604040D03*
X675710Y1620320D03*
X671112Y1639962D03*
X671290Y1646320D03*
X676648Y1657380D03*
X668695Y1662235D03*
X671620Y1670862D03*
Y1668303D03*
X677940Y1670110D03*
X678490Y1695660D03*
X674195Y1708362D03*
Y1712362D03*
X669120Y1718862D03*
X674195Y1728362D03*
X672895Y1737108D03*
X674195Y1732362D03*
X689940Y38952D03*
X696838Y45112D03*
X686854Y43701D03*
X692380Y43532D03*
X694751Y70212D03*
X685780Y70022D03*
X682941Y69982D03*
X685968Y58157D03*
X694400D03*
X681980D03*
X690510Y59132D03*
X696700Y72462D03*
X692389Y72692D03*
X687664Y73202D03*
X687050Y79212D03*
X685230Y76952D03*
X683820Y79192D03*
X682890Y72642D03*
X696370Y78512D03*
X696727Y81552D03*
Y84052D03*
X681053Y104668D03*
X695720Y102162D03*
X694220Y104862D03*
X684953Y104968D03*
X695055Y112678D03*
Y115178D03*
X687030Y113090D03*
X694390Y133682D03*
X684520Y152482D03*
X688520D03*
X692520D03*
X686760Y222912D03*
X685600Y364282D03*
X690600D03*
X695600D03*
X685600Y375462D03*
X690600D03*
X695600D03*
X688220Y388362D03*
X685210Y388852D03*
X694920Y388797D03*
X692330Y388751D03*
X692402Y391250D03*
X697220Y404362D03*
X697120Y408262D03*
X695220Y399862D03*
X685270Y408362D03*
Y404262D03*
X692400Y404682D03*
X684077Y414864D03*
X680928Y424313D03*
X687227Y414864D03*
X690376Y421163D03*
Y418013D03*
Y414864D03*
X693526Y427462D03*
X687227Y424313D03*
X690376Y427462D03*
X680928Y414864D03*
Y418013D03*
X684077Y421163D03*
X680928Y427462D03*
X684077Y418013D03*
Y427462D03*
X680928Y421163D03*
X684077Y424313D03*
X687227Y427462D03*
X696676D03*
X693526Y421163D03*
Y424313D03*
X690376D03*
X696676Y421163D03*
Y424313D03*
Y418013D03*
Y436911D03*
X693526Y443210D03*
Y440061D03*
Y436911D03*
X690376Y440061D03*
Y433761D03*
X680928Y436911D03*
Y433761D03*
X693526Y430612D03*
X696676Y440061D03*
Y443210D03*
X684077Y430612D03*
Y440061D03*
X687227Y436911D03*
Y443210D03*
X684077D03*
Y436911D03*
X680928Y443210D03*
X690376Y436911D03*
Y443210D03*
X687227Y440061D03*
X693526Y433761D03*
X696676D03*
X687227Y430612D03*
X690376D03*
X696676D03*
X687227Y433761D03*
X680928Y430612D03*
X687227Y462108D03*
X693526Y452659D03*
Y449510D03*
X696676Y455809D03*
X693526D03*
X690376Y452659D03*
Y458959D03*
X680928Y455809D03*
X693526Y462108D03*
X680928Y449510D03*
X687227D03*
X690376Y462108D03*
X684077Y449510D03*
X680928Y452659D03*
X684077D03*
X687227Y455809D03*
X684077D03*
X680928Y462108D03*
X696676Y449510D03*
Y452659D03*
X690376Y449510D03*
Y455809D03*
X687227Y452659D03*
X693526Y458959D03*
X696676D03*
Y462108D03*
X684077Y458959D03*
Y468407D03*
X687227Y471557D03*
Y474707D03*
Y477856D03*
X684077Y471557D03*
X690376Y465258D03*
X684077D03*
X680928Y471557D03*
Y474707D03*
Y477856D03*
X696676D03*
X684077D03*
X680928Y468407D03*
X693526Y465258D03*
Y471557D03*
X690376Y468407D03*
Y477856D03*
Y471557D03*
X687227Y465258D03*
X690376Y474707D03*
X687227Y468407D03*
X693526D03*
X684077Y474707D03*
X696676Y465258D03*
Y474707D03*
Y468407D03*
X693526Y474707D03*
X694720Y491962D03*
X690720D03*
X683320Y490662D03*
X690580Y482992D03*
X694510Y482942D03*
X686120Y481862D03*
X685220Y508862D03*
X690220Y506362D03*
X685220Y503837D03*
X690220Y508882D03*
X695257Y503847D03*
X690220Y516852D03*
X685220D03*
X690220Y519662D03*
X695220D03*
X689720Y530862D03*
X695220Y530662D03*
X684357Y742345D03*
X683457Y745175D03*
X692784Y1298845D03*
X684555Y1338896D03*
X689605Y1336396D03*
Y1338896D03*
X687105Y1336396D03*
X684555D03*
X687105Y1338896D03*
X689605Y1333896D03*
X687105D03*
X684555D03*
X689605Y1348896D03*
X687105D03*
X689605Y1346396D03*
X687105D03*
X684555Y1341396D03*
Y1343896D03*
Y1346396D03*
Y1348896D03*
X689605Y1341396D03*
Y1343896D03*
X687105Y1341396D03*
Y1343896D03*
X686426Y1360822D03*
X695022Y1361990D03*
X696462Y1386122D03*
X682937Y1384311D03*
X685881Y1384327D03*
Y1387434D03*
X691351Y1380922D03*
X688751D03*
X691240Y1383522D03*
X693851D03*
Y1378322D03*
Y1380922D03*
X691351Y1378322D03*
X688751D03*
X693851Y1386122D03*
X696462Y1378322D03*
Y1383522D03*
Y1380922D03*
X696272Y1404560D03*
X685850Y1390557D03*
X684541Y1399280D03*
X682211Y1400030D03*
X686871D03*
X691777Y1405594D03*
Y1399794D03*
X689577Y1401194D03*
X687511Y1402924D03*
X691777Y1402694D03*
X689677Y1404194D03*
X687511Y1405824D03*
X694596Y1396198D03*
X694129Y1420283D03*
X696754Y1419809D03*
X691129Y1420283D03*
X685015Y1438475D03*
X696940Y1437955D03*
X681899Y1434049D03*
Y1426049D03*
Y1431049D03*
Y1428549D03*
X694129Y1423303D03*
X691129D03*
X696694Y1427949D03*
Y1425449D03*
Y1430449D03*
X696784Y1422614D03*
X683930Y1552562D03*
Y1555062D03*
Y1557562D03*
X689875Y1577913D03*
X692026Y1580490D03*
X697122Y1632667D03*
X683592Y1634844D03*
X697197Y1644667D03*
Y1640667D03*
X697122Y1636667D03*
X689200Y1648843D03*
X689128Y1652262D03*
X692595Y1670862D03*
X687045Y1673362D03*
X701838Y45112D03*
X706370Y46782D03*
X703900Y72112D03*
X701400D03*
X700610Y57782D03*
X713000Y69662D03*
X697720Y58162D03*
X710200Y69662D03*
X706867Y58197D03*
X703100Y58157D03*
X700741Y83050D03*
X712500Y79862D03*
X700500Y74862D03*
X698710Y86035D03*
X705390Y85792D03*
X703000Y84862D03*
X712433Y103308D03*
X706720Y100462D03*
X699220Y102162D03*
X702720D03*
X701220Y104862D03*
X697720D03*
X712733Y117488D03*
Y114588D03*
X698598Y115178D03*
X705685D03*
X702141D03*
X698598Y112678D03*
X705685D03*
X702141D03*
X712290Y106722D03*
X706673Y122762D03*
X703520Y122540D03*
X704880Y133643D03*
X700600Y125309D03*
X705800Y167788D03*
X701926Y166535D03*
X704770Y179599D03*
Y182999D03*
X705800Y171188D03*
X701926Y178346D03*
Y184252D03*
Y172441D03*
X704770Y182999D03*
Y179599D03*
Y191410D03*
Y194810D03*
Y203221D03*
X701926Y190157D03*
Y196063D03*
Y201968D03*
X704770Y194810D03*
Y191410D03*
Y218432D03*
Y215032D03*
Y206621D03*
X701926Y207874D03*
Y213779D03*
X704770Y218432D03*
Y206621D03*
Y215032D03*
Y203221D03*
X701926Y219685D03*
X700600Y364282D03*
X705600D03*
X710600D03*
X709000Y354000D03*
X700600Y375462D03*
X705600D03*
X709400Y378200D03*
X713220Y378362D03*
X709160Y386730D03*
X707400Y396200D03*
X713220Y399862D03*
X705195Y408362D03*
Y404262D03*
X705780Y411022D03*
X712770Y406822D03*
X706125Y421163D03*
X702975Y414864D03*
X706125Y418013D03*
X712424Y424313D03*
X699825Y427462D03*
X699826Y414864D03*
X699825Y424313D03*
X709274Y436911D03*
X706125Y440061D03*
Y436911D03*
X699825Y440061D03*
Y436911D03*
X712424Y443210D03*
Y440061D03*
Y436911D03*
Y430612D03*
X709274Y440061D03*
Y443210D03*
X706125D03*
X699825D03*
X709274Y433761D03*
X712424D03*
X699825D03*
X706125D03*
X699825Y430612D03*
X706125Y462108D03*
X709274D03*
X712424D03*
Y455809D03*
X709274D03*
X706125D03*
Y452659D03*
X699825Y455809D03*
Y452659D03*
X712424D03*
Y449510D03*
X709274D03*
X699825D03*
X706125D03*
X709274Y452659D03*
X699825Y458959D03*
X706125D03*
X709274D03*
X712424D03*
X699825Y462108D03*
X709274Y474707D03*
Y471557D03*
Y465258D03*
Y468407D03*
X712424Y474707D03*
Y468407D03*
Y465258D03*
X709274Y477856D03*
X699825Y468407D03*
X706125Y471557D03*
Y468407D03*
X699825Y471557D03*
Y474707D03*
X706125Y477856D03*
X699825Y465258D03*
X712424Y471557D03*
X705720Y488862D03*
X703220Y490362D03*
X705720Y484862D03*
X706125Y481006D03*
X711220Y503842D03*
X705220D03*
Y508862D03*
X711220Y508882D03*
X710720Y521362D03*
X705220D03*
Y516852D03*
X698600Y530700D03*
X710940Y591172D03*
X698602Y580536D03*
X705240Y594020D03*
X702740D03*
X712060Y638542D03*
X708680Y638812D03*
X708310Y646032D03*
X704320Y645262D03*
X701917Y742865D03*
X704000Y740862D03*
X700500Y745862D03*
X703545Y745907D03*
X703755Y1290545D03*
X711720Y1286162D03*
X707720Y1290162D03*
X705720Y1286662D03*
X708795Y1303701D03*
X704795Y1294559D03*
X707320Y1301162D03*
X708137Y1336396D03*
Y1338896D03*
X703087Y1336396D03*
X705587D03*
Y1338896D03*
X703087D03*
X708137Y1333896D03*
X705587D03*
X703087D03*
Y1346396D03*
X705587D03*
X703087Y1348896D03*
X705587D03*
X708137Y1341396D03*
Y1343896D03*
X705587Y1341396D03*
X703087D03*
Y1343896D03*
X705587D03*
X708137Y1348896D03*
Y1346396D03*
X698094Y1361947D03*
X706239Y1360822D03*
X712060Y1360815D03*
X699062Y1380922D03*
Y1383522D03*
Y1378322D03*
X707480Y1384311D03*
X710080D03*
X707480Y1387418D03*
X710080D03*
X701662Y1380922D03*
Y1383522D03*
Y1378322D03*
X699062Y1386122D03*
X701662D03*
X712680Y1384311D03*
Y1387418D03*
X709493Y1399757D03*
Y1394157D03*
X712880Y1390525D03*
X711963Y1399757D03*
Y1394157D03*
X701330Y1395195D03*
Y1397695D03*
X704446Y1403476D03*
X699262Y1413970D03*
X704568Y1414119D03*
X701830Y1407326D03*
X711620Y1409386D03*
X707620Y1406694D03*
Y1409660D03*
X699754Y1419809D03*
X706680Y1437535D03*
X701730Y1437855D03*
X711440Y1436905D03*
X699694Y1427949D03*
Y1425449D03*
Y1430449D03*
X699784Y1422614D03*
X702112Y1583683D03*
Y1571683D03*
Y1575683D03*
Y1579683D03*
X704497Y1598927D03*
X702112Y1587683D03*
Y1591683D03*
Y1595683D03*
X711350Y1590720D03*
X711780Y1614590D03*
X704370Y1604580D03*
X709111Y1618842D03*
X705516Y1620296D03*
X710540Y1636070D03*
X697595Y1658862D03*
X704433Y1657964D03*
X697595Y1662862D03*
X697770Y1680810D03*
X702462Y1673258D03*
X697730Y1677460D03*
X717313Y-27626D03*
X714015Y-27612D03*
X720308Y-26403D03*
X723041Y-13200D03*
Y-19800D03*
Y-23200D03*
Y-9800D03*
Y-13200D03*
Y-9800D03*
Y-19800D03*
Y-23200D03*
X725537Y-23978D03*
Y-19022D03*
Y-13978D03*
Y-9022D03*
X714015Y-21457D03*
X717313Y-21471D03*
Y-17597D03*
X717298Y-15082D03*
X714015Y-17583D03*
X714030Y-15068D03*
X714015Y-11428D03*
X717313Y-11442D03*
X717298Y-25111D03*
X714030Y-25097D03*
X720308Y-16374D03*
X717313Y-7568D03*
X717298Y-5053D03*
X714015Y-7554D03*
X714030Y-5039D03*
X720308Y-6345D03*
X722580Y49182D03*
X728980Y39872D03*
X717320Y44062D03*
X729293Y58062D03*
X724644Y58362D03*
X719949Y58862D03*
X715990Y69662D03*
X725740Y69580D03*
X721990Y69762D03*
X718900Y69662D03*
X727700Y60562D03*
X728591Y71960D03*
X722415Y77862D03*
X718425Y77882D03*
X728090Y75132D03*
X719100Y85262D03*
X728028Y101968D03*
X728023Y98058D03*
X727518Y90984D03*
X728028Y105468D03*
X715933Y117488D03*
Y114588D03*
X728733Y132088D03*
Y129288D03*
X720433Y135088D03*
X717433D03*
X728733Y126388D03*
X719933Y124488D03*
X723133D03*
X724133Y141288D03*
X715940Y157362D03*
X718213Y159241D03*
X720633Y160788D03*
X716698Y185687D03*
Y177087D03*
Y173687D03*
X719194Y172909D03*
X714202D03*
X719194Y177865D03*
X714202D03*
X719194Y184909D03*
X714202D03*
X716698Y185687D03*
Y173687D03*
Y177087D03*
Y197187D03*
Y200587D03*
Y189087D03*
X719194Y189865D03*
X714202D03*
X719194Y196409D03*
X714202D03*
X719194Y201365D03*
X714202D03*
X716698Y197187D03*
Y200587D03*
Y189087D03*
Y209021D03*
Y212421D03*
X719194Y208243D03*
X714202D03*
X719194Y213199D03*
X714202D03*
X716698Y209021D03*
Y212421D03*
X717020Y220862D03*
X719720Y220142D03*
X727720Y356362D03*
X724897Y353887D03*
X721989Y351234D03*
X715600Y375462D03*
X718220Y388362D03*
X718720Y381892D03*
X715220Y404362D03*
X715120Y408262D03*
X723195Y408362D03*
Y404262D03*
X725220Y399862D03*
X721873Y427462D03*
X725022D03*
X728172Y418013D03*
X725022Y414864D03*
X718723Y418013D03*
X715574Y427462D03*
X728172Y421163D03*
X718723Y414864D03*
X725022Y424313D03*
X721873D03*
X725022Y421163D03*
X728172Y427462D03*
X725022Y418013D03*
X718723Y427462D03*
Y424313D03*
Y421163D03*
X715574Y424313D03*
Y421163D03*
Y418013D03*
X718723Y436911D03*
X721873Y433761D03*
Y436911D03*
Y440061D03*
Y430612D03*
X718723Y433761D03*
Y440061D03*
X725022Y436911D03*
Y433761D03*
X728172D03*
X715574D03*
X718723Y430612D03*
X715574D03*
X725022D03*
X728172Y436911D03*
X715574D03*
Y440061D03*
Y443210D03*
X728172D03*
Y430612D03*
X725022Y440061D03*
X718723Y443210D03*
X721873D03*
X725022D03*
X728172Y440061D03*
Y455809D03*
Y458959D03*
X718723Y455809D03*
X721873Y458959D03*
X715574D03*
X728172Y449510D03*
X721873Y452659D03*
X725022D03*
X728172D03*
X715574Y462108D03*
X725022Y458959D03*
X721873Y455809D03*
X725022Y462108D03*
X718723Y452659D03*
X715574Y449510D03*
Y452659D03*
Y455809D03*
X728172Y462108D03*
X718723Y449510D03*
X721873D03*
X725022D03*
X718723Y458959D03*
X721873Y462108D03*
X725022Y468407D03*
X721873Y465258D03*
Y477856D03*
X725022D03*
X718723Y468407D03*
X715574Y474707D03*
Y471557D03*
Y468407D03*
Y465258D03*
X718723Y474707D03*
Y471557D03*
X728172Y477856D03*
X721873Y471557D03*
X725022D03*
X718723Y465258D03*
X728172D03*
X725022Y474707D03*
X728172Y468407D03*
X721873Y474707D03*
Y468407D03*
X728172Y474707D03*
Y471557D03*
X725022Y465258D03*
X718723Y477856D03*
X725132Y481116D03*
X713820Y488762D03*
Y484662D03*
X728272Y481006D03*
X729220Y503842D03*
X723220D03*
X717220D03*
X714000Y496132D03*
X723120Y525362D03*
X728220Y521362D03*
X717220D03*
X722720D03*
X717296Y525407D03*
X723220Y516852D03*
X729220D03*
X717220D03*
X729200Y588952D03*
X729328Y583076D03*
X729295Y586113D03*
X725207Y579371D03*
X722707D03*
X715860Y585540D03*
X714320Y597462D03*
X715420Y639162D03*
X719190Y646642D03*
X717720Y643262D03*
X715220D03*
X723340Y642922D03*
X714087Y745865D03*
X720697Y765862D03*
X723460Y1245632D03*
X713836Y1283689D03*
X714720Y1286162D03*
X723054Y1333896D03*
X725604D03*
X728104D03*
X725604Y1338896D03*
X723054Y1336396D03*
X725604D03*
X728104Y1338896D03*
Y1336396D03*
X723054Y1338896D03*
X725604Y1346396D03*
X728104D03*
X725604Y1348896D03*
X728104D03*
X725604Y1343896D03*
Y1341396D03*
X728104Y1343896D03*
Y1341396D03*
X723054Y1348896D03*
Y1346396D03*
Y1343896D03*
Y1341396D03*
X724969Y1360822D03*
X714560Y1360815D03*
X717060D03*
X729443Y1361224D03*
X726694Y1381583D03*
Y1378983D03*
X715280Y1384311D03*
X717880D03*
X715280Y1387418D03*
X721080Y1384311D03*
X724024Y1384327D03*
Y1387434D03*
X728044Y1384083D03*
X729294Y1381583D03*
Y1378983D03*
X715480Y1390525D03*
X723993Y1390557D03*
X714393Y1399757D03*
Y1394157D03*
X725654Y1405824D03*
Y1402924D03*
X727720Y1401194D03*
X727820Y1404194D03*
X718024Y1399280D03*
X722684D03*
X720354Y1400030D03*
X725014D03*
X714455Y1411554D03*
X715762Y1408887D03*
X714019Y1406619D03*
X717300Y1547370D03*
X715792Y1567461D03*
X720370Y1566910D03*
X723520Y1561604D03*
X724712Y1566820D03*
X716612Y1584635D03*
X717152Y1570093D03*
X724465Y1580092D03*
X722465Y1582092D03*
X726465D03*
X718230Y1600372D03*
X724465Y1590950D03*
X722465Y1588950D03*
X726465D03*
X725378Y1614503D03*
X719770Y1614590D03*
X715780D03*
X723542Y1612702D03*
X721488Y1610945D03*
X725910Y1611900D03*
X716688Y1610055D03*
X719168Y1612016D03*
X722040Y1623970D03*
X713791Y1629816D03*
X714203Y1639776D03*
X721345Y1647300D03*
X716140Y1649895D03*
X718195Y1647300D03*
X714203Y1642926D03*
X729150Y1641690D03*
X726830Y1655380D03*
X714071Y1663842D03*
X724500Y1676500D03*
Y1680400D03*
X744987Y49062D03*
X742840Y39832D03*
X736790D03*
X745130Y69508D03*
X738043D03*
X730957D03*
X731330Y60712D03*
X745474Y57932D03*
X733642Y58062D03*
X741377Y57932D03*
X737595D03*
X732793Y71436D03*
X736193D03*
X742620Y71762D03*
X735880Y60662D03*
X730820Y84062D03*
X740819Y82362D03*
X737623Y98858D03*
X734523Y98758D03*
X735733Y111988D03*
X738600Y136600D03*
X736060Y145532D03*
X745725Y167537D03*
X734220Y238362D03*
X745685Y265322D03*
X744247Y312598D03*
X742090Y356082D03*
X735600Y351400D03*
X736220Y380787D03*
X742720Y380262D03*
X738220Y388362D03*
X742160Y396452D03*
X738220Y383862D03*
X737621Y411714D03*
X743720Y404362D03*
X743820Y408262D03*
X745720Y399862D03*
X735220Y410842D03*
X735745Y408362D03*
Y404262D03*
X733720Y399862D03*
X734471Y418013D03*
X731322Y427462D03*
Y418013D03*
X734471Y421163D03*
X731322Y424313D03*
X734471D03*
X731322Y414864D03*
Y433761D03*
Y430612D03*
X734471Y436911D03*
X731322D03*
X734471Y443210D03*
X737621D03*
X731322D03*
Y455809D03*
X737621Y458959D03*
X731322D03*
Y462108D03*
X734471Y452659D03*
X731322D03*
Y449510D03*
X734471Y458959D03*
X731322Y465258D03*
Y477856D03*
X737621Y471557D03*
X734471Y468407D03*
X731322D03*
X731321Y474707D03*
X731322Y471557D03*
X740740Y473822D03*
X737621Y481006D03*
X734471D03*
X745220Y503842D03*
X730070Y506212D03*
X744630Y506529D03*
X735220Y503842D03*
X735430Y516862D03*
X745220Y516852D03*
X730220Y523362D03*
X740840Y521982D03*
X745220Y530362D03*
X736480Y531722D03*
X738980D03*
X733922Y531712D03*
X733117Y580071D03*
Y582571D03*
X733134Y585672D03*
X736710Y603842D03*
Y607242D03*
X739206Y608020D03*
Y603064D03*
X735620Y613862D03*
X730690Y655532D03*
X744538Y746524D03*
X737609Y744282D03*
X730889Y746834D03*
X740820Y741762D03*
X737299Y766887D03*
X737784Y1360017D03*
X730752Y1384080D03*
X731794Y1381583D03*
Y1378983D03*
X732238Y1388343D03*
X738810Y1396665D03*
X741540Y1396585D03*
X739170Y1405655D03*
X741670Y1405675D03*
X729920Y1405594D03*
X732226Y1396212D03*
X729920Y1399794D03*
Y1402694D03*
X738170Y1414185D03*
X740760Y1414165D03*
X733336Y1568341D03*
Y1565341D03*
Y1559341D03*
Y1562341D03*
X730336Y1559341D03*
Y1562341D03*
X745336D03*
Y1559341D03*
Y1565341D03*
Y1568341D03*
X742336Y1562341D03*
Y1559341D03*
Y1565341D03*
Y1568341D03*
X739336Y1562341D03*
Y1559341D03*
Y1565341D03*
Y1568341D03*
X736336D03*
Y1565341D03*
Y1559341D03*
Y1562341D03*
X733336Y1574341D03*
Y1571341D03*
X745336Y1574341D03*
Y1571341D03*
X742336Y1574341D03*
Y1571341D03*
X739336Y1574341D03*
Y1571341D03*
X736336D03*
Y1574341D03*
X730282Y1580391D03*
X741382Y1585251D03*
Y1580121D03*
X735882Y1580391D03*
X730282Y1590651D03*
Y1585521D03*
X735882Y1590651D03*
X741382Y1590691D03*
X732504Y1600321D03*
Y1597321D03*
X744504D03*
Y1600321D03*
X741504Y1597321D03*
Y1600321D03*
X735504Y1597321D03*
Y1600321D03*
X738504Y1597321D03*
Y1600321D03*
X744504Y1609521D03*
Y1612521D03*
X741504Y1609521D03*
X738504D03*
X735504D03*
X741504Y1612521D03*
X738504D03*
X735504D03*
X732504Y1603321D03*
Y1606321D03*
X744504Y1603321D03*
Y1606321D03*
X741504Y1603321D03*
Y1606321D03*
X738504Y1603321D03*
X735504D03*
X738504Y1606321D03*
X735504D03*
X744800Y1664840D03*
X737080Y1655820D03*
X735080Y1662980D03*
X742655Y1682362D03*
Y1678362D03*
X732705Y1669450D03*
X732895Y1737108D03*
X758606Y23797D03*
X747487Y49062D03*
X754620Y51602D03*
X758620D03*
X752720Y59002D03*
X749477Y57932D03*
X755700Y59942D03*
Y62442D03*
X758200Y59942D03*
Y62442D03*
X760700Y59942D03*
Y62442D03*
X747487Y71429D03*
X754219Y75707D03*
X757693Y100653D03*
Y96423D03*
X750033Y92888D03*
Y89988D03*
X754633Y108288D03*
Y105288D03*
X748033Y116288D03*
X747230Y108572D03*
X760390Y111810D03*
X762198Y129684D03*
Y126684D03*
X762172Y123898D03*
X751220Y137864D03*
X758110Y172636D03*
X747200Y251500D03*
X761720Y283262D03*
X748085Y278942D03*
X758360Y276122D03*
X757150Y280592D03*
X758720Y283262D03*
X759920Y280562D03*
X754290Y286632D03*
X755200Y296062D03*
X755305Y298847D03*
X748820Y284562D03*
X758390Y295450D03*
X748498Y309640D03*
X759637Y311585D03*
X757936Y303908D03*
X760670Y317432D03*
X747554Y384962D03*
X757430Y408212D03*
X759940Y438232D03*
X750290Y462162D03*
X758420Y447662D03*
X756642Y496522D03*
Y501744D03*
X751220Y516852D03*
X759790Y525522D03*
X751220Y530362D03*
X757020Y530462D03*
X759820D03*
X754220D03*
X753137Y766625D03*
X762345Y1284542D03*
Y1287542D03*
Y1290542D03*
X762205Y1293272D03*
X757779Y1390645D03*
X757542Y1420684D03*
X755420Y1426262D03*
Y1422862D03*
X748336Y1562341D03*
Y1559341D03*
Y1565341D03*
Y1568341D03*
X751336D03*
Y1565341D03*
Y1559341D03*
Y1562341D03*
X748336Y1574341D03*
Y1571341D03*
X760112Y1579183D03*
X760152Y1583183D03*
X760112Y1592183D03*
Y1587183D03*
X747504Y1600321D03*
Y1609521D03*
Y1612521D03*
X750504Y1609521D03*
X747504Y1603321D03*
Y1606321D03*
X761716Y1661194D03*
X761770Y1695347D03*
X755859Y1686090D03*
X759859D03*
X755183Y1709850D03*
X759359Y1729520D03*
X752875Y1726670D03*
X752895Y1737108D03*
X765606Y44894D03*
X769474Y75360D03*
X765858Y87340D03*
X762368Y84088D03*
X769284Y103895D03*
X767061Y99959D03*
X767045Y95960D03*
X767028Y91490D03*
X776730Y117479D03*
X773943Y114633D03*
X771131Y111788D03*
X769775Y107977D03*
X766769Y140138D03*
X773420Y143462D03*
X771774Y167518D03*
X772328Y153728D03*
X771426Y158026D03*
X763320Y264892D03*
X771630Y258102D03*
X762420Y280562D03*
X777420Y277962D03*
X773220Y296262D03*
X769789Y296231D03*
X777467Y296315D03*
X769860Y302462D03*
X772866Y311558D03*
X771377Y314139D03*
X777283Y320892D03*
X777420Y354962D03*
X771960Y375162D03*
X767960Y369662D03*
X776100Y375100D03*
X776000Y369662D03*
X764000D03*
X766195Y393212D03*
Y403212D03*
Y413212D03*
X768910Y403260D03*
X766195Y418212D03*
Y423212D03*
X768701Y418662D03*
X765315Y454862D03*
Y459862D03*
X765360Y475412D03*
X765315Y464862D03*
X765335Y469552D03*
X772364Y475062D03*
X772365Y469862D03*
X765315Y479862D03*
Y488862D03*
X772365D03*
X776170Y493422D03*
X766510Y493452D03*
X765386Y483572D03*
X773530Y507062D03*
X765521Y525364D03*
X769220Y530362D03*
X765720D03*
X772220D03*
X777020D03*
X772020Y746562D03*
X774384Y744088D03*
X762562Y746444D03*
X769921Y742095D03*
X767421D03*
X764921D03*
X775317Y764025D03*
X763747Y764335D03*
X769337Y760775D03*
X762617Y758885D03*
X765345Y1284542D03*
X768335Y1284612D03*
X765345Y1287542D03*
Y1290542D03*
X768335Y1287612D03*
Y1290612D03*
X765205Y1293272D03*
X768195Y1293342D03*
X778005Y1294092D03*
X768520Y1379962D03*
Y1384062D03*
Y1375462D03*
X768620Y1392762D03*
Y1397262D03*
X775375Y1403561D03*
X767820Y1410262D03*
Y1414762D03*
X763152Y1581893D03*
Y1577893D03*
Y1573793D03*
X773952Y1580493D03*
X768714Y1571203D03*
X770252Y1587268D03*
X763152Y1590893D03*
Y1594893D03*
X774052Y1590293D03*
X776052Y1611893D03*
X764920Y1695347D03*
X766880Y1689020D03*
X763359Y1729520D03*
X772208Y1731911D03*
X785095Y49388D03*
X785180Y120947D03*
X792680D03*
X790180D03*
X787680D03*
X783940Y118637D03*
X786440D03*
X788940D03*
X781440D03*
X782553Y150031D03*
Y152531D03*
X779893Y147521D03*
Y150021D03*
X785135Y281822D03*
Y267822D03*
X780820Y278262D03*
X785135Y274822D03*
X785200Y271400D03*
X780617Y296345D03*
X794220Y296062D03*
X785220Y284762D03*
X792943Y312642D03*
X784415Y313734D03*
X779120Y306162D03*
X793820Y304962D03*
X779120Y303410D03*
Y308755D03*
X794600Y360600D03*
X785000Y355000D03*
X779920Y354962D03*
X782420D03*
X790120Y354862D03*
X792620D03*
X787600Y354900D03*
X787925Y387900D03*
X791075Y388000D03*
X781195Y393212D03*
X787720Y408362D03*
X781195Y413212D03*
Y423212D03*
X785560Y417902D03*
X781195Y418212D03*
X791590Y417050D03*
X788120Y422942D03*
X791040Y422892D03*
X793660Y422842D03*
X785720Y427862D03*
X789230Y414942D03*
X780020Y438287D03*
X781410Y431822D03*
X780020Y441437D03*
Y445287D03*
X791582Y435352D03*
X781205Y454402D03*
X780315Y459862D03*
X780340Y468982D03*
Y474862D03*
X786220Y464862D03*
X780315D03*
X793220Y493362D03*
X781170Y493422D03*
X793875Y483262D03*
X778670Y493422D03*
X793673Y512862D03*
X783400Y511902D03*
X789720Y589862D03*
X785220Y581362D03*
X789720Y587362D03*
X792720Y589862D03*
X789720Y581862D03*
X791720Y593862D03*
X793720Y595862D03*
X783100Y593582D03*
X794720Y617862D03*
X783507Y761875D03*
X794157Y761295D03*
X782515Y766702D03*
X791140Y761693D03*
X792045Y1284542D03*
Y1290542D03*
Y1287542D03*
X791905Y1293272D03*
X788225Y1388683D03*
X791260Y1388662D03*
X790380Y1432132D03*
X784352Y1568293D03*
Y1565293D03*
Y1559293D03*
Y1562293D03*
X781352Y1568293D03*
Y1565293D03*
Y1559293D03*
Y1562293D03*
X793352D03*
Y1559293D03*
Y1565293D03*
Y1568293D03*
X790352Y1562293D03*
Y1559293D03*
Y1565293D03*
Y1568293D03*
X787352D03*
Y1565293D03*
Y1559293D03*
Y1562293D03*
X784352Y1574293D03*
Y1571293D03*
X781352Y1574293D03*
Y1571293D03*
X793352Y1574293D03*
Y1571293D03*
X790352Y1574293D03*
Y1571293D03*
X787352D03*
Y1574293D03*
X788079Y1580393D03*
X782479D03*
X793579D03*
X788079Y1590653D03*
X782479D03*
Y1585523D03*
X793579Y1590653D03*
Y1585523D03*
X785052Y1600693D03*
Y1597693D03*
X782052D03*
Y1600693D03*
X794052D03*
X788052D03*
X791052D03*
X794052Y1597693D03*
X788052D03*
X791052D03*
X785052Y1607793D03*
X782052D03*
X779052D03*
X785052Y1611893D03*
X782052D03*
X779052D03*
X794052Y1607793D03*
X791052D03*
X788052D03*
X794052Y1611893D03*
X788052D03*
X791052D03*
X785052Y1603693D03*
X782052D03*
X794052D03*
X788052D03*
X791052D03*
X792208Y1731911D03*
X805095Y49388D03*
X797443Y271469D03*
X806300Y279662D03*
X809700Y273562D03*
X808800Y267900D03*
X810920Y280062D03*
X795190Y298572D03*
X797924Y298358D03*
X798620Y312773D03*
X806450Y310362D03*
X803620Y302962D03*
X805870Y304812D03*
X799720Y300462D03*
X795920Y312662D03*
X803280Y354982D03*
X800646Y354921D03*
X809800Y360600D03*
X802200D03*
X806588Y351097D03*
X795220Y354862D03*
X806000Y360600D03*
X798400D03*
X805910Y355012D03*
X797900Y354800D03*
X799800Y368700D03*
X810781Y372615D03*
X803150Y408512D03*
X795600Y402500D03*
X795520Y398212D03*
X799458Y431217D03*
X802010Y439940D03*
X795320Y439862D03*
X805720Y432902D03*
X795320Y444862D03*
X810860Y454862D03*
X795320D03*
Y449862D03*
X810860Y459862D03*
X795320D03*
X810860Y449862D03*
X795370Y474862D03*
X798990D03*
X795320Y464862D03*
X810860D03*
X810815Y469862D03*
X807220Y493362D03*
X801940Y485932D03*
X804510Y486122D03*
X809510D03*
X799230Y485922D03*
X802790Y495652D03*
X805470Y510522D03*
X807640Y506672D03*
X808100Y509900D03*
X797420Y512503D03*
X805445Y587582D03*
X798720Y585362D03*
X810720Y586862D03*
X811143Y605265D03*
X798220Y597362D03*
X808860Y603802D03*
X807945Y594362D03*
X803220D03*
X797200Y599883D03*
X797720Y617862D03*
X795720Y614862D03*
X796702Y761195D03*
X799637Y763625D03*
X799577Y760985D03*
X807000Y757562D03*
X798035Y1284612D03*
X795045Y1284542D03*
X798035Y1290612D03*
Y1287612D03*
X795045Y1290542D03*
Y1287542D03*
X797895Y1293342D03*
X794905Y1293272D03*
X809210Y1343062D03*
X804100Y1435010D03*
X800000Y1431100D03*
X799352Y1562293D03*
Y1559293D03*
Y1565293D03*
Y1568293D03*
X796352Y1562293D03*
Y1559293D03*
Y1565293D03*
Y1568293D03*
X799352Y1574293D03*
Y1571293D03*
X796352Y1574293D03*
Y1571293D03*
X804652Y1581793D03*
Y1573793D03*
Y1597793D03*
Y1585993D03*
X799152Y1586507D03*
X804652Y1589793D03*
X797052Y1607793D03*
X804652Y1609793D03*
X825095Y49388D03*
X819114Y115223D03*
X827114D03*
X823114D03*
X821118Y134632D03*
X825698Y139062D03*
X824498Y145198D03*
X813900Y269698D03*
X816220Y277162D03*
X827403Y286625D03*
X816420Y287062D03*
X813293D03*
X826300Y311962D03*
X823800D03*
X813855Y354008D03*
X820936Y356956D03*
X821164Y372312D03*
X818000Y378800D03*
X813210Y374292D03*
X815710D03*
X825003Y397276D03*
X819220Y397664D03*
X824980Y405260D03*
Y409260D03*
Y413260D03*
X823600Y421194D03*
X815310Y440100D03*
X818500Y451700D03*
X816500Y476800D03*
X825100Y468900D03*
X824860Y464862D03*
X820720Y493862D03*
X822415Y479600D03*
X814305Y499503D03*
X819320Y502347D03*
X821720Y519082D03*
Y515082D03*
Y523082D03*
X815040Y590772D03*
X820220Y586862D03*
X814220Y582530D03*
X823720Y594862D03*
X820470Y595112D03*
X815120Y593582D03*
X820613Y744641D03*
X823589Y746924D03*
X814800Y760922D03*
X822442Y762369D03*
X822374Y757039D03*
X814770Y763874D03*
X815789Y1008845D03*
X814234Y1340465D03*
X826090Y1334362D03*
Y1339362D03*
Y1329362D03*
Y1344362D03*
X820920Y1344342D03*
X818420D03*
X823352Y1565293D03*
Y1562293D03*
Y1559293D03*
Y1568293D03*
X826352Y1565293D03*
Y1562293D03*
Y1559293D03*
Y1568293D03*
X823352Y1571293D03*
Y1574293D03*
X826352Y1571293D03*
Y1574293D03*
X824479Y1580393D03*
X815652Y1582570D03*
Y1573793D03*
X813352Y1590893D03*
X812652Y1593793D03*
X824479Y1590653D03*
Y1585523D03*
X824052Y1597693D03*
Y1600693D03*
X827052D03*
Y1597693D03*
X815551Y1593793D03*
X818652Y1590444D03*
X812652Y1605793D03*
X824052Y1611893D03*
Y1607793D03*
Y1603693D03*
X827052Y1611893D03*
Y1607793D03*
Y1603693D03*
X821052Y1611893D03*
Y1607793D03*
X818052Y1611893D03*
X812652Y1601793D03*
X812208Y1731911D03*
X840001Y6800D03*
D03*
X842497Y6022D03*
X834273Y2374D03*
X834258Y4889D03*
X830975Y2388D03*
X830990Y4903D03*
X837268Y3597D03*
X840001Y10200D03*
Y20200D03*
Y16800D03*
Y20200D03*
Y16800D03*
Y10200D03*
X842497Y16022D03*
Y20978D03*
Y10978D03*
X834273Y22432D03*
X830975Y22446D03*
Y8543D03*
X834273Y8529D03*
Y12403D03*
X834258Y14918D03*
X830975Y12417D03*
X830990Y14932D03*
X830975Y18572D03*
X834273Y18558D03*
X837268Y13626D03*
X834258Y24947D03*
X830990Y24961D03*
X837268Y23655D03*
X836126Y62681D03*
X828600Y61752D03*
X837791Y85186D03*
X837250Y93221D03*
X831297Y104206D03*
X842864Y110296D03*
X831114Y115223D03*
X839360Y114862D03*
X835114Y115223D03*
X829114Y150273D03*
Y147123D03*
X836502Y161553D03*
X828145Y160362D03*
X838220Y163862D03*
X835220D03*
X837320Y175112D03*
X842720Y181360D03*
X837975Y210064D03*
X830339Y228143D03*
X837500Y229642D03*
X829680Y264580D03*
X836210Y272452D03*
X829720Y277562D03*
X829800Y271562D03*
X839450Y272662D03*
X835400Y268800D03*
X829620Y280345D03*
X829820Y275045D03*
X829320Y296762D03*
X834400Y283862D03*
X834900Y293462D03*
X829720Y292762D03*
X839860Y294702D03*
X827620Y302962D03*
X830417Y311865D03*
X828222Y359960D03*
X835471Y363003D03*
X843133Y366158D03*
X833300Y386500D03*
X836300Y418800D03*
X832400Y427100D03*
X840400Y418900D03*
X839200Y434300D03*
X841300Y446800D03*
X831720Y457700D03*
X839640Y449612D03*
X832700Y446800D03*
X830600Y449200D03*
X841200Y456500D03*
X842600Y477200D03*
X842341Y474241D03*
X832720Y494862D03*
X829720D03*
X841795Y492862D03*
X830870Y480010D03*
X829745Y502082D03*
X832370Y525849D03*
X843287Y527817D03*
X834635Y515447D03*
X830480Y527817D03*
X841461Y525849D03*
X840990Y529786D03*
X828009Y587913D03*
X829230Y582772D03*
X831700Y596962D03*
X831530Y651932D03*
X830587Y741205D03*
X833120Y743392D03*
X838587Y766825D03*
X836847Y762495D03*
X841827Y766795D03*
X837127Y758976D03*
X829420Y758422D03*
X841997Y773085D03*
X838020Y1232432D03*
X828799Y1336870D03*
X828910Y1331756D03*
X832090Y1331862D03*
Y1336862D03*
X828910Y1341725D03*
X832090Y1341862D03*
X829352Y1565293D03*
Y1562293D03*
Y1559293D03*
Y1568293D03*
X832352D03*
Y1565293D03*
Y1559293D03*
Y1562293D03*
X835352Y1568293D03*
Y1565293D03*
Y1559293D03*
Y1562293D03*
X838352Y1568293D03*
Y1565293D03*
Y1559293D03*
Y1562293D03*
X841352Y1568293D03*
Y1565293D03*
Y1559293D03*
Y1562293D03*
X829352Y1574293D03*
Y1571293D03*
X832352D03*
Y1574293D03*
X835352Y1571293D03*
Y1574293D03*
X838352Y1571293D03*
Y1574293D03*
X841352Y1571293D03*
Y1574293D03*
X830079Y1580393D03*
X835579D03*
X843652Y1584539D03*
X833052Y1597693D03*
X836052D03*
X830079Y1590653D03*
X835579D03*
X833052Y1600693D03*
X836052D03*
X835579Y1585523D03*
X830052Y1600693D03*
Y1597693D03*
X841152Y1586507D03*
X833052Y1603693D03*
X836052D03*
X833052Y1607793D03*
Y1611893D03*
X836052Y1607793D03*
Y1611893D03*
X830052D03*
Y1607793D03*
Y1603693D03*
X839052Y1607793D03*
X832208Y1731911D03*
X845095Y49388D03*
X858629Y60293D03*
X843855Y87711D03*
X854577Y99651D03*
X854107Y91232D03*
X850280Y113852D03*
X847660Y113962D03*
X853100Y113762D03*
X856776Y129268D03*
X846846Y127064D03*
X854100Y132972D03*
X854220Y135862D03*
Y129362D03*
X854200Y138562D03*
X851895Y160262D03*
X848745Y160187D03*
X848709Y156752D03*
X848360Y182872D03*
X845720Y181362D03*
X849710Y212062D03*
X845220Y216532D03*
X855858Y212425D03*
X855933Y215375D03*
X854706Y229878D03*
X852206D03*
X853828Y265057D03*
X854333Y276117D03*
X854338Y280027D03*
Y283527D03*
X853828Y269043D03*
X850133Y271049D03*
X852800Y288562D03*
X853200Y297462D03*
X850093Y286625D03*
X855480Y299692D03*
X856700Y304862D03*
X848000Y374622D03*
X851396Y369614D03*
X859734Y373032D03*
X846040Y399210D03*
X844200Y418800D03*
X847830Y443892D03*
X843810Y453322D03*
X851606Y447927D03*
X844210Y455902D03*
X846700Y473000D03*
Y476900D03*
X855200D03*
X848710Y505641D03*
X858600Y511130D03*
X857195Y522162D03*
X859054Y583752D03*
X845523Y582126D03*
X856698Y594011D03*
X856520Y751262D03*
X853200Y751062D03*
X859450Y750462D03*
X854687Y761685D03*
X844957Y763065D03*
X854620Y1242125D03*
X854237Y1250358D03*
X846652Y1581793D03*
Y1573793D03*
X854652Y1577793D03*
X857652Y1582570D03*
Y1573793D03*
X846652Y1597793D03*
X855352Y1590893D03*
X854652Y1593793D03*
X846652Y1585993D03*
X857551Y1593793D03*
X846652Y1589793D03*
X854652Y1605793D03*
Y1601793D03*
X846652Y1609793D03*
X852208Y1731911D03*
X865095Y49388D03*
X862930Y70072D03*
X866330D03*
X876124Y66072D03*
X868187Y72006D03*
X860937Y71877D03*
X861350Y61672D03*
X876124Y86072D03*
Y106072D03*
Y126072D03*
X862452Y151590D03*
X874295Y163862D03*
X867620Y154362D03*
X871145Y163862D03*
X863488Y176332D03*
X871580Y183370D03*
X871980Y199500D03*
X864859Y187110D03*
X871890Y196740D03*
X875543Y266447D03*
X860833Y276817D03*
X863933Y276917D03*
X875543Y269347D03*
X862043Y290047D03*
X874243Y287047D03*
X872320Y304936D03*
X869820D03*
X867320D03*
X864820D03*
X867922Y376450D03*
X875922Y379793D03*
X860531Y375826D03*
X870700Y382415D03*
Y390620D03*
Y394620D03*
Y386476D03*
Y398620D03*
Y402581D03*
X871320Y416752D03*
X870513Y414276D03*
X860574Y445404D03*
X861080Y459742D03*
X870360Y493042D03*
X862620Y503162D03*
Y499062D03*
Y507162D03*
X865290Y499032D03*
X865810Y521862D03*
X860345Y513062D03*
X864680Y751582D03*
X874155Y756993D03*
X864700Y778300D03*
X868352Y1568293D03*
Y1565293D03*
Y1559293D03*
Y1562293D03*
X865352Y1568293D03*
Y1565293D03*
Y1559293D03*
Y1562293D03*
X874352D03*
Y1559293D03*
Y1565293D03*
Y1568293D03*
X871352D03*
Y1565293D03*
Y1559293D03*
Y1562293D03*
X868352Y1574293D03*
Y1571293D03*
X865352Y1574293D03*
Y1571293D03*
X874352Y1574293D03*
Y1571293D03*
X871352D03*
Y1574293D03*
X866479Y1580393D03*
X872079D03*
X866052Y1597693D03*
X869052D03*
X866479Y1590653D03*
X869052Y1600693D03*
X866052D03*
X872052Y1597693D03*
X872079Y1590653D03*
X872052Y1600693D03*
X866479Y1585523D03*
X875052Y1597693D03*
Y1600693D03*
X860652Y1590444D03*
X869052Y1603693D03*
X866052D03*
X872052D03*
X869052Y1607793D03*
Y1611893D03*
X866052Y1607793D03*
X863052Y1611893D03*
X866052D03*
X872052Y1607793D03*
Y1611893D03*
X875052Y1603693D03*
Y1607793D03*
Y1611893D03*
X863052Y1607793D03*
X860052Y1611893D03*
X872208Y1731911D03*
X892214Y141891D03*
X886280Y174085D03*
X878327Y183169D03*
X876695Y171362D03*
Y176862D03*
X887520Y171362D03*
Y176862D03*
X878220Y192055D03*
X877724Y200837D03*
X878220Y187449D03*
X888929Y209223D03*
X891620Y209662D03*
X888929Y206723D03*
X891620Y207162D03*
X880943Y283347D03*
X884003Y278712D03*
X883870Y275802D03*
X880943Y286347D03*
X880473Y329370D03*
X882520Y327562D03*
X885020D03*
X887520D03*
X890422Y333879D03*
X887869Y386618D03*
X883472Y382910D03*
X890920Y386352D03*
X889453Y458926D03*
X887590Y471552D03*
X889439Y489599D03*
Y492999D03*
X887671Y487831D03*
Y494767D03*
X878931Y509051D03*
X878941Y503813D03*
X881680Y504742D03*
Y508142D03*
X884512Y523800D03*
X882410Y526132D03*
X888130Y532612D03*
X891530D03*
X886362Y534380D03*
X886500Y739162D03*
X889000Y737562D03*
X886720Y741902D03*
X878152Y876760D03*
X878192Y879910D03*
X884747Y871745D03*
X879100Y912608D03*
X881372Y920655D03*
X880102Y923235D03*
X889439Y1437938D03*
X891560Y1435510D03*
X883352Y1562293D03*
Y1559293D03*
Y1565293D03*
Y1568293D03*
X880352Y1562293D03*
Y1559293D03*
Y1565293D03*
Y1568293D03*
X877352Y1562293D03*
Y1559293D03*
Y1565293D03*
Y1568293D03*
X883352Y1574293D03*
Y1571293D03*
X880352Y1574293D03*
Y1571293D03*
X877352Y1574293D03*
Y1571293D03*
X888652Y1581793D03*
Y1573793D03*
X877579Y1580393D03*
X885652Y1584539D03*
X888652Y1585993D03*
X877579Y1585523D03*
X878052Y1597693D03*
Y1600693D03*
X877579Y1590653D03*
X883152Y1586507D03*
X888652Y1589793D03*
X878052Y1603693D03*
Y1607793D03*
X881052Y1611893D03*
X878052D03*
X881052Y1607793D03*
X892208Y1731911D03*
X908620Y188899D03*
X902350Y208294D03*
X907470Y211980D03*
Y215380D03*
X902350Y204894D03*
Y219068D03*
X903930Y202885D03*
X903980Y210355D03*
X903930Y217059D03*
X896620Y209662D03*
X894120D03*
Y207162D03*
X896620D03*
X902350Y208294D03*
X907470Y211980D03*
X902350Y204894D03*
X907470Y215380D03*
Y226154D03*
Y229554D03*
X902350Y222468D03*
X903980Y224529D03*
X902350Y219068D03*
X907470Y226154D03*
X902350Y222468D03*
X907470Y229554D03*
X906120Y261252D03*
X894770Y283062D03*
X893500Y339062D03*
X908675Y455386D03*
X899625Y473856D03*
X902260Y473153D03*
Y475653D03*
X903124Y470797D03*
X900020Y470672D03*
X896060Y481222D03*
Y484622D03*
X893321Y480293D03*
X893311Y485531D03*
X907678Y488177D03*
X895340Y497882D03*
Y501282D03*
X893572Y503050D03*
Y496114D03*
X900061Y510962D03*
X906127Y496343D03*
X901829Y512730D03*
Y516130D03*
X900061Y517898D03*
X893450Y516862D03*
X901230Y531612D03*
X904630D03*
X893298Y534380D03*
X899462Y533380D03*
X906398D03*
X894897Y871745D03*
X897000Y891895D03*
X894375Y913692D03*
X894965Y917422D03*
X898062Y976652D03*
Y969716D03*
X899830Y971484D03*
Y974884D03*
X907770Y1045242D03*
X894830Y1435970D03*
X907352Y1568293D03*
Y1565293D03*
Y1559293D03*
Y1562293D03*
Y1574293D03*
Y1571293D03*
X908479Y1580393D03*
X896652Y1577793D03*
X899652Y1582570D03*
Y1573793D03*
X897352Y1590893D03*
X896652Y1593793D03*
X908479Y1590653D03*
Y1585523D03*
X908052Y1600693D03*
Y1597693D03*
X899551Y1593793D03*
X902652Y1590444D03*
X908052Y1611893D03*
X905052D03*
X902052D03*
X908052Y1607793D03*
X905052D03*
X908052Y1603693D03*
X896652Y1601793D03*
X912214Y141891D03*
X917680Y174999D03*
Y177999D03*
Y171999D03*
X920246Y184138D03*
X909386Y195925D03*
X924920Y196199D03*
X909386Y203011D03*
Y210098D03*
Y217185D03*
Y224271D03*
Y231358D03*
X914550Y239924D03*
X912984Y458135D03*
X909584D03*
X913913Y455396D03*
X919279Y461244D03*
X924447Y463012D03*
X921047D03*
X909190Y473392D03*
X920682Y494586D03*
X918532Y492445D03*
X924623Y492097D03*
X921189Y492086D03*
X918212Y497677D03*
X918131Y503330D03*
X921060Y506086D03*
X923783Y506076D03*
X909984Y496330D03*
X920980Y503393D03*
X913394Y521662D03*
X916794D03*
X909600Y521162D03*
X911720Y511662D03*
X911626Y523430D03*
X918562D03*
X924647Y526808D03*
X922879Y531976D03*
Y528576D03*
X924647Y533744D03*
X918420Y804062D03*
X909720Y798861D03*
Y794862D03*
X913720Y799362D03*
X914152Y803294D03*
X924600Y824262D03*
X921757Y962082D03*
X916974Y962108D03*
X923403Y983327D03*
X923930Y976652D03*
X923322Y990227D03*
X924440Y996852D03*
X918720Y1009937D03*
X921880Y1525110D03*
X924380D03*
X921880Y1527610D03*
X924380D03*
X910352Y1568293D03*
Y1565293D03*
Y1559293D03*
Y1562293D03*
X922352D03*
Y1559293D03*
Y1565293D03*
Y1568293D03*
X919352Y1562293D03*
Y1559293D03*
Y1565293D03*
Y1568293D03*
X916352Y1562293D03*
Y1559293D03*
Y1565293D03*
Y1568293D03*
X913352D03*
Y1565293D03*
Y1559293D03*
Y1562293D03*
X910352Y1574293D03*
Y1571293D03*
X922352Y1574293D03*
Y1571293D03*
X919352Y1574293D03*
Y1571293D03*
X916352Y1574293D03*
Y1571293D03*
X913352D03*
Y1574293D03*
X919579Y1580393D03*
X914079D03*
X919579Y1590653D03*
X914079D03*
X919579Y1585523D03*
X917052Y1600693D03*
Y1597693D03*
X914052Y1600693D03*
Y1597693D03*
X911052Y1600693D03*
Y1597693D03*
X920052Y1600693D03*
Y1597693D03*
X917052Y1611893D03*
X914052D03*
X911052D03*
X917052Y1607793D03*
X914052D03*
X911052D03*
X920052Y1611893D03*
X923052D03*
Y1607793D03*
X920052D03*
X917052Y1603693D03*
X914052D03*
X911052D03*
X920052D03*
X922320Y1660953D03*
X918020Y1672860D03*
X912208Y1731911D03*
X932214Y141891D03*
X938160Y173389D03*
X935550Y173329D03*
X940720Y173389D03*
X938160Y176389D03*
X935550Y176329D03*
X940720Y176389D03*
X927133Y189386D03*
X935496Y195925D03*
X935770Y191419D03*
X939270D03*
X935496Y203012D03*
X925320Y203399D03*
X935496Y210098D03*
Y217185D03*
Y224272D03*
Y231358D03*
X930472Y246093D03*
X938603Y240063D03*
X933122Y246115D03*
X933686Y242922D03*
X935454Y241154D03*
X933217Y380693D03*
Y384693D03*
X941059Y427911D03*
Y424511D03*
X940709Y460438D03*
X938437Y455454D03*
X932724Y455538D03*
X926215Y461244D03*
X937447Y457862D03*
X934047D03*
X928394Y472201D03*
Y474701D03*
X932373Y495175D03*
X929234Y494915D03*
X938588Y485197D03*
X932089Y492691D03*
X929654Y492103D03*
X929698Y503595D03*
X940596Y498648D03*
X932218Y499314D03*
X939872Y495813D03*
X932089Y505986D03*
X932289Y502986D03*
X926637Y506069D03*
X929281Y506086D03*
X931720Y524862D03*
X939097Y527257D03*
X940550Y517400D03*
X940140Y514925D03*
X933773Y530479D03*
X930731D03*
X941050Y532252D03*
Y528852D03*
X928231Y530479D03*
X936273Y530478D03*
X939282Y534020D03*
X938742Y803831D03*
X931573Y816109D03*
X927470Y815112D03*
X927200Y811462D03*
X934260Y808312D03*
X938371Y809311D03*
X930786Y811785D03*
X925220Y817862D03*
X928237Y824844D03*
X926469Y826612D03*
X931496Y962082D03*
X926823D03*
X940170Y962842D03*
X930233Y983298D03*
X930274Y990237D03*
X936998Y985750D03*
X932310Y996812D03*
X929221Y1014664D03*
X927220Y1012362D03*
X931220D03*
X939380Y1525110D03*
X926880D03*
X929380D03*
X931880D03*
X934380D03*
X936880D03*
X926880Y1527610D03*
X929380D03*
X931880D03*
X934380D03*
X936880D03*
X939380D03*
X925352Y1562293D03*
Y1559293D03*
Y1565293D03*
Y1568293D03*
Y1574293D03*
Y1571293D03*
X938652Y1581393D03*
X928152Y1584539D03*
X938652Y1593393D03*
Y1585393D03*
X925152Y1586507D03*
X938652Y1589393D03*
X927122Y1661380D03*
X938220Y1661062D03*
X929979Y1661352D03*
X932208Y1731911D03*
X952214Y141891D03*
X957420Y153699D03*
X945720Y173389D03*
X943220D03*
X945720Y176389D03*
X943220D03*
X948400Y176499D03*
X949120Y184912D03*
X949710Y198289D03*
X941634Y199051D03*
Y193451D03*
X944250Y194489D03*
Y197889D03*
X957020Y193299D03*
X949550Y192819D03*
X953970Y208275D03*
X947496Y211997D03*
Y215397D03*
X953970Y204875D03*
X951354Y209437D03*
Y203837D03*
X944880Y210959D03*
Y216559D03*
X953970Y208275D03*
X947496Y215397D03*
X953970Y204875D03*
X947496Y211997D03*
X957156Y227163D03*
Y230563D03*
X947496Y226135D03*
Y229535D03*
X944880Y230697D03*
Y225097D03*
X954874Y232071D03*
X954904Y225741D03*
X957156Y227163D03*
X947496Y226135D03*
X957156Y230563D03*
X947496Y229535D03*
X953046Y390103D03*
X951181Y391916D03*
X956487Y394831D03*
X942646Y400793D03*
X942827Y422743D03*
Y429679D03*
X944032Y437631D03*
Y434231D03*
X945800Y432463D03*
Y439399D03*
X946492Y460410D03*
X945447Y463012D03*
X942047D03*
X946727Y507952D03*
Y504552D03*
X954420Y511252D03*
Y500552D03*
Y497152D03*
X956188Y495384D03*
Y502320D03*
X948495Y502784D03*
X948693Y509497D03*
X956188Y509484D03*
X954420Y514652D03*
X954390Y527596D03*
X956188Y516420D03*
X947190Y527330D03*
X945524Y515483D03*
X944261Y517871D03*
X941740Y512922D03*
X942610Y515350D03*
X952622Y529364D03*
X955123Y533642D03*
X948415Y534313D03*
X956518Y531567D03*
X953594Y787477D03*
X956700Y786862D03*
X954447Y791735D03*
X951043Y796140D03*
X950190Y791382D03*
X944272Y803410D03*
X943366Y798707D03*
X946786Y795287D03*
X947921Y799761D03*
X941400Y810062D03*
X944170Y962842D03*
X946865Y974077D03*
X953235Y972642D03*
X946938Y991162D03*
X943720Y985772D03*
X951560Y997422D03*
X956980Y1536260D03*
X953980D03*
X950980D03*
X947980D03*
X944980D03*
Y1551260D03*
X947980D03*
X950980D03*
X953980D03*
X956980D03*
X944980Y1548260D03*
X947980D03*
X950980D03*
X953980D03*
X956980D03*
X944980Y1545260D03*
X947980D03*
X950980D03*
X953980D03*
X956980D03*
X944980Y1542260D03*
X947980D03*
X950980D03*
X953980D03*
X956980D03*
Y1539260D03*
X953980D03*
X950980D03*
X947980D03*
X944980D03*
Y1554260D03*
X947980D03*
X950980D03*
X953980D03*
X956980D03*
X956022Y1620730D03*
X953022D03*
Y1632730D03*
X956022D03*
Y1629730D03*
X953022D03*
X956022Y1626730D03*
X953022D03*
Y1623730D03*
X956022D03*
X946100Y1661100D03*
X956600Y1666875D03*
X952208Y1731911D03*
X972214Y141891D03*
X960420Y153699D03*
X962604Y165313D03*
X962458Y162398D03*
X965150Y193412D03*
X966720Y198099D03*
X970720D03*
X961120Y193299D03*
X963520Y214699D03*
X960703Y212668D03*
X971471Y242358D03*
X968384Y242051D03*
X965884D03*
X960020Y264862D03*
X963020D03*
X963300Y347962D03*
X965792Y350959D03*
X962623Y350642D03*
X965420Y365719D03*
X970730Y377872D03*
X963856Y394202D03*
X960059Y387004D03*
X972986Y393171D03*
X972220Y386251D03*
Y390239D03*
X963856Y398302D03*
X965890Y405967D03*
X970054Y478773D03*
X961320Y476242D03*
X970054Y485709D03*
X968286Y483941D03*
Y480541D03*
X966720Y511362D03*
X960620Y509462D03*
X972379Y509303D03*
X964347Y509462D03*
X957790Y527596D03*
X963930Y533362D03*
X967330D03*
X959558Y529364D03*
X962162Y535130D03*
X969098D03*
X959351Y533566D03*
X958755Y657078D03*
X960920Y644762D03*
Y649762D03*
Y654762D03*
X963720Y647262D03*
Y657262D03*
Y652262D03*
X963520Y665062D03*
X958866Y662378D03*
X960820Y665062D03*
X960920Y659762D03*
X963720Y662262D03*
X959100Y789862D03*
X963610Y981292D03*
X959535Y990477D03*
X963780Y997496D03*
X967750Y1376460D03*
X969000Y1536262D03*
X971700D03*
X969000Y1548262D03*
X971700D03*
X969000Y1545262D03*
X971700D03*
X969000Y1551262D03*
X971700D03*
Y1542262D03*
X969000D03*
X971700Y1539262D03*
X969000D03*
Y1554262D03*
X971700D03*
X965622Y1579240D03*
Y1576240D03*
Y1573240D03*
X966852Y1585920D03*
X969852D03*
X960852D03*
X963852D03*
X957852D03*
X965086Y1603984D03*
X962022Y1620730D03*
X959022D03*
Y1632730D03*
X962022D03*
Y1629730D03*
X959022D03*
X962022Y1626730D03*
X959022D03*
Y1623730D03*
X962022D03*
X968022Y1620730D03*
X965022D03*
X971022D03*
X965022Y1632730D03*
X968022Y1629730D03*
X965022D03*
X968022Y1626730D03*
X965022D03*
Y1623730D03*
X968022D03*
X971022Y1626730D03*
Y1623730D03*
Y1629730D03*
Y1632730D03*
X968022D03*
X972208Y1731911D03*
X989910Y-27961D03*
X989925Y-25446D03*
X986642Y-27947D03*
X986627Y-25432D03*
X983632Y-26655D03*
X980899Y-23200D03*
Y-19800D03*
Y-13200D03*
Y-9800D03*
Y-13200D03*
Y-9800D03*
Y-19800D03*
Y-23200D03*
X978403Y-9022D03*
Y-13978D03*
Y-19022D03*
Y-23978D03*
X986627Y-21558D03*
X989925Y-21572D03*
X983632Y-16626D03*
X989910Y-17932D03*
X989925Y-15417D03*
X986642Y-17918D03*
X986627Y-15403D03*
Y-11529D03*
X989925Y-11543D03*
X980899Y6800D03*
D03*
X978403Y6022D03*
X989910Y-7903D03*
X989925Y-5388D03*
X986642Y-7889D03*
X986627Y-5374D03*
X983632Y-6597D03*
X986627Y4655D03*
X986642Y2140D03*
X989925Y4641D03*
X989910Y2126D03*
X983632Y3432D03*
X980899Y20200D03*
Y10200D03*
Y16800D03*
Y20200D03*
Y16800D03*
Y10200D03*
X978403Y10978D03*
Y20978D03*
Y16022D03*
X986627Y14684D03*
X989925Y14670D03*
X986642Y12169D03*
X989910Y12155D03*
X989925Y8515D03*
X986627Y8529D03*
X983632Y13461D03*
X986642Y22698D03*
X989910Y22684D03*
X986627Y19058D03*
X989925Y19044D03*
X986627Y25213D03*
X989895Y25199D03*
X983632Y23990D03*
X975688Y152950D03*
Y149950D03*
X975690Y157220D03*
X983811Y156694D03*
X988835Y185443D03*
X981445Y181058D03*
X985431D03*
X987320Y194599D03*
Y198099D03*
Y201599D03*
X977220Y201399D03*
X986020Y191099D03*
X981795Y216623D03*
X978012Y276436D03*
X975512Y282096D03*
X978012D03*
X975512Y279266D03*
X978012D03*
X981470Y268532D03*
X979940Y292262D03*
Y289762D03*
X975512Y294996D03*
X978012D03*
X979940Y284762D03*
Y287262D03*
X988818Y346372D03*
X985016Y344659D03*
X974791Y339990D03*
X986182Y361062D03*
X989500Y376362D03*
X979380Y373082D03*
X988908Y373392D03*
X980916Y384286D03*
X986955Y391939D03*
X988159Y409068D03*
X983760Y424292D03*
X980092Y421289D03*
X984254Y418379D03*
X987440Y431193D03*
X985672Y432961D03*
X986400Y503200D03*
X983720Y512362D03*
X976283Y534226D03*
X986273Y532996D03*
X980535Y532643D03*
X986418Y530019D03*
X975900Y1265062D03*
X987920Y1290662D03*
X985320Y1288762D03*
X979373Y1342724D03*
X974700Y1536262D03*
X980400D03*
X977700D03*
X974700Y1548262D03*
Y1545262D03*
Y1551262D03*
X980400Y1548262D03*
X977700D03*
X980400Y1545262D03*
X977700D03*
X980400Y1551262D03*
X977700D03*
Y1542262D03*
X980400D03*
X974700D03*
X977700Y1539262D03*
X980400D03*
X974700D03*
Y1554262D03*
X980400D03*
X977700D03*
X989270Y1554364D03*
X988988Y1579240D03*
Y1573240D03*
Y1576240D03*
X987662Y1620870D03*
Y1629870D03*
Y1626870D03*
Y1623870D03*
Y1632870D03*
X995000Y150883D03*
X1001500D03*
X1002735Y153943D03*
X999735D03*
X1006220Y160799D03*
X1002720D03*
X999915Y180548D03*
X996415D03*
X992505Y180553D03*
X993205Y174053D03*
X993305Y170953D03*
X999220Y185299D03*
X1002720D03*
X1006220D03*
X998205Y195735D03*
Y192191D03*
X1000705Y195735D03*
Y192191D03*
X998205Y199278D03*
X1000705D03*
X990220Y195699D03*
Y199199D03*
X990495Y212923D03*
X998205Y202821D03*
X1000705D03*
X990195Y216823D03*
X990220Y202699D03*
X1001195Y219898D03*
X1005120Y230399D03*
X1002500Y266862D03*
X998500Y269862D03*
X1002500D03*
X1001065Y304622D03*
Y307122D03*
Y309622D03*
X1006232Y343983D03*
X1001440Y359702D03*
X994553Y365711D03*
X994689Y379348D03*
X997598Y382952D03*
X997612Y391804D03*
X1006221Y382945D03*
X997900Y400720D03*
X994322Y404090D03*
X991770Y418835D03*
X993387Y429827D03*
X993012Y421570D03*
X990840Y431193D03*
X992608Y432961D03*
X999720Y512862D03*
X991097Y529902D03*
X991237Y533043D03*
X1002640Y594692D03*
X1005960Y594682D03*
X1005373Y748826D03*
X995120Y773122D03*
X994942Y777055D03*
X996675Y1286985D03*
X996320Y1280683D03*
Y1284062D03*
X997920Y1278762D03*
X994574Y1297318D03*
X995066Y1536262D03*
X992466D03*
X1001066D03*
X1003766D03*
X998066D03*
X995066Y1551262D03*
X992466D03*
X995066Y1545262D03*
X992466D03*
X995066Y1548262D03*
X992466D03*
X1001066Y1551262D03*
X1003766D03*
X1001066Y1545262D03*
X1003766D03*
X1001066Y1548262D03*
X1003766D03*
X998066Y1551262D03*
Y1545262D03*
Y1548262D03*
Y1542262D03*
X1003766D03*
X1001066D03*
X992466D03*
X995066D03*
X998066Y1539262D03*
X1003766D03*
X1001066D03*
X992466D03*
X995066D03*
Y1554262D03*
X992466D03*
X1001066D03*
X1003766D03*
X998066D03*
X1002782Y1585920D03*
X999782D03*
X996782D03*
X990782D03*
X993782D03*
X996698Y1604000D03*
X990662Y1620870D03*
X993662D03*
X996662D03*
X999662D03*
X1002662D03*
Y1626870D03*
Y1623870D03*
X996662Y1629870D03*
X999662Y1626870D03*
X996662D03*
Y1623870D03*
X999662D03*
X996662Y1632870D03*
X993662Y1629870D03*
X990662D03*
X993662Y1626870D03*
X990662D03*
Y1623870D03*
X993662D03*
X990662Y1632870D03*
X993662D03*
X1001810Y1662700D03*
Y1665200D03*
X992208Y1731911D03*
X1021908Y60392D03*
Y120392D03*
X1012214Y141826D03*
X1015300Y148736D03*
X1012187Y148749D03*
X1008129Y150948D03*
X1009720Y160799D03*
X1013220D03*
X1006435Y172843D03*
X1012000Y185299D03*
X1014900D03*
X1017800D03*
X1017200Y175699D03*
X1014300D03*
X1019900Y175799D03*
X1009895Y192359D03*
X1008067Y194356D03*
X1020645Y190499D03*
X1019935Y206463D03*
Y203333D03*
X1019802Y214099D03*
X1011720Y229699D03*
X1019355Y222423D03*
X1019530Y226423D03*
X1007820Y229999D03*
X1018000Y263862D03*
X1022000Y264362D03*
X1014500Y263862D03*
X1010500D03*
X1018000Y266862D03*
X1022002Y267342D03*
X1010500Y266862D03*
X1006500D03*
X1014500Y269862D03*
X1018000D03*
X1022002Y270142D03*
X1006500Y269862D03*
X1010500D03*
X1010828Y304822D03*
Y307322D03*
Y309822D03*
X1021419Y305704D03*
X1020720Y310937D03*
X1013500Y344900D03*
X1021695Y364518D03*
X1006710Y372931D03*
X1015096Y373758D03*
X1015638Y382968D03*
X1015637Y391334D03*
X1006589Y392017D03*
X1006750Y401010D03*
X1015657Y401013D03*
X1015420Y410862D03*
X1021259Y420548D03*
X1007249Y422682D03*
X1011611Y430038D03*
X1017511D03*
X1009009Y419948D03*
X1021239Y416974D03*
X1016261Y432888D03*
X1012861D03*
X1008720Y498362D03*
X1019145Y503823D03*
X1018092Y520212D03*
X1011720Y589362D03*
X1018720Y592362D03*
X1016220Y590862D03*
X1021720Y601862D03*
X1011160Y594682D03*
X1010630Y748741D03*
X1007873Y748826D03*
X1007600Y1298250D03*
X1007610Y1295040D03*
X1021612Y1536262D03*
X1016012D03*
X1018612D03*
Y1551262D03*
X1016012D03*
X1018612Y1545262D03*
X1016012D03*
X1018612Y1548262D03*
X1016012D03*
X1021612Y1551262D03*
Y1545262D03*
Y1548262D03*
X1018612Y1542262D03*
X1016012D03*
X1021612D03*
Y1539262D03*
X1016012D03*
X1018612D03*
Y1554262D03*
X1016012D03*
X1021612D03*
X1012636Y1554364D03*
X1012354Y1579240D03*
Y1573240D03*
Y1576240D03*
X1021942Y1586090D03*
X1019252Y1620870D03*
X1022252D03*
Y1623870D03*
Y1626870D03*
X1019252Y1623870D03*
Y1626870D03*
X1019910Y1662700D03*
Y1665200D03*
X1012208Y1731911D03*
X1032433Y-33211D03*
Y-29811D03*
D03*
Y-33211D03*
X1034929Y-33989D03*
Y-29033D03*
X1026705Y-27695D03*
X1023407Y-27681D03*
X1029700Y-26472D03*
X1026705Y-38224D03*
X1023437Y-38210D03*
X1026690Y-35709D03*
X1023422Y-35695D03*
X1026705Y-32069D03*
X1023407Y-32055D03*
X1029700Y-37001D03*
X1032433Y-23211D03*
Y-19811D03*
Y-13211D03*
Y-9811D03*
Y-23211D03*
Y-19811D03*
Y-13211D03*
Y-9811D03*
X1034929Y-13989D03*
Y-9033D03*
Y-23989D03*
Y-19033D03*
X1026705Y-17666D03*
X1026690Y-15151D03*
X1023407Y-17652D03*
X1023422Y-15137D03*
X1026705Y-11511D03*
X1023407Y-11497D03*
X1029700Y-16443D03*
X1026690Y-25180D03*
X1023422Y-25166D03*
X1023407Y-21526D03*
X1026705Y-21540D03*
X1032433Y-3211D03*
Y189D03*
Y-3211D03*
Y189D03*
X1034929Y-3989D03*
Y967D03*
X1029700Y3615D03*
X1023422Y4921D03*
X1023407Y2406D03*
X1026690Y4907D03*
X1026705Y2392D03*
X1023422Y-5108D03*
X1023407Y-7623D03*
X1026690Y-5122D03*
X1026705Y-7637D03*
Y-1482D03*
X1023407Y-1468D03*
X1029700Y-6414D03*
X1023407Y22464D03*
X1026705Y22450D03*
Y18576D03*
X1023407Y18590D03*
X1026705Y8547D03*
X1023407Y8561D03*
X1023422Y14950D03*
X1023407Y12435D03*
X1026690Y14936D03*
X1026705Y12421D03*
X1029700Y13644D03*
Y23673D03*
X1023422Y24979D03*
X1026690Y24965D03*
X1038609Y49388D03*
X1027520Y122732D03*
X1037650Y128842D03*
X1026620Y125662D03*
X1034229Y128953D03*
X1032894Y155185D03*
X1022800Y175799D03*
X1023220Y187574D03*
X1025000Y264362D03*
X1031502Y267342D03*
X1028202D03*
X1025102D03*
X1031702Y264130D03*
X1033133Y272564D03*
X1031502Y270142D03*
X1029833Y272564D03*
X1026733D03*
X1023633D03*
X1028202Y270142D03*
X1025102D03*
X1036915Y290969D03*
X1032317Y291284D03*
X1033285Y353627D03*
X1029395Y375844D03*
X1031950Y383771D03*
Y387171D03*
X1029094Y383070D03*
Y387872D03*
X1026820Y394362D03*
X1033860Y400802D03*
X1038320Y407062D03*
Y404462D03*
X1026548Y400571D03*
X1035920Y428962D03*
Y420062D03*
Y417462D03*
X1027190Y510672D03*
X1026370Y503562D03*
X1029220Y520032D03*
X1038220Y589862D03*
X1030980Y598722D03*
X1023740Y596152D03*
X1036480Y596272D03*
X1024154Y601152D03*
X1026654Y596152D03*
X1035760Y592952D03*
X1033260Y601272D03*
X1038260D03*
X1033817Y735612D03*
X1036954Y734669D03*
X1030660Y735082D03*
X1027212Y1536262D03*
X1024612D03*
Y1551262D03*
X1027212D03*
X1024612Y1545262D03*
X1027212D03*
X1024612Y1548262D03*
X1027212D03*
X1024612Y1542262D03*
X1027212D03*
Y1539262D03*
X1024612D03*
Y1554262D03*
X1027212D03*
X1036002Y1554364D03*
X1035720Y1579240D03*
Y1573240D03*
Y1576240D03*
X1030942Y1586090D03*
X1033942D03*
X1024942D03*
X1027942D03*
X1028298Y1604000D03*
X1025252Y1620870D03*
X1034252Y1623870D03*
Y1626870D03*
X1031252Y1623870D03*
Y1626870D03*
X1025252Y1623870D03*
X1028252D03*
Y1626870D03*
X1025252D03*
X1031252Y1620870D03*
X1034252D03*
X1028252D03*
X1023580Y1662700D03*
Y1665200D03*
X1027370Y1662700D03*
Y1665200D03*
X1032208Y1731911D03*
X1040970Y128332D03*
X1053028Y246518D03*
X1053428Y261118D03*
X1040924Y286073D03*
X1043629Y375078D03*
Y372578D03*
X1054820Y370162D03*
X1044120Y366362D03*
X1049100Y390162D03*
X1040120Y393962D03*
X1042720D03*
X1046156Y442699D03*
X1041420Y443962D03*
X1043920D03*
X1050470Y447062D03*
X1041444Y506504D03*
X1053690Y520760D03*
X1043720Y589362D03*
X1050200Y598062D03*
X1050390Y604172D03*
X1043260Y601272D03*
X1048260D03*
X1053200Y612162D03*
X1053745Y742341D03*
X1053354Y1286714D03*
Y1291714D03*
X1039510Y1296655D03*
X1049510D03*
X1044510D03*
X1039510Y1293155D03*
X1049510D03*
X1044510D03*
X1053354Y1296714D03*
X1041798Y1536262D03*
X1047798D03*
X1050498D03*
X1044798D03*
X1039298D03*
X1041798Y1551262D03*
X1039298D03*
X1041798Y1545262D03*
X1039298D03*
X1041798Y1548262D03*
X1039298D03*
X1047798Y1551262D03*
X1050498D03*
X1047798Y1545262D03*
X1050498D03*
X1047798Y1548262D03*
X1050498D03*
X1044798Y1551262D03*
Y1545262D03*
Y1548262D03*
X1039298Y1542262D03*
X1044798D03*
X1050498D03*
X1047798D03*
X1041798D03*
X1044798Y1539262D03*
X1050498D03*
X1047798D03*
X1039298D03*
X1041798D03*
Y1554262D03*
X1039298D03*
X1047798D03*
X1050498D03*
X1044798D03*
X1053612Y1586010D03*
X1050721Y1633043D03*
X1053721D03*
Y1624043D03*
Y1627043D03*
Y1630043D03*
X1050721Y1624043D03*
Y1627043D03*
Y1630043D03*
X1053721Y1621043D03*
X1050721D03*
X1044850Y1665050D03*
Y1662550D03*
X1052208Y1731911D03*
X1058609Y49388D03*
X1067220Y145362D03*
X1066820Y151632D03*
X1067220Y142862D03*
Y148362D03*
X1058028Y246518D03*
X1055528D03*
X1068093Y265503D03*
X1058428Y261118D03*
X1055928D03*
X1067618Y273800D03*
X1070718Y273700D03*
X1067718Y288500D03*
X1070618D03*
X1067718Y285600D03*
X1070618D03*
X1059943Y435314D03*
X1056190Y520760D03*
X1056280Y601232D03*
X1056220Y605052D03*
X1055205Y744853D03*
X1063354Y1286714D03*
X1058354D03*
X1063354Y1291714D03*
X1058354D03*
X1063354Y1296714D03*
X1058290Y1296302D03*
X1071179Y1294669D03*
X1066462Y1520088D03*
X1065164Y1536262D03*
X1062464D03*
X1071164D03*
X1068164D03*
X1065164Y1551262D03*
X1062464D03*
X1065164Y1545262D03*
X1062464D03*
X1065164Y1548262D03*
X1062464D03*
X1071164Y1551262D03*
Y1545262D03*
Y1548262D03*
X1068164Y1551262D03*
Y1545262D03*
Y1548262D03*
Y1542262D03*
X1071164D03*
X1062464D03*
X1065164D03*
X1068164Y1539262D03*
X1071164D03*
X1062464D03*
X1065164D03*
Y1554262D03*
X1062464D03*
X1071164D03*
X1068164D03*
X1059368Y1554364D03*
X1059086Y1573240D03*
Y1576240D03*
X1062612Y1586010D03*
X1065612D03*
X1056612D03*
X1059612D03*
X1059898Y1604000D03*
X1065721Y1633043D03*
X1068721D03*
Y1624043D03*
Y1627043D03*
Y1630043D03*
X1065721Y1624043D03*
Y1627043D03*
Y1630043D03*
X1062721Y1633043D03*
Y1624043D03*
Y1627043D03*
Y1630043D03*
X1056721Y1633043D03*
X1059721D03*
X1056721Y1624043D03*
X1059721D03*
Y1627043D03*
X1056721D03*
X1059721Y1630043D03*
X1056721D03*
X1068721Y1621043D03*
X1065721D03*
X1062721D03*
X1059721D03*
X1056721D03*
X1078609Y49388D03*
X1075100Y55682D03*
X1071920Y53862D03*
X1084146Y67102D03*
X1079114Y75775D03*
X1080168Y90721D03*
X1078270Y93462D03*
X1081282Y180937D03*
X1086756Y187540D03*
X1077973Y246362D03*
X1083973D03*
X1080973D03*
X1077883Y260842D03*
X1076823Y265438D03*
X1083823D03*
X1083883Y260842D03*
X1080883D03*
X1080323Y265438D03*
X1082853Y269492D03*
X1079853D03*
X1075400Y273762D03*
X1078400D03*
X1081400D03*
X1084400D03*
X1087400D03*
X1076018Y289400D03*
X1079018D03*
X1082018D03*
X1085018D03*
X1084130Y298342D03*
X1086630D03*
X1076353Y363966D03*
X1078853D03*
X1077270Y369061D03*
Y379251D03*
X1087330Y369061D03*
Y374131D03*
Y379251D03*
X1075462Y386723D03*
X1078151Y413911D03*
X1078120Y411262D03*
X1084245Y435437D03*
X1078545Y435637D03*
X1081045D03*
X1087280Y435437D03*
X1073724Y476867D03*
X1081906Y472577D03*
X1079320Y473892D03*
X1076820D03*
X1073589Y506461D03*
X1082220Y522362D03*
X1085720Y522422D03*
X1073250Y582332D03*
X1084637Y744635D03*
X1083714Y1285144D03*
Y1288144D03*
Y1291144D03*
X1077634Y1294869D03*
X1074387Y1294652D03*
X1073864Y1536262D03*
X1085830D03*
X1073864Y1551262D03*
Y1545262D03*
Y1548262D03*
X1085830Y1551262D03*
Y1545262D03*
Y1548262D03*
Y1542262D03*
X1073864D03*
X1085830Y1539262D03*
X1073864D03*
Y1554262D03*
X1085830D03*
X1082734Y1554364D03*
X1072208Y1731911D03*
X1098609Y49388D03*
X1097794Y67881D03*
X1094644Y67992D03*
X1102561Y78461D03*
X1102480Y133722D03*
X1090279Y126524D03*
X1099030Y245140D03*
X1088018Y289400D03*
X1089130Y298342D03*
X1091630D03*
X1094130D03*
X1089660Y408560D03*
X1095820Y420762D03*
X1090245Y435437D03*
X1096477Y744385D03*
X1093497Y744655D03*
X1089714Y1285144D03*
X1088530Y1536262D03*
X1091530D03*
X1088530Y1551262D03*
Y1545262D03*
Y1548262D03*
X1094530Y1551262D03*
X1097230D03*
X1094530Y1545262D03*
X1097230D03*
X1094530Y1548262D03*
X1097230D03*
X1091530Y1551262D03*
Y1545262D03*
Y1548262D03*
Y1542262D03*
X1097230D03*
X1094530D03*
X1088530D03*
X1091530Y1539262D03*
X1094530D03*
X1088530D03*
Y1554262D03*
X1094530D03*
X1097230D03*
X1091530D03*
X1092302Y1585650D03*
X1089302D03*
X1098302D03*
X1095302D03*
X1095436Y1603944D03*
X1099901Y1633203D03*
Y1624203D03*
Y1627203D03*
Y1630203D03*
Y1621203D03*
X1093901Y1633203D03*
X1096901D03*
Y1624203D03*
Y1627203D03*
Y1630203D03*
X1093901Y1624203D03*
Y1627203D03*
Y1630203D03*
X1090901Y1633203D03*
X1087901D03*
X1090901Y1624203D03*
X1087901D03*
Y1627203D03*
X1090901D03*
X1087901Y1630203D03*
X1090901D03*
X1096901Y1621203D03*
X1093901D03*
X1087901D03*
X1090901D03*
X1095900Y1646935D03*
X1095649Y1638875D03*
X1099457D03*
X1088790Y1641830D03*
X1102930Y1668690D03*
X1094225Y1671710D03*
X1091880Y1673720D03*
X1092072Y1734244D03*
X1118609Y49388D03*
X1110977Y55505D03*
X1110754Y60028D03*
X1113594Y69862D03*
X1109020Y80592D03*
X1118309Y111687D03*
X1115860Y113883D03*
X1109088Y234668D03*
X1111918Y237718D03*
Y240718D03*
X1109088Y237668D03*
Y240668D03*
X1117820Y456132D03*
X1113207Y744455D03*
X1118110Y1398010D03*
X1115853Y1426342D03*
Y1435532D03*
X1117574Y1448604D03*
X1114400Y1518237D03*
X1109118Y1526046D03*
X1113725Y1530935D03*
X1117407Y1628495D03*
X1113990Y1631370D03*
X1113325Y1627975D03*
X1106480Y1641275D03*
X1113110Y1666460D03*
X1104457Y1675490D03*
X1108320Y1680200D03*
X1116338Y1711380D03*
X1112130Y1711600D03*
X1112252Y1706170D03*
X1112200Y1709000D03*
X1113055Y1718338D03*
X1110663Y1719189D03*
X1119200Y1730300D03*
Y1727200D03*
X1114300Y1722700D03*
X1119300Y1724100D03*
X1111866Y1737108D03*
X1132856Y52926D03*
X1129948Y66786D03*
X1122278Y107549D03*
X1120420Y109829D03*
X1133041Y194137D03*
X1120544Y312200D03*
X1129995Y301637D03*
X1122059Y305673D03*
X1124985Y302578D03*
X1127402Y456174D03*
X1136051Y503324D03*
X1129420Y644062D03*
X1122980Y741312D03*
X1127972Y747250D03*
X1135750Y1255672D03*
X1127179Y1372700D03*
X1124679D03*
Y1370200D03*
X1127179D03*
X1129729Y1372700D03*
Y1370200D03*
Y1375200D03*
X1127179D03*
X1124679D03*
X1129729Y1377700D03*
Y1380200D03*
Y1385200D03*
Y1382700D03*
X1127179D03*
X1124679D03*
X1127179Y1380200D03*
Y1377700D03*
X1124679D03*
Y1380200D03*
Y1385200D03*
X1127179D03*
X1127788Y1397126D03*
X1135709Y1397119D03*
X1133209D03*
X1131629Y1420615D03*
X1129029D03*
X1134229D03*
X1123674Y1414936D03*
X1121174D03*
X1123674Y1417536D03*
Y1420136D03*
X1121174Y1417536D03*
Y1420136D03*
X1131629Y1423722D03*
X1129029D03*
X1134229D03*
X1123674Y1422736D03*
X1121174D03*
X1131042Y1436061D03*
X1135942D03*
X1133512D03*
X1131042Y1430461D03*
X1135942D03*
X1133512D03*
X1134429Y1426829D03*
X1122879Y1434024D03*
X1136004Y1447858D03*
X1126117Y1450504D03*
X1123379Y1443583D03*
X1133169Y1445690D03*
X1129169Y1442998D03*
X1135568Y1442923D03*
X1129169Y1445719D03*
X1130841Y1462953D03*
X1128341Y1465453D03*
Y1462953D03*
X1130841Y1465453D03*
X1133841Y1462953D03*
Y1465453D03*
X1128341Y1468453D03*
X1130841D03*
X1133841D03*
X1128341Y1460453D03*
X1130841D03*
X1133841D03*
Y1471453D03*
X1130841D03*
X1128341D03*
X1127008Y1524203D03*
X1135748Y1524187D03*
X1127008Y1550285D03*
X1133780Y1550301D03*
X1132142Y1555301D03*
X1135187Y1582738D03*
X1132187Y1590738D03*
X1135187D03*
X1120472Y1615010D03*
X1124862D03*
X1131632Y1625969D03*
X1131866Y1737108D03*
X1138609Y49388D03*
X1145603Y73679D03*
X1140242Y101135D03*
X1152720Y180862D03*
X1150914Y197407D03*
X1148795Y213731D03*
X1141957Y227277D03*
X1144457D03*
X1139457D03*
X1148354Y222677D03*
X1146670Y230110D03*
X1142302Y366532D03*
X1137315Y379592D03*
X1148220Y501362D03*
X1138551Y503324D03*
X1144720Y501362D03*
Y498662D03*
X1142967Y592097D03*
X1138500Y586362D03*
X1142127Y586452D03*
X1140697Y608762D03*
X1142790Y611122D03*
X1153370Y638192D03*
X1150272Y638346D03*
X1142674Y1287608D03*
X1144247Y1372700D03*
Y1370200D03*
X1146797Y1372700D03*
X1149297D03*
X1146797Y1370200D03*
X1149297D03*
X1144247Y1375200D03*
X1146797D03*
X1149297D03*
X1144247Y1377700D03*
Y1380200D03*
Y1385200D03*
Y1382700D03*
X1146797D03*
X1149297D03*
X1146797Y1380200D03*
Y1377700D03*
X1149297Y1380200D03*
Y1377700D03*
Y1385200D03*
X1146797D03*
X1146118Y1397126D03*
X1138209Y1397119D03*
X1150843Y1415126D03*
X1148243D03*
X1150843Y1417726D03*
X1148243D03*
X1150732Y1420326D03*
X1142629Y1420615D03*
X1145573Y1420631D03*
X1139429Y1420615D03*
X1136829D03*
X1145573Y1423738D03*
X1136829Y1423722D03*
X1145542Y1426861D03*
X1137029Y1426829D03*
X1146563Y1436334D03*
X1141903D03*
X1144233Y1435584D03*
X1139573D03*
X1149469Y1437098D03*
X1151669Y1435698D03*
Y1438598D03*
X1137311Y1445191D03*
X1147203Y1441968D03*
X1149569Y1440098D03*
X1151669Y1441498D03*
X1147203Y1439068D03*
X1141591Y1462853D03*
Y1465353D03*
Y1468353D03*
Y1471353D03*
Y1460353D03*
X1150821Y1459607D03*
Y1456587D03*
X1145108Y1476732D03*
X1138430Y1524150D03*
X1151497Y1524187D03*
X1149528Y1550301D03*
X1145410Y1540640D03*
X1143060Y1538380D03*
X1141654Y1550301D03*
X1137717Y1558020D03*
X1141690Y1552920D03*
X1152187Y1574738D03*
X1142187D03*
X1145187D03*
Y1582738D03*
X1141525Y1597630D03*
X1152187Y1590738D03*
X1142187D03*
X1145187D03*
X1150380Y1602590D03*
X1146960Y1618960D03*
X1152257Y1628910D03*
X1158609Y49388D03*
X1155703Y73679D03*
X1160720Y180862D03*
X1165440Y176450D03*
X1168710Y176590D03*
X1165000Y190962D03*
X1162500D03*
X1164300Y197262D03*
X1163732Y204887D03*
X1160732D03*
X1160630Y213870D03*
X1158172Y230157D03*
X1156790Y363231D03*
X1161690Y374110D03*
X1164320Y451062D03*
X1156100Y456342D03*
X1167190Y526922D03*
X1153467Y586462D03*
X1153490Y610322D03*
X1156770Y638192D03*
X1169820Y636052D03*
X1161860Y642112D03*
X1165260D03*
X1159912Y638216D03*
X1166722Y636206D03*
X1156770Y638192D03*
X1153370D03*
X1158762Y642266D03*
X1168402Y642136D03*
X1161860Y642112D03*
X1165260D03*
X1155962Y746193D03*
X1156609Y1286685D03*
X1165279Y1372700D03*
X1162779D03*
X1167829D03*
X1162779Y1370200D03*
X1165279D03*
X1167829D03*
X1162779Y1375200D03*
X1165279D03*
X1167829D03*
Y1377700D03*
Y1380200D03*
Y1385200D03*
Y1382700D03*
X1165279D03*
X1162779D03*
X1165279Y1380200D03*
X1162779D03*
Y1377700D03*
X1165279D03*
X1162779Y1385200D03*
X1165279D03*
X1165931Y1397126D03*
X1154714Y1398295D03*
X1157786Y1398252D03*
X1167172Y1420615D03*
X1153913Y1420606D03*
Y1415406D03*
Y1418006D03*
X1159124D03*
Y1420606D03*
Y1415406D03*
X1161724D03*
Y1420606D03*
Y1418006D03*
X1156524Y1415406D03*
Y1420606D03*
Y1418006D03*
X1167172Y1423722D03*
X1153913Y1423206D03*
X1159124D03*
X1161724D03*
X1156524D03*
X1161022Y1431499D03*
Y1433999D03*
X1154288Y1432502D03*
X1155964Y1440864D03*
X1164260Y1450423D03*
X1158954Y1450274D03*
X1161522Y1443630D03*
X1167312Y1442998D03*
Y1445964D03*
X1159386Y1464253D03*
Y1466753D03*
X1156386Y1464253D03*
Y1466753D03*
X1159386Y1469253D03*
X1156386D03*
X1153821Y1459607D03*
Y1456587D03*
X1159386Y1461753D03*
X1159476Y1458918D03*
X1156386Y1461753D03*
X1156476Y1458918D03*
X1159446Y1456113D03*
X1156446D03*
X1167245Y1524187D03*
X1159371D03*
X1165276Y1550301D03*
X1157402D03*
X1164595Y1574738D03*
X1155187D03*
X1164595Y1582738D03*
X1155187D03*
X1163079Y1601479D03*
X1161595Y1590738D03*
X1164595D03*
X1155187D03*
X1168192Y1604130D03*
X1152950Y1616470D03*
X1165950Y1617729D03*
X1152930Y1633880D03*
X1158030Y1619250D03*
X1159930Y1645632D03*
X1164830Y1654632D03*
X1159930D03*
X1161076Y1680624D03*
X1157700Y1681100D03*
X1174120Y57111D03*
X1175926Y69151D03*
X1180676Y106858D03*
X1170595Y170056D03*
X1181476Y172247D03*
X1173065Y194174D03*
X1173100Y186962D03*
X1172925Y202174D03*
X1181369Y199234D03*
X1172865Y210174D03*
X1172835Y218174D03*
X1181500Y211962D03*
Y218462D03*
Y215962D03*
X1180398Y289814D03*
X1171540Y310902D03*
X1181450Y306052D03*
X1169690Y526922D03*
X1172720Y527862D03*
X1172310Y584562D03*
X1181300Y584762D03*
X1174980Y585632D03*
X1174880Y592652D03*
X1170337Y607327D03*
X1173990Y602192D03*
X1173220Y636052D03*
X1186760Y642062D03*
X1183360D03*
X1176362Y636076D03*
X1173220Y636052D03*
X1169820D03*
X1180262Y642216D03*
X1183360Y642062D03*
X1183230Y739102D03*
X1173020Y745972D03*
X1175573Y1286765D03*
X1172573D03*
X1182747Y1372700D03*
X1185297D03*
X1182747Y1370200D03*
X1185297D03*
X1182747Y1375200D03*
X1185297D03*
X1182747Y1380200D03*
Y1377700D03*
Y1385200D03*
Y1382700D03*
X1185297D03*
Y1377700D03*
Y1380200D03*
Y1385200D03*
X1184661Y1397126D03*
X1171752Y1397119D03*
X1176752D03*
X1174252D03*
X1183716Y1420631D03*
X1180772Y1420615D03*
X1174972D03*
X1177572D03*
X1172372D03*
X1169772D03*
X1183716Y1423738D03*
X1174972Y1423722D03*
X1172372D03*
X1169772D03*
X1174085Y1436061D03*
Y1430461D03*
X1171655Y1436061D03*
X1169185D03*
X1171655Y1430461D03*
X1169185D03*
X1183685Y1426861D03*
X1175172Y1426829D03*
X1172572D03*
X1184706Y1436334D03*
X1180046D03*
X1182376Y1435584D03*
X1177716D03*
X1174147Y1447858D03*
X1171342Y1445650D03*
X1175454Y1445191D03*
X1173711Y1442923D03*
X1179922Y1524203D03*
X1171182Y1524187D03*
X1179922Y1550285D03*
X1184330Y1573260D03*
X1184290Y1570080D03*
X1171595Y1574738D03*
X1174595D03*
Y1582738D03*
X1183410Y1594450D03*
X1183440Y1591640D03*
X1171595Y1590738D03*
X1178140Y1601100D03*
X1183320Y1597080D03*
X1184501Y1606521D03*
X1169968Y1602370D03*
X1174550Y1615630D03*
X1178250Y1609100D03*
X1184200Y1602700D03*
X1185030Y1633010D03*
X1182470Y1618914D03*
X1172530Y1623020D03*
X1176900Y1627510D03*
X1181930Y1645632D03*
X1170930D03*
X1181930Y1654632D03*
X1175830D03*
X1170930D03*
X1183076Y1680624D03*
X1172076D03*
X1198609Y49388D03*
X1194478Y56986D03*
X1188720Y56755D03*
X1191700Y56822D03*
X1197520Y56962D03*
X1201158Y57130D03*
X1189393Y60183D03*
X1185500Y101400D03*
X1190700Y99000D03*
X1188700Y100700D03*
X1185400Y104000D03*
X1197627Y132859D03*
X1185420Y153762D03*
X1200720Y184862D03*
X1196100Y188962D03*
X1193500D03*
X1188300Y189062D03*
X1200720Y187862D03*
X1200963Y212648D03*
X1192600Y217662D03*
X1193000Y204486D03*
X1195500D03*
X1195100Y217662D03*
X1200830Y206002D03*
X1186340Y204492D03*
X1187300Y217862D03*
X1188500Y205772D03*
X1188600Y225962D03*
X1187013Y238972D03*
X1194840Y236592D03*
X1199720Y252362D03*
X1196720D03*
X1186280Y298972D03*
X1199027Y588714D03*
X1193198Y586172D03*
X1195698D03*
X1198198D03*
X1200698D03*
X1189902Y642086D03*
X1186760Y642062D03*
X1185687Y744475D03*
X1187797Y1372700D03*
Y1370200D03*
Y1375200D03*
Y1382700D03*
Y1377700D03*
Y1380200D03*
Y1385200D03*
X1189135Y1397529D03*
X1187736Y1420387D03*
X1188986Y1415287D03*
Y1417887D03*
X1186386Y1415287D03*
Y1417887D03*
X1191486Y1415287D03*
Y1417887D03*
X1190444Y1420384D03*
X1194750Y1424672D03*
X1197700Y1432672D03*
X1191930Y1424647D03*
X1187412Y1437498D03*
X1189612Y1436098D03*
X1191918Y1432516D03*
X1198010Y1441902D03*
X1185346Y1442128D03*
X1187512Y1440498D03*
X1189612Y1441898D03*
X1185346Y1439228D03*
X1189612Y1438998D03*
X1198880Y1457162D03*
X1187720Y1517688D03*
X1198546Y1520188D03*
X1187830Y1526688D03*
X1198436Y1529362D03*
X1187720Y1531862D03*
X1198497Y1539667D03*
X1187720Y1548772D03*
X1197181Y1563587D03*
X1194510Y1563076D03*
X1196772Y1578182D03*
X1200172D03*
X1195994Y1580678D03*
Y1575686D03*
X1200950Y1580678D03*
Y1575686D03*
X1196772Y1578182D03*
X1200172D03*
Y1590094D03*
X1196772D03*
X1202072Y1602380D03*
X1201294Y1599884D03*
X1195994Y1592590D03*
Y1587598D03*
X1200950Y1592590D03*
Y1587598D03*
X1196772Y1590094D03*
X1200172D03*
X1202072Y1614292D03*
X1201294Y1604876D03*
Y1611796D03*
Y1616788D03*
X1187600Y1622064D03*
X1199400Y1627800D03*
X1192500Y1645942D03*
X1186000Y1640000D03*
X1197400Y1654942D03*
X1192500D03*
X1186830Y1654632D03*
X1201110Y1681767D03*
X1193646Y1680934D03*
X1201106Y1677873D03*
X1192340Y1691422D03*
Y1700422D03*
X1197240D03*
X1193174Y1726414D03*
X1191866Y1737108D03*
X1213026Y56742D03*
X1216176D03*
X1201800Y94600D03*
X1202860Y120392D03*
X1206093Y120362D03*
X1204800Y108900D03*
X1206900Y115900D03*
X1215800Y111300D03*
X1201700Y110000D03*
X1202920Y117162D03*
X1210910Y129502D03*
X1206434Y129492D03*
X1214573Y148909D03*
X1206664Y158952D03*
X1214091Y164962D03*
X1214593Y168962D03*
X1214534Y157462D03*
X1203858Y185451D03*
X1214693Y174962D03*
X1214134Y180972D03*
X1213720Y200309D03*
X1204420Y195362D03*
X1213720Y189362D03*
X1204220D03*
X1203200Y202514D03*
X1210084Y224362D03*
X1217720Y249862D03*
X1207220Y243998D03*
X1208365Y271151D03*
X1204475Y350684D03*
X1207100Y600882D03*
X1204880Y754032D03*
X1211277Y744265D03*
X1206757Y744455D03*
X1210288Y754081D03*
X1202300Y753962D03*
X1207607Y754095D03*
X1202600Y759662D03*
X1215896Y756942D03*
X1206432Y758995D03*
X1202307Y757082D03*
X1212232Y1578182D03*
X1208832D03*
X1213010Y1575686D03*
X1208054D03*
X1213010Y1580678D03*
X1208054D03*
X1212232Y1578182D03*
X1208832D03*
X1212232Y1590094D03*
X1208832D03*
X1205472Y1602380D03*
X1214132D03*
X1217532D03*
X1206250Y1599884D03*
X1213354D03*
X1213010Y1587598D03*
X1208054D03*
X1213010Y1592590D03*
X1208054D03*
X1212232Y1590094D03*
X1208832D03*
X1205472Y1614292D03*
X1214132D03*
X1217532D03*
X1206250Y1604876D03*
Y1611796D03*
Y1616788D03*
X1213354D03*
Y1604876D03*
Y1611796D03*
X1214132Y1614292D03*
X1202072D03*
X1217532D03*
X1205472D03*
X1214132Y1602380D03*
X1202072D03*
X1217532D03*
X1205472D03*
X1210830Y1676500D03*
X1213910Y1691732D03*
X1203110Y1691467D03*
X1207180Y1685680D03*
X1208010Y1700467D03*
X1213910Y1700732D03*
X1203110Y1700467D03*
X1203939Y1726459D03*
X1214834Y1726724D03*
X1211866Y1737108D03*
X1218609Y49388D03*
X1228420Y58862D03*
X1230250Y89450D03*
X1228425Y91500D03*
X1222100Y91600D03*
X1228704Y112122D03*
X1232182Y110659D03*
X1224614Y116962D03*
X1219534Y116492D03*
X1223100Y127300D03*
X1226400Y125200D03*
X1226093Y134262D03*
X1223100Y130700D03*
X1226093Y152792D03*
X1234093Y144962D03*
X1226093Y140962D03*
X1222593D03*
X1222920Y144909D03*
Y148909D03*
X1222593Y168962D03*
X1222890Y157002D03*
X1226093Y156962D03*
X1222594Y154242D03*
X1226093Y168162D03*
X1225874Y163462D03*
X1222720Y163362D03*
X1226093Y177962D03*
X1222724Y176102D03*
X1226093Y172962D03*
X1223134Y190802D03*
X1228520Y202162D03*
X1226093Y193462D03*
X1223720Y217862D03*
Y205862D03*
X1223180Y210552D03*
X1232000Y244332D03*
X1219220Y243862D03*
Y247148D03*
X1227500Y380400D03*
X1221220Y380362D03*
X1223650Y520672D03*
X1230650D03*
X1227150D03*
X1219060Y757272D03*
X1223327Y757615D03*
X1228320Y758598D03*
X1224292Y1578182D03*
X1220892D03*
X1232952D03*
X1225070Y1580678D03*
Y1575686D03*
X1220114D03*
Y1580678D03*
X1232174D03*
Y1575686D03*
X1220892Y1578182D03*
X1232952D03*
X1224292D03*
X1232952Y1590094D03*
X1224292D03*
X1220892D03*
X1226192Y1602380D03*
X1229592D03*
X1218310Y1599884D03*
X1225414D03*
X1230370D03*
X1225070Y1592590D03*
X1220114D03*
X1225070Y1587598D03*
X1220114D03*
X1232174D03*
Y1592590D03*
X1220892Y1590094D03*
X1232952D03*
X1224292D03*
X1226192Y1614292D03*
X1229592D03*
X1218310Y1616788D03*
Y1604876D03*
Y1611796D03*
X1225414D03*
Y1604876D03*
X1230370Y1611796D03*
Y1604876D03*
X1225414Y1616788D03*
X1230370D03*
X1226192Y1614292D03*
X1229592D03*
X1226192Y1602380D03*
X1229592D03*
X1218810Y1700732D03*
X1231866Y1737108D03*
X1238609Y49388D03*
X1236620Y58862D03*
X1239907Y95008D03*
X1241010Y110782D03*
X1243808Y116832D03*
X1250010Y117121D03*
X1241035Y114399D03*
X1247333Y121999D03*
X1234746Y136040D03*
X1240728Y136198D03*
X1240904Y151592D03*
X1238604Y150062D03*
X1242520Y165362D03*
X1244120Y167462D03*
X1239874Y182322D03*
X1236410Y201462D03*
X1236220Y189362D03*
X1236593Y197462D03*
X1236584Y205762D03*
X1236593Y209562D03*
X1236584Y217462D03*
X1236520Y213462D03*
X1245486Y203000D03*
X1245593Y211762D03*
X1236620Y221562D03*
X1245614Y227462D03*
X1245574Y234042D03*
X1244720Y230362D03*
X1245514Y224302D03*
X1245593Y219662D03*
X1239045Y224062D03*
X1245593Y241462D03*
X1246878Y248615D03*
X1240500Y248332D03*
X1246444Y256098D03*
X1236720Y257362D03*
X1243589Y379595D03*
X1236720Y377862D03*
X1234720Y380362D03*
X1248150Y520672D03*
X1244650D03*
X1241150D03*
X1237650D03*
X1234150D03*
X1242260Y757602D03*
X1236352Y1578182D03*
X1248412D03*
X1245012D03*
X1237130Y1575686D03*
Y1580678D03*
X1244234D03*
X1249190D03*
X1244234Y1575686D03*
X1249190D03*
X1245012Y1578182D03*
X1236352D03*
X1248412D03*
Y1590094D03*
X1236352D03*
X1245012D03*
X1238252Y1602380D03*
X1241652D03*
X1250312D03*
X1242430Y1599884D03*
X1237474D03*
X1249534D03*
X1237130Y1587598D03*
Y1592590D03*
X1249190D03*
X1244234D03*
Y1587598D03*
X1249190D03*
X1245012Y1590094D03*
X1236352D03*
X1248412D03*
X1238252Y1614292D03*
X1241652D03*
X1250312D03*
X1242430Y1616788D03*
X1237474D03*
X1242430Y1611796D03*
Y1604876D03*
X1237474Y1611796D03*
Y1604876D03*
X1249534Y1611796D03*
Y1604876D03*
Y1616788D03*
X1238252Y1614292D03*
X1241652D03*
X1238252Y1602380D03*
X1241652D03*
X1258609Y49388D03*
X1261227Y52061D03*
X1258727D03*
X1263454Y83060D03*
X1266464Y83090D03*
X1264098Y88787D03*
X1262320Y96012D03*
X1262800Y101100D03*
X1264620Y92724D03*
X1258539Y100900D03*
X1252520Y92022D03*
X1258539Y109263D03*
X1260641Y114399D03*
X1252961Y111903D03*
X1264220Y110462D03*
X1250424Y108943D03*
X1257581Y114579D03*
X1266093Y129962D03*
X1256093Y143462D03*
X1264663Y158946D03*
X1254994Y157382D03*
X1264685Y175506D03*
X1253624Y201362D03*
X1264874Y217462D03*
X1256504D03*
X1255613Y209568D03*
X1265207Y208442D03*
X1256070Y229512D03*
X1264584Y226592D03*
X1256593Y221462D03*
Y233972D03*
Y225972D03*
X1256494Y243177D03*
X1256574Y238662D03*
X1266518Y237042D03*
X1256584Y248002D03*
X1256454Y252122D03*
X1264854Y253996D03*
Y256496D03*
X1255150Y306211D03*
X1260220Y477362D03*
X1251650Y520672D03*
X1255150D03*
X1256787Y749605D03*
X1258667Y751405D03*
X1255520Y747362D03*
X1263486Y739949D03*
X1253586Y1334649D03*
X1257672Y1351008D03*
X1260472Y1578182D03*
X1257072D03*
X1261250Y1575686D03*
X1256294D03*
X1261250Y1580678D03*
X1256294D03*
X1257072Y1578182D03*
X1260472D03*
Y1590094D03*
X1257072D03*
X1253712Y1602380D03*
X1262372D03*
X1265772D03*
X1254490Y1599884D03*
X1261594D03*
X1261250Y1587598D03*
X1256294D03*
X1261250Y1592590D03*
X1256294D03*
X1257072Y1590094D03*
X1260472D03*
X1253712Y1614292D03*
X1262372D03*
X1265772D03*
X1254490Y1611796D03*
Y1604876D03*
Y1616788D03*
X1261594D03*
Y1611796D03*
Y1604876D03*
X1262372Y1614292D03*
X1250312D03*
X1265772D03*
X1253712D03*
X1262372Y1602380D03*
X1250312D03*
X1265772D03*
X1253712D03*
X1251866Y1737108D03*
X1276820Y58142D03*
X1282360Y58132D03*
X1279580D03*
X1278300Y81232D03*
X1279390Y87697D03*
X1270329Y101011D03*
X1266722Y101005D03*
X1278456Y96187D03*
X1279415Y90847D03*
X1281704Y95402D03*
X1279485Y105752D03*
X1282824Y108872D03*
X1276745Y125850D03*
X1275807Y132922D03*
X1281600Y137962D03*
X1278993Y193262D03*
X1273093Y200038D03*
X1275493Y193962D03*
X1267289Y192167D03*
X1269904Y192692D03*
X1282568Y212722D03*
X1267773Y208373D03*
X1275727Y209597D03*
X1267618Y225382D03*
X1267593Y229462D03*
X1282176Y221436D03*
X1278320Y239292D03*
X1282293Y248962D03*
X1279493Y248662D03*
X1282645Y255671D03*
Y252271D03*
X1280223Y256841D03*
X1279841Y253052D03*
X1277771Y255173D03*
X1273754Y256504D03*
X1275557Y269477D03*
Y272436D03*
X1282653Y269446D03*
X1278557Y272436D03*
Y269477D03*
X1272557Y272436D03*
X1271150Y305792D03*
X1269220Y477362D03*
X1274420Y463362D03*
X1275576Y730879D03*
X1266727Y752955D03*
X1279788Y1304042D03*
X1280135Y1340002D03*
Y1337402D03*
X1272707Y1334865D03*
X1280135Y1345202D03*
Y1342602D03*
X1279812Y1353552D03*
X1279334Y1356089D03*
X1280312Y1365689D03*
X1275856Y1358098D03*
X1271990Y1358079D03*
X1276891Y1362891D03*
X1282928Y1361833D03*
X1269012Y1368293D03*
X1269132Y1578182D03*
X1272532D03*
X1281192D03*
X1284592D03*
X1273310Y1580678D03*
Y1575592D03*
X1268354D03*
Y1580678D03*
X1280414Y1575686D03*
Y1580678D03*
X1269132Y1578182D03*
X1281192D03*
X1272532D03*
X1281192Y1590094D03*
X1284592D03*
X1269132D03*
X1272532D03*
X1274432Y1602380D03*
X1277832D03*
X1266550Y1599884D03*
X1273654Y1599790D03*
X1278610D03*
X1273310Y1592590D03*
X1268354D03*
X1273310Y1587598D03*
X1268354D03*
X1280414D03*
Y1592590D03*
X1269132Y1590094D03*
X1281192D03*
X1272532D03*
X1274432Y1614292D03*
X1277832D03*
X1266550Y1616788D03*
Y1611796D03*
Y1604876D03*
X1273654Y1611796D03*
Y1604876D03*
X1278610Y1611796D03*
Y1604876D03*
X1273654Y1616788D03*
X1278610D03*
X1274432Y1614292D03*
X1277832D03*
X1274432Y1602380D03*
X1277832D03*
X1271866Y1737108D03*
X1290291Y-29811D03*
Y-33211D03*
Y-29811D03*
Y-33211D03*
X1287795Y-29033D03*
Y-33989D03*
X1296019Y-35472D03*
Y-31598D03*
X1293024Y-36695D03*
X1296034Y-37987D03*
Y-27958D03*
X1296019Y-25443D03*
X1293024Y-26666D03*
X1290291Y-19811D03*
Y-9811D03*
Y-13211D03*
Y-23211D03*
D03*
Y-19811D03*
Y-13211D03*
Y-9811D03*
X1287795Y-9033D03*
Y-13989D03*
Y-19033D03*
Y-23989D03*
X1296019Y-21569D03*
X1293024Y-16637D03*
X1296034Y-17929D03*
X1296019Y-15414D03*
Y-11540D03*
X1290291Y-3211D03*
Y189D03*
Y-3211D03*
Y189D03*
X1287795Y967D03*
Y-3989D03*
X1296034Y-7900D03*
X1296019Y-5385D03*
X1293024Y-6608D03*
X1296019Y4644D03*
X1296034Y2129D03*
X1296019Y-1511D03*
X1293024Y3421D03*
X1296019Y14673D03*
X1296034Y12158D03*
X1296019Y8518D03*
X1293024Y13450D03*
X1296034Y22687D03*
X1296019Y19047D03*
Y25202D03*
X1293024Y23979D03*
X1291280Y58262D03*
X1293860Y58312D03*
X1285201Y58121D03*
X1293430Y84072D03*
X1289210Y81232D03*
X1294354Y103166D03*
Y105912D03*
X1291704Y109427D03*
X1284930Y124922D03*
X1295053Y140181D03*
X1285793Y141562D03*
X1292293Y143162D03*
X1288258Y145501D03*
X1283781Y149115D03*
X1297605Y145824D03*
X1283781Y155788D03*
X1283425Y179272D03*
X1283397Y202085D03*
X1287943Y233748D03*
X1284437Y230280D03*
X1293893Y237962D03*
X1286611Y260908D03*
X1291071Y275543D03*
Y278543D03*
X1290005Y293768D03*
X1295278Y297056D03*
X1290322D03*
X1290005Y290268D03*
X1294500Y299692D03*
X1291100D03*
X1295887Y315571D03*
X1291500Y312862D03*
Y315362D03*
X1291420Y320662D03*
Y318162D03*
X1296630Y463462D03*
X1284220Y463362D03*
X1289936Y732539D03*
X1294937Y746965D03*
X1290520Y746562D03*
X1292904Y782048D03*
X1292572Y785575D03*
X1292614Y789910D03*
X1296719Y1290197D03*
X1299169Y1295467D03*
Y1297967D03*
X1296569D03*
Y1295467D03*
Y1292967D03*
X1299169D03*
X1296581Y1300474D03*
X1299181D03*
X1296576Y1303298D03*
X1299176D03*
X1295150Y1323217D03*
X1298150D03*
X1291010Y1323307D03*
X1288010D03*
X1291205Y1345875D03*
X1286005Y1342768D03*
Y1345875D03*
X1296405Y1342768D03*
X1293805D03*
X1288605D03*
X1291205D03*
X1288605Y1345875D03*
X1293805D03*
X1291405Y1348982D03*
X1294005D03*
X1292916Y1352531D03*
X1290436D03*
X1287956D03*
X1292916Y1358131D03*
X1290436D03*
X1287956D03*
X1283280Y1372301D03*
X1293887Y1370043D03*
X1294477Y1372651D03*
X1290102Y1365789D03*
X1286102Y1365051D03*
X1294312Y1367279D03*
X1292840Y1364821D03*
X1286102Y1368107D03*
X1298836Y1358387D03*
X1296506Y1357637D03*
X1296652Y1578182D03*
X1293252D03*
X1285370Y1575686D03*
Y1580678D03*
X1297430D03*
X1292474D03*
Y1575686D03*
X1297430D03*
X1293252Y1578182D03*
X1284592D03*
X1296652D03*
Y1590094D03*
X1293252D03*
X1289892Y1602380D03*
X1286492D03*
X1298552D03*
X1285714Y1599884D03*
X1290670D03*
X1297774D03*
X1285370Y1587598D03*
Y1592590D03*
X1297430D03*
X1292474D03*
X1297430Y1587598D03*
X1292474D03*
X1293252Y1590094D03*
X1284592D03*
X1296652D03*
X1289892Y1614292D03*
X1286492D03*
X1298552D03*
X1290670Y1616788D03*
X1285714D03*
Y1611796D03*
X1290670D03*
X1285714Y1604876D03*
X1290670D03*
X1297774Y1611796D03*
Y1604876D03*
Y1616788D03*
X1298552Y1614292D03*
X1286492D03*
X1289892D03*
X1298552Y1602380D03*
X1286492D03*
X1289892D03*
X1291866Y1737108D03*
X1299317Y-35486D03*
Y-31612D03*
X1299302Y-38001D03*
Y-27972D03*
X1299317Y-25457D03*
Y-21583D03*
X1299302Y-17943D03*
X1299317Y-15428D03*
Y-11554D03*
X1299302Y-7914D03*
X1299317Y-5399D03*
Y4630D03*
X1299302Y2115D03*
X1299317Y-1525D03*
Y14659D03*
X1299302Y12144D03*
X1299317Y8504D03*
X1299302Y22673D03*
X1299317Y19033D03*
X1299287Y25188D03*
X1311960Y49672D03*
X1301820Y58672D03*
X1314741Y68652D03*
X1311424D03*
X1308174D03*
X1311960Y58152D03*
X1310857Y78542D03*
X1307120Y78562D03*
X1310906Y97807D03*
X1300454Y95302D03*
X1314059Y93877D03*
X1307244Y118452D03*
X1306836Y108242D03*
X1302964Y124633D03*
X1300990Y121812D03*
X1315156Y130656D03*
X1314920Y135361D03*
X1301993Y140462D03*
X1313117Y250605D03*
X1314685Y248651D03*
X1313950Y261612D03*
X1307431Y256099D03*
X1309283Y254162D03*
X1311275Y252297D03*
X1305552Y257974D03*
X1308736Y284948D03*
X1312136D03*
X1308790Y290172D03*
X1302450Y290072D03*
X1307798Y287561D03*
X1313246Y287631D03*
X1307042Y292636D03*
X1303642D03*
X1316218Y318073D03*
X1307442Y306998D03*
X1304042D03*
X1308220Y304262D03*
X1303120Y304162D03*
X1311077Y322996D03*
X1307677D03*
D03*
X1311077D03*
X1314450Y319841D03*
X1312845Y324764D03*
X1305909D03*
X1308600Y653500D03*
X1311420Y738262D03*
X1315020Y739862D03*
X1307469Y787772D03*
X1303017Y785837D03*
X1301034Y784165D03*
X1304260Y788265D03*
X1309930Y789852D03*
X1306701Y794779D03*
X1309210Y792802D03*
X1315169Y1274887D03*
X1315289Y1269717D03*
X1315229Y1272287D03*
X1304149Y1291317D03*
X1301889Y1284987D03*
X1301829Y1290167D03*
X1301859Y1287587D03*
X1304299Y1280967D03*
X1304269Y1283567D03*
X1304239Y1286147D03*
X1304209Y1288747D03*
X1315176Y1280218D03*
X1315181Y1277594D03*
X1299319Y1290197D03*
X1299349Y1287617D03*
X1301686Y1303268D03*
X1304196Y1299248D03*
X1304189Y1293917D03*
X1304201Y1296624D03*
X1301679Y1292937D03*
Y1295437D03*
Y1297937D03*
X1301691Y1300444D03*
X1307656Y1337104D03*
X1305056D03*
X1307656Y1326704D03*
X1305056D03*
X1307656Y1334504D03*
Y1329304D03*
Y1331904D03*
X1305056Y1334504D03*
Y1329304D03*
Y1331904D03*
Y1339704D03*
X1311820Y1330518D03*
Y1333018D03*
X1314936Y1338799D03*
X1312488Y1348353D03*
X1299605Y1342768D03*
X1302549Y1345891D03*
X1302520Y1348762D03*
X1315058Y1349488D03*
X1302549Y1342784D03*
X1312650Y1342572D03*
X1308616Y1363345D03*
Y1360445D03*
X1306082Y1359315D03*
X1306182Y1362315D03*
X1304016Y1363945D03*
Y1361045D03*
X1308616Y1357945D03*
X1303496Y1358387D03*
X1301166Y1357637D03*
X1308712Y1578182D03*
X1305312D03*
X1317372D03*
X1309490Y1575686D03*
X1304534D03*
X1309490Y1580678D03*
X1304534D03*
X1305312Y1578182D03*
X1308712D03*
X1317372Y1590094D03*
X1308712D03*
X1305312D03*
X1301952Y1602380D03*
X1314012D03*
X1310612D03*
X1302730Y1599884D03*
X1309834D03*
X1314790D03*
X1309490Y1587598D03*
X1304534D03*
X1309490Y1592590D03*
X1304534D03*
X1305312Y1590094D03*
X1308712D03*
X1301952Y1614292D03*
X1310612D03*
X1314012D03*
X1302730Y1611796D03*
Y1604876D03*
Y1616788D03*
X1309834D03*
Y1611796D03*
Y1604876D03*
X1314790Y1616788D03*
Y1611796D03*
Y1604876D03*
X1310612Y1614292D03*
X1314012D03*
X1301952D03*
X1310612Y1602380D03*
X1314012D03*
X1301952D03*
X1311866Y1737108D03*
X1318609Y49388D03*
X1316459Y58697D03*
X1330102Y59025D03*
X1321279Y58767D03*
X1317831Y68652D03*
X1327920Y84418D03*
X1316478Y92970D03*
X1329891Y99455D03*
X1329646Y104954D03*
X1330273Y128373D03*
X1323958Y146227D03*
X1326493Y249562D03*
X1317893Y257462D03*
X1328393Y264262D03*
X1325414Y293556D03*
X1328814D03*
X1319903Y299176D03*
X1323303D03*
X1319125Y296540D03*
X1324081D03*
X1324636Y290920D03*
X1329592D03*
X1319618Y318073D03*
X1331745Y332616D03*
X1328480Y323902D03*
X1325080D03*
X1319618Y318073D03*
X1325080Y323902D03*
X1316218Y318073D03*
X1328480Y323902D03*
X1330248Y325670D03*
X1323312D03*
X1321386Y319841D03*
X1329977Y334384D03*
X1330101Y540049D03*
X1327601D03*
X1328530Y747702D03*
X1325210Y744322D03*
X1331519Y1262027D03*
X1331459Y1264597D03*
X1331399Y1267197D03*
X1317889Y1267147D03*
X1320399Y1267117D03*
X1317883Y1269978D03*
X1317895Y1272485D03*
X1320393Y1269948D03*
X1320405Y1272455D03*
X1331177Y1269933D03*
Y1272433D03*
X1317895Y1274985D03*
X1320405Y1274955D03*
X1331177Y1274933D03*
X1331166Y1280248D03*
X1317746D03*
X1320256Y1280218D03*
X1317895Y1277485D03*
X1320405Y1277455D03*
X1331189Y1277440D03*
X1317970Y1322741D03*
Y1319634D03*
X1325770Y1322741D03*
X1323170D03*
X1331570Y1319634D03*
X1323170D03*
X1325770D03*
X1328370D03*
X1320570Y1322741D03*
Y1319634D03*
X1322444Y1329497D03*
X1324924D03*
X1319964D03*
X1322444Y1335097D03*
X1324924D03*
X1319964D03*
X1323370Y1325848D03*
X1325970D03*
X1328514Y1334603D03*
X1330844Y1335353D03*
X1324945Y1346877D03*
X1327196Y1349068D03*
X1322110Y1342755D03*
X1318110Y1342017D03*
X1326320Y1344245D03*
X1324848Y1341787D03*
X1318110Y1345073D03*
X1331288Y1372440D03*
X1327491Y1372358D03*
X1324491Y1372658D03*
X1327491Y1375858D03*
X1331288Y1375940D03*
X1324491Y1375858D03*
X1327491Y1381478D03*
Y1378478D03*
X1331288Y1378560D03*
X1324491Y1381478D03*
Y1378478D03*
X1331304Y1401986D03*
Y1404986D03*
X1327926D03*
X1322228Y1419890D03*
X1322186Y1411326D03*
Y1414326D03*
Y1417326D03*
X1322270Y1422454D03*
X1325084Y1420066D03*
X1325042Y1408502D03*
Y1411502D03*
Y1417502D03*
Y1414502D03*
X1331344Y1414456D03*
X1330804Y1411536D03*
Y1408536D03*
X1331386Y1420020D03*
X1328008D03*
X1331344Y1417456D03*
X1327966Y1408456D03*
Y1411456D03*
Y1417456D03*
Y1414456D03*
X1331428Y1422584D03*
X1328050D03*
X1322312Y1425018D03*
X1325126Y1422630D03*
X1325168Y1425194D03*
X1328092Y1425148D03*
X1331470D03*
X1320772Y1578182D03*
X1329432D03*
X1332832D03*
X1321550Y1580678D03*
X1316594D03*
X1321550Y1575686D03*
X1316594D03*
X1328654D03*
Y1580678D03*
X1317372Y1578182D03*
X1320772D03*
X1329432D03*
Y1590094D03*
X1332832D03*
X1320772D03*
X1322672Y1602380D03*
X1326072D03*
X1321894Y1599884D03*
X1326850D03*
X1321550Y1592590D03*
X1316594D03*
X1321550Y1587598D03*
X1316594D03*
X1328654D03*
Y1592590D03*
X1317372Y1590094D03*
X1320772D03*
X1329432D03*
X1322672Y1614292D03*
X1326072D03*
X1321894Y1611796D03*
Y1604876D03*
X1326850Y1611796D03*
Y1604876D03*
X1321894Y1616788D03*
X1326850D03*
X1322672Y1614292D03*
X1326072D03*
X1322672Y1602380D03*
X1326072D03*
X1341752Y-33211D03*
Y-29811D03*
D03*
Y-33211D03*
X1344248Y-33989D03*
Y-29033D03*
X1332726Y-27681D03*
X1336024Y-27695D03*
X1339019Y-26472D03*
X1332726Y-32055D03*
X1336024Y-32069D03*
X1332741Y-35695D03*
X1336009Y-35709D03*
X1332756Y-38210D03*
X1336024Y-38224D03*
X1339019Y-37001D03*
X1341752Y-19811D03*
Y-13211D03*
Y-23211D03*
Y-9811D03*
Y-19811D03*
Y-23211D03*
Y-9811D03*
Y-13211D03*
X1344248Y-13989D03*
Y-9033D03*
Y-23989D03*
Y-19033D03*
X1332726Y-11497D03*
X1336024Y-11511D03*
X1339019Y-16443D03*
X1332741Y-15137D03*
X1332726Y-17652D03*
X1336009Y-15151D03*
X1336024Y-17666D03*
Y-21540D03*
X1332726Y-21526D03*
X1332741Y-25166D03*
X1336009Y-25180D03*
X1341752Y-3211D03*
Y189D03*
D03*
Y-3211D03*
X1344248Y-3989D03*
Y967D03*
X1336024Y2392D03*
X1336009Y4907D03*
X1332726Y2406D03*
X1332741Y4921D03*
X1339019Y3615D03*
X1332726Y-1468D03*
X1336024Y-1482D03*
X1339019Y-6414D03*
X1336024Y-7637D03*
X1336009Y-5122D03*
X1332726Y-7623D03*
X1332741Y-5108D03*
X1332726Y18590D03*
X1336024Y18576D03*
Y22450D03*
X1332726Y22464D03*
X1339019Y13644D03*
X1336024Y12421D03*
X1336009Y14936D03*
X1332726Y12435D03*
X1332741Y14950D03*
X1332726Y8561D03*
X1336024Y8547D03*
X1336009Y24965D03*
X1332741Y24979D03*
X1339019Y23673D03*
X1338609Y49388D03*
X1333190Y58825D03*
X1346720Y82912D03*
X1345583Y91307D03*
X1336549Y105970D03*
X1339280Y126175D03*
X1344631Y127244D03*
X1332497Y133931D03*
X1333811Y235348D03*
X1344684Y280259D03*
X1348084D03*
X1344684D03*
X1343362Y283155D03*
X1336761Y293404D03*
X1340161D03*
X1335947Y290755D03*
X1340903D03*
X1348824Y328981D03*
X1345424D03*
X1338031Y322693D03*
X1341431D03*
X1335145Y332616D03*
D03*
X1341431Y322693D03*
X1331745Y332616D03*
X1338031Y322693D03*
X1345424Y328981D03*
X1343656Y330749D03*
X1343199Y324461D03*
X1336263D03*
X1336913Y334384D03*
X1344720Y423162D03*
X1337220D03*
X1342220D03*
X1339720D03*
X1333143Y540049D03*
X1340420Y538422D03*
Y541822D03*
X1338652Y536654D03*
Y543590D03*
X1335643Y540048D03*
X1336187Y755635D03*
X1347419Y1259257D03*
X1347379Y1256687D03*
X1336269Y1274957D03*
X1333969Y1264567D03*
X1334029Y1261997D03*
X1333909Y1267167D03*
X1336339Y1269777D03*
X1336279Y1272347D03*
X1347359Y1261857D03*
X1347371Y1264564D03*
X1336519Y1264627D03*
X1336579Y1262057D03*
X1347366Y1267188D03*
X1336459Y1267227D03*
X1333687Y1269903D03*
Y1272403D03*
Y1274903D03*
X1333676Y1280218D03*
X1336261Y1277654D03*
X1333699Y1277410D03*
X1339784Y1306506D03*
X1337184D03*
X1344080Y1305919D03*
X1337663Y1301001D03*
X1343968Y1300579D03*
X1340663Y1301001D03*
X1344080Y1308519D03*
X1334514Y1322757D03*
Y1319650D03*
X1337184Y1309106D03*
X1339784D03*
X1338534Y1319406D03*
X1339784Y1316906D03*
Y1314306D03*
Y1311706D03*
X1337184Y1314306D03*
Y1316906D03*
Y1311706D03*
X1343948Y1317092D03*
Y1319592D03*
X1334414Y1325853D03*
X1347015Y1335876D03*
X1343631Y1332568D03*
X1344532Y1328161D03*
X1347397Y1325320D03*
X1336144Y1341147D03*
X1338288Y1339653D03*
X1340488Y1340853D03*
X1336144Y1338247D03*
X1340214Y1334853D03*
X1340410Y1338017D03*
X1338288Y1336553D03*
X1333174Y1334603D03*
X1335504Y1335353D03*
X1334288Y1372440D03*
X1340288D03*
X1346193Y1372523D03*
X1343193D03*
X1337288Y1372440D03*
Y1375940D03*
X1334288D03*
X1343193Y1376023D03*
X1346193D03*
X1340288Y1375940D03*
X1346304Y1401986D03*
X1343304D03*
X1340304D03*
X1337304D03*
X1334304D03*
Y1404986D03*
X1346304D03*
X1343304D03*
X1340304D03*
X1337304D03*
X1337344Y1414456D03*
X1346344D03*
X1343344D03*
X1340344D03*
X1346534Y1411496D03*
Y1408496D03*
X1334344Y1414456D03*
X1346344Y1417456D03*
X1340344D03*
X1337344D03*
X1334386Y1420020D03*
X1334344Y1417456D03*
X1346386Y1420020D03*
X1343386D03*
X1340386D03*
X1337386D03*
X1343344Y1417456D03*
X1337428Y1422584D03*
X1340428D03*
X1343428D03*
X1334428D03*
X1337328Y1425164D03*
X1340328D03*
X1343328D03*
X1346178Y1425254D03*
X1346278Y1422674D03*
X1334470Y1425148D03*
X1341492Y1578182D03*
X1344892D03*
X1333610Y1575686D03*
Y1580678D03*
X1345670D03*
X1340714D03*
X1345670Y1575686D03*
X1340714D03*
X1332832Y1578182D03*
X1341492D03*
X1344892D03*
X1341492Y1590094D03*
X1344892D03*
X1338132Y1602380D03*
X1334732D03*
X1346792D03*
X1338910Y1599884D03*
X1333954D03*
X1346014D03*
X1333610Y1587598D03*
Y1592590D03*
X1345670D03*
X1340714D03*
X1345670Y1587598D03*
X1340714D03*
X1332832Y1590094D03*
X1341492D03*
X1344892D03*
X1338132Y1614292D03*
X1334732D03*
X1346792D03*
X1338910Y1616788D03*
Y1611796D03*
Y1604876D03*
X1333954Y1616788D03*
Y1611796D03*
Y1604876D03*
X1346014Y1611796D03*
Y1604876D03*
Y1616788D03*
X1346792Y1614292D03*
X1334732D03*
X1338132D03*
X1346792Y1602380D03*
X1334732D03*
X1338132D03*
X1331866Y1737108D03*
X1348610Y84712D03*
X1349480Y77072D03*
X1350550Y101632D03*
X1349570Y104147D03*
X1356223Y131569D03*
X1353394Y131812D03*
X1348620Y136162D03*
X1362793Y145262D03*
X1349704Y145385D03*
X1357888Y145893D03*
X1349220Y140362D03*
X1361111Y236448D03*
X1365124Y282744D03*
X1355224Y284644D03*
X1358624D03*
X1348084Y280259D03*
X1363846Y279848D03*
X1349362Y283155D03*
X1358624Y284644D03*
X1355224D03*
X1353902Y287540D03*
X1359902D03*
X1361771Y332275D03*
X1358371D03*
X1348824Y328981D03*
X1358371Y332275D03*
X1361771D03*
X1350592Y330749D03*
X1355200Y337843D03*
X1351800D03*
X1355200D03*
X1351800D03*
X1356968Y339611D03*
X1350032D03*
X1363539Y334043D03*
X1356603D03*
X1356047Y680000D03*
X1358907Y681262D03*
X1352474Y1256866D03*
X1349964Y1256896D03*
X1352486Y1259373D03*
X1349976Y1259403D03*
X1363258Y1256851D03*
Y1259351D03*
X1349876Y1267158D03*
X1352426Y1267218D03*
X1363266Y1267188D03*
X1349976Y1261903D03*
X1352486Y1261873D03*
Y1264373D03*
X1349976Y1264403D03*
X1363258Y1261851D03*
X1363270Y1264358D03*
X1353982Y1287048D03*
X1362382D03*
X1359382D03*
X1350982D03*
X1350098Y1306208D03*
X1352698D03*
X1355298D03*
X1360498D03*
X1363698D03*
X1357898D03*
X1352698Y1309315D03*
X1350098D03*
X1355498Y1312422D03*
X1358098D03*
X1355298Y1309315D03*
X1357898D03*
X1352092Y1316071D03*
Y1321671D03*
X1357052Y1316071D03*
X1354572D03*
X1357052Y1321671D03*
X1354572D03*
X1360593Y1321872D03*
X1363098Y1320951D03*
X1356983Y1334095D03*
X1359516Y1334058D03*
X1354238Y1329329D03*
X1350238Y1328591D03*
X1358448Y1330819D03*
X1356976Y1328361D03*
X1350238Y1331647D03*
X1352666Y1378560D03*
X1349666D03*
X1352666Y1381560D03*
X1349666D03*
X1352666Y1375940D03*
X1349666D03*
X1355357Y1396020D03*
X1352126Y1401986D03*
X1349426D03*
X1352126Y1404986D03*
X1349426D03*
X1349508Y1420020D03*
X1352166Y1420456D03*
Y1414456D03*
Y1411456D03*
Y1408456D03*
Y1417456D03*
X1349466Y1411456D03*
Y1408456D03*
Y1417456D03*
Y1414456D03*
X1349278Y1422674D03*
X1362410Y1445272D03*
X1356952Y1578182D03*
X1353552D03*
X1365612D03*
X1357730Y1575686D03*
X1352774D03*
X1357730Y1580678D03*
X1352774D03*
X1353552Y1578182D03*
X1356952D03*
X1365612Y1590094D03*
X1356952D03*
X1353552D03*
X1350192Y1602380D03*
X1362252D03*
X1358852D03*
X1350970Y1599884D03*
X1363030D03*
X1358074D03*
X1357730Y1587598D03*
X1352774D03*
X1357730Y1592590D03*
X1352774D03*
X1353552Y1590094D03*
X1356952D03*
X1350192Y1614292D03*
X1362252D03*
X1358852D03*
X1350970Y1611796D03*
Y1604876D03*
Y1616788D03*
X1363030D03*
Y1611796D03*
Y1604876D03*
X1358074Y1616788D03*
Y1611796D03*
Y1604876D03*
X1358852Y1614292D03*
X1362252D03*
X1350192D03*
X1358852Y1602380D03*
X1362252D03*
X1350192D03*
X1351866Y1737108D03*
X1378839Y87626D03*
X1366124Y101529D03*
X1366369Y92450D03*
X1378550Y110692D03*
X1366714Y109506D03*
X1366868Y147341D03*
X1369593Y147462D03*
X1369916Y154132D03*
X1379969Y176330D03*
X1370586Y176366D03*
X1376991Y176430D03*
X1373591D03*
X1380602Y197668D03*
X1370405Y186938D03*
X1377597Y197604D03*
X1375300Y208422D03*
X1369479Y208384D03*
X1370636Y227292D03*
X1369410Y224504D03*
X1375257Y229756D03*
X1373493Y227762D03*
X1380638Y249094D03*
Y245694D03*
X1378452Y236055D03*
X1377742Y244372D03*
Y250372D03*
X1380522Y263636D03*
Y260236D03*
D03*
Y263636D03*
X1377626Y258914D03*
Y264914D03*
X1368524Y282744D03*
D03*
X1365124D03*
X1369846Y279848D03*
X1378306Y657608D03*
X1374668Y659708D03*
X1378306Y657608D03*
Y669608D03*
X1374668Y671708D03*
X1372381Y661428D03*
X1371931Y672978D03*
X1374668Y659708D03*
X1378306Y669608D03*
X1374668Y671708D03*
X1378306Y681608D03*
X1374668Y683708D03*
X1371931Y685278D03*
X1374668Y683708D03*
X1378306Y681608D03*
Y705608D03*
X1374668Y695708D03*
X1378306Y693608D03*
X1374668Y707708D03*
X1372243Y697108D03*
X1374668Y695708D03*
X1378306Y693608D03*
Y705608D03*
Y717608D03*
X1374668Y719708D03*
X1372243Y709108D03*
Y721108D03*
X1374668Y707708D03*
Y719708D03*
X1378306Y717608D03*
X1374938Y1161569D03*
Y1170069D03*
X1379579Y1259317D03*
X1368379Y1259287D03*
X1379639Y1256747D03*
X1368439Y1256717D03*
X1365768Y1256821D03*
Y1259321D03*
X1365776Y1267158D03*
X1368326Y1267218D03*
X1379519Y1261917D03*
X1379531Y1264624D03*
X1379526Y1267248D03*
X1368361Y1264594D03*
X1368369Y1261897D03*
X1365768Y1261821D03*
X1365780Y1264328D03*
X1375463Y1287048D03*
X1372463D03*
X1370662Y1305980D03*
X1371912Y1303480D03*
X1376208Y1305919D03*
Y1303319D03*
X1371912Y1300880D03*
X1376208Y1300719D03*
Y1295586D03*
X1371912Y1295747D03*
Y1298280D03*
X1376208Y1298119D03*
X1369312Y1303480D03*
X1366642Y1306224D03*
X1369312Y1300880D03*
Y1295747D03*
Y1298280D03*
X1376208Y1308519D03*
X1366542Y1312427D03*
X1366642Y1309331D03*
X1376076Y1317092D03*
Y1319592D03*
X1368272Y1324821D03*
X1372538Y1324591D03*
X1370338Y1323091D03*
X1372538Y1321691D03*
X1365376Y1321938D03*
X1367635Y1320904D03*
X1379271Y1335963D03*
X1375814Y1332653D03*
X1377214Y1327653D03*
X1368272Y1327721D03*
X1370438Y1326091D03*
X1372538Y1327491D03*
X1377054Y1394028D03*
X1376666Y1402778D03*
X1376686Y1399758D03*
X1367316Y1399053D03*
Y1403458D03*
X1377060Y1411231D03*
X1367436Y1414778D03*
X1370891Y1410306D03*
X1378417Y1415292D03*
X1367316Y1407458D03*
X1367889Y1419235D03*
X1371960Y1436172D03*
X1365040Y1431142D03*
X1365235Y1428637D03*
X1370250Y1433715D03*
X1367620Y1431472D03*
X1367170Y1453142D03*
X1368842Y1449261D03*
X1364800Y1449231D03*
X1368980Y1457122D03*
X1370041Y1460374D03*
X1369012Y1578182D03*
X1377672D03*
X1381072D03*
X1369790Y1580678D03*
X1364834D03*
X1369790Y1575592D03*
X1364834D03*
X1376894Y1575686D03*
Y1580678D03*
X1365612Y1578182D03*
X1377672D03*
X1369012D03*
X1381072Y1590094D03*
X1369012D03*
X1377672D03*
X1374312Y1602380D03*
X1370912D03*
X1375090Y1599790D03*
X1370134D03*
X1369790Y1592590D03*
X1364834D03*
X1369790Y1587598D03*
X1364834D03*
X1376894D03*
Y1592590D03*
X1365612Y1590094D03*
X1377672D03*
X1369012D03*
X1374312Y1614292D03*
X1370912D03*
X1375090Y1611796D03*
Y1604876D03*
Y1616788D03*
X1370134Y1611796D03*
Y1604876D03*
Y1616788D03*
X1370912Y1614292D03*
X1374312D03*
X1370912Y1602380D03*
X1374312D03*
X1371866Y1737108D03*
X1393250Y93802D03*
X1383480Y88932D03*
X1389609Y145291D03*
X1389443Y147859D03*
X1398006Y197668D03*
X1384002D03*
X1392656D03*
X1389256D03*
X1386780D03*
X1395321D03*
X1384002D03*
X1389256D03*
X1380602D03*
X1392656D03*
X1395960Y226422D03*
X1393460D03*
X1386868Y222937D03*
X1384017Y223697D03*
X1386138Y225411D03*
X1384895Y221346D03*
X1381951Y221420D03*
X1386630Y242051D03*
Y238651D03*
X1380638Y245694D03*
X1386630Y238651D03*
X1380638Y249094D03*
X1386630Y242051D03*
X1381235Y236020D03*
X1383734Y243329D03*
Y237329D03*
X1388778Y250661D03*
X1390600Y248262D03*
X1388754Y257203D03*
Y253803D03*
X1386273Y268670D03*
X1388754Y253803D03*
Y257203D03*
X1388908Y260301D03*
X1386237Y265620D03*
X1386273Y272070D03*
Y268670D03*
Y272070D03*
X1386237Y275200D03*
X1385190Y501242D03*
X1390220Y497742D03*
X1392685Y498992D03*
X1387550Y502922D03*
X1387600Y499182D03*
X1391260Y507082D03*
X1381131Y656378D03*
X1393206Y664708D03*
X1389568Y662608D03*
X1381131Y668378D03*
X1395831Y666278D03*
X1386931Y660978D03*
X1393206Y664708D03*
X1389568Y662608D03*
X1393206Y679208D03*
X1389568Y677108D03*
Y691608D03*
X1381131Y680278D03*
X1396031Y680678D03*
X1386931Y675478D03*
X1387143Y690208D03*
X1393206Y679208D03*
X1389568Y677108D03*
Y706108D03*
X1393206Y693708D03*
Y708208D03*
X1380731Y692208D03*
X1395631Y695108D03*
X1380731Y704208D03*
X1387143Y704708D03*
X1393206Y693708D03*
X1389568Y691608D03*
Y706108D03*
X1393199Y722708D03*
X1389561Y720608D03*
X1380731Y716208D03*
X1395631Y709608D03*
X1387143Y719235D03*
X1393206Y708208D03*
X1393199Y722708D03*
X1389561Y720608D03*
X1385338Y735098D03*
X1388976Y737198D03*
X1395631Y724135D03*
X1382920Y733725D03*
X1391408Y738625D03*
X1385338Y735098D03*
X1388976Y737198D03*
X1384173Y1161549D03*
X1384089Y1153369D03*
X1386673Y1161520D03*
Y1153340D03*
X1396081Y1161569D03*
Y1153369D03*
X1384173Y1169599D03*
X1386673Y1169570D03*
X1396081Y1170069D03*
X1384652Y1256866D03*
X1382142Y1256896D03*
X1384664Y1259373D03*
X1382154Y1259403D03*
X1395436Y1256851D03*
Y1259351D03*
X1384586Y1267278D03*
X1395426Y1267188D03*
X1382036Y1267218D03*
X1382154Y1261903D03*
X1384664Y1261873D03*
Y1264373D03*
X1382154Y1264403D03*
X1395436Y1261851D03*
X1395448Y1264358D03*
X1382226Y1306208D03*
X1384826D03*
X1387426D03*
X1390026D03*
X1392626D03*
X1395826D03*
X1386700Y1321671D03*
X1389180D03*
X1382226Y1309315D03*
X1384826D03*
X1390226Y1312422D03*
X1387626D03*
X1390026Y1309315D03*
X1387426D03*
X1384220Y1316071D03*
Y1321671D03*
X1389180Y1316071D03*
X1386700D03*
X1392770Y1321177D03*
X1395100Y1321927D03*
X1390758Y1333473D03*
X1392076Y1335658D03*
X1386366Y1329329D03*
X1382366Y1328591D03*
X1390576Y1330819D03*
X1389104Y1328361D03*
X1382366Y1331647D03*
X1388813Y1393160D03*
X1396115Y1405289D03*
Y1412789D03*
X1396615Y1420289D03*
X1387470Y1418302D03*
X1385109Y1410427D03*
X1387068Y1413991D03*
X1384695Y1425047D03*
X1381066Y1425008D03*
X1392620Y1446708D03*
X1382600Y1563480D03*
X1384840Y1565640D03*
X1386790Y1563610D03*
X1392475Y1576097D03*
X1381850Y1575686D03*
Y1580678D03*
X1396600Y1582500D03*
X1381072Y1578182D03*
X1386372Y1602380D03*
X1382972D03*
X1387150Y1599884D03*
X1382194D03*
X1381850Y1587598D03*
Y1592590D03*
X1396600Y1594000D03*
Y1590200D03*
Y1586400D03*
X1381072Y1590094D03*
X1386372Y1614292D03*
X1382972D03*
X1387150Y1616788D03*
X1382194D03*
X1387150Y1611796D03*
Y1604876D03*
X1382194Y1611796D03*
Y1604876D03*
X1382972Y1614292D03*
X1386372D03*
X1382972Y1602380D03*
X1386372D03*
X1395325Y1606862D03*
X1386200Y1645700D03*
X1386600Y1641400D03*
X1391866Y1737108D03*
X1412954Y138742D03*
X1409558Y151948D03*
X1404402Y138742D03*
X1407029Y152732D03*
X1410370Y138742D03*
X1406970D03*
X1412284Y171696D03*
X1409558Y156904D03*
X1407029Y156132D03*
X1408229Y184263D03*
X1404829D03*
X1401341Y177159D03*
X1404741D03*
X1413950Y184263D03*
X1407613Y177159D03*
X1398770D03*
X1402258Y184263D03*
X1411101D03*
X1409716Y171696D03*
X1401240Y171672D03*
X1401341Y177159D03*
X1404829Y184263D03*
X1404741Y177159D03*
X1408229Y184263D03*
X1412284Y171696D03*
X1407178Y171684D03*
X1403778D03*
X1410186Y197668D03*
X1406786D03*
X1401406D03*
X1404071D03*
X1412851D03*
X1398006D03*
X1406786D03*
X1401406D03*
X1410186D03*
X1410820Y220018D03*
X1407420D03*
X1404630D03*
X1412270Y230952D03*
X1396900Y228932D03*
X1407420Y220018D03*
X1410820D03*
X1404385Y240929D03*
X1400985D03*
X1405436Y238378D03*
X1400207Y238257D03*
X1404385Y240929D03*
X1400985D03*
X1407913Y1161569D03*
X1410413Y1153369D03*
X1407913D03*
X1410613Y1161569D03*
X1398831D03*
Y1153369D03*
X1407913Y1170069D03*
X1410613D03*
X1398831D03*
X1411909Y1259257D03*
X1400599Y1256717D03*
X1411969Y1256687D03*
X1397946Y1256821D03*
Y1259321D03*
X1400539Y1259287D03*
X1400521Y1264594D03*
X1400529Y1261897D03*
X1397936Y1267158D03*
X1400486Y1267218D03*
X1411849Y1261857D03*
X1411861Y1264564D03*
X1411856Y1267188D03*
X1397946Y1261821D03*
X1397958Y1264328D03*
X1410819Y1287198D03*
X1407819D03*
X1399419D03*
X1402419D03*
X1398770Y1306224D03*
X1404040Y1303480D03*
X1408336Y1305919D03*
Y1303319D03*
X1404040Y1300880D03*
X1408336Y1300719D03*
Y1295586D03*
X1404040Y1295747D03*
Y1298280D03*
X1408336Y1298119D03*
X1401440Y1303480D03*
X1402790Y1305980D03*
X1401440Y1300880D03*
Y1295747D03*
Y1298280D03*
X1408336Y1308519D03*
X1398670Y1312427D03*
X1398770Y1309331D03*
X1408204Y1317092D03*
Y1319592D03*
X1400400Y1324821D03*
X1404666Y1324591D03*
X1402466Y1323091D03*
X1404666Y1321691D03*
X1397430Y1321177D03*
X1399760Y1321927D03*
X1411124Y1335924D03*
X1407719Y1332560D03*
X1408969Y1327645D03*
X1402566Y1326091D03*
X1400400Y1327721D03*
X1404666Y1327491D03*
X1412961Y1387387D03*
X1403615Y1405289D03*
X1411115D03*
Y1412789D03*
X1403615Y1420289D03*
X1411115D03*
X1405876Y1453298D03*
X1403687Y1444711D03*
X1400287D03*
X1400220Y1518862D03*
X1403590Y1532255D03*
X1403350Y1521335D03*
X1409248Y1528862D03*
X1403740Y1548375D03*
X1403590Y1537155D03*
X1403740Y1543475D03*
X1400160Y1543342D03*
X1404433Y1565037D03*
X1407440Y1557552D03*
X1404433Y1570037D03*
X1402536Y1576097D03*
X1398700Y1597800D03*
X1407200Y1591400D03*
X1402680Y1597700D03*
X1411070Y1603282D03*
X1400000Y1630362D03*
X1410900Y1624800D03*
X1400000Y1642362D03*
Y1634362D03*
Y1638362D03*
X1396900Y1642100D03*
X1411866Y1737108D03*
X1415684Y171696D03*
X1417350Y184263D03*
X1423110D03*
X1426510D03*
X1420222D03*
X1418268Y171696D03*
X1413950Y184263D03*
X1423110D03*
X1417350D03*
X1426510D03*
X1415684Y171696D03*
X1413350Y220018D03*
X1416020D03*
X1424690D03*
X1424520Y225002D03*
X1416810Y225422D03*
X1428640Y230022D03*
X1428336Y232762D03*
X1418630Y220018D03*
X1422030D03*
X1413847Y239528D03*
X1426020Y261501D03*
X1428940Y269292D03*
X1426647Y329050D03*
X1417022Y621419D03*
X1424119Y1161520D03*
X1426619D03*
X1424119Y1153369D03*
X1426619D03*
Y1169570D03*
X1424119D03*
X1416999Y1256866D03*
X1414489Y1256896D03*
X1417011Y1259373D03*
X1414501Y1259403D03*
X1427783Y1256851D03*
Y1259351D03*
X1414366Y1267158D03*
X1416916Y1267218D03*
X1427786Y1267158D03*
X1414501Y1261903D03*
X1417011Y1261873D03*
Y1264373D03*
X1414501Y1264403D03*
X1427783Y1261851D03*
X1427795Y1264358D03*
X1414354Y1306208D03*
X1416954D03*
X1419554D03*
X1422154D03*
X1424754D03*
X1427954D03*
X1418828Y1316071D03*
X1416348D03*
X1418828Y1321671D03*
X1416348D03*
X1421308Y1316071D03*
Y1321671D03*
X1414354Y1309315D03*
X1416954D03*
X1419554D03*
X1422354Y1312422D03*
X1419754D03*
X1422154Y1309315D03*
X1424898Y1321177D03*
X1427228Y1321927D03*
X1421294Y1334095D03*
X1423656Y1335468D03*
X1418494Y1329329D03*
X1414494Y1328591D03*
X1422704Y1330819D03*
X1421232Y1328361D03*
X1414494Y1331647D03*
X1422594Y1383301D03*
X1419995Y1397492D03*
X1426872Y1405811D03*
X1422371Y1407722D03*
X1429345Y1433695D03*
X1424930Y1433850D03*
X1419746Y1435932D03*
X1427349Y1442776D03*
X1414264Y1439494D03*
X1419256Y1440258D03*
X1423829Y1442776D03*
X1414350Y1516435D03*
X1414590Y1532255D03*
X1414350Y1521335D03*
X1414590Y1537155D03*
X1414740Y1543475D03*
Y1548375D03*
X1418241Y1583441D03*
X1422145Y1575362D03*
X1422680Y1582100D03*
X1419450Y1596150D03*
X1423700Y1600400D03*
X1426680Y1603262D03*
X1425770Y1633772D03*
X1429250Y1623391D03*
X1419270Y1631000D03*
X1413230Y1641042D03*
X1438609Y49388D03*
X1434600Y59262D03*
X1441125Y57362D03*
X1438680Y64412D03*
X1444275Y57262D03*
X1432220Y61862D03*
X1440800Y66862D03*
X1429382Y184263D03*
X1432660Y220018D03*
X1436060D03*
X1442434Y210757D03*
X1441490Y224062D03*
X1438720Y220018D03*
X1430000D03*
X1430120Y225182D03*
X1436060Y220018D03*
X1432660D03*
X1431636Y230448D03*
X1444570Y238372D03*
X1431933Y238125D03*
X1430130Y259342D03*
X1431431Y267378D03*
X1436436Y300319D03*
X1436120Y315772D03*
X1436320Y305862D03*
Y303362D03*
X1436120Y318272D03*
X1436232Y344176D03*
X1437177Y720965D03*
X1433418Y729104D03*
X1435387Y1161569D03*
X1435837Y1153369D03*
X1432887Y1161569D03*
X1433337Y1153369D03*
X1435387Y1170069D03*
X1432887D03*
X1444099Y1259397D03*
X1432899Y1259257D03*
X1444159Y1256827D03*
X1432959Y1256687D03*
X1430293Y1256821D03*
Y1259321D03*
X1444051Y1264704D03*
X1444039Y1261997D03*
X1444046Y1267328D03*
X1432889Y1261867D03*
X1432881Y1264564D03*
X1432846Y1267188D03*
X1430296Y1267128D03*
X1430293Y1261821D03*
X1430305Y1264328D03*
X1437258Y1287198D03*
X1445106Y1287158D03*
X1440258Y1287198D03*
X1437182Y1298991D03*
X1430898Y1306224D03*
X1434582Y1304191D03*
Y1306791D03*
Y1301591D03*
Y1296458D03*
Y1298991D03*
X1440507Y1305430D03*
Y1302830D03*
Y1300230D03*
X1440536Y1296455D03*
X1440464Y1308519D03*
X1437182Y1304191D03*
Y1306791D03*
Y1301591D03*
Y1296458D03*
X1430798Y1312427D03*
X1430898Y1309331D03*
X1440332Y1317092D03*
Y1319592D03*
X1432528Y1324821D03*
X1436794Y1324591D03*
X1434594Y1323091D03*
X1436794Y1321691D03*
X1429558Y1321177D03*
X1431888Y1321927D03*
X1443785Y1335981D03*
X1440879Y1333085D03*
X1441332Y1327793D03*
X1434694Y1326091D03*
X1432528Y1327721D03*
X1436794Y1327491D03*
X1439155Y1399064D03*
X1437443Y1406289D03*
X1435462Y1393009D03*
X1431717Y1420625D03*
Y1417125D03*
Y1409125D03*
X1431829Y1412370D03*
X1443325Y1410068D03*
X1434312Y1415197D03*
X1431717Y1427632D03*
Y1424125D03*
X1433750Y1429208D03*
X1430204Y1452014D03*
X1444468Y1570610D03*
X1433720Y1569762D03*
X1438300Y1598400D03*
X1440105Y1593352D03*
X1430250Y1608442D03*
X1438300Y1611000D03*
Y1606800D03*
Y1602600D03*
X1430250Y1612812D03*
X1441800Y1620300D03*
Y1632900D03*
Y1628700D03*
Y1624500D03*
X1438547Y1638212D03*
X1443617D03*
X1431575Y1634842D03*
X1442573Y1649862D03*
X1442587Y1659242D03*
X1438273Y1671103D03*
X1431866Y1737108D03*
X1458609Y49388D03*
X1446000Y67802D03*
X1458720Y153362D03*
Y149362D03*
Y145362D03*
Y169862D03*
Y165862D03*
Y161862D03*
Y157862D03*
X1450720Y169862D03*
X1458720Y181862D03*
Y177862D03*
Y173862D03*
X1450720Y181862D03*
Y177862D03*
X1456423Y209362D03*
X1453823Y205982D03*
X1449110Y233742D03*
X1446830Y236232D03*
X1453670Y278170D03*
X1455600Y297200D03*
X1459312Y341130D03*
X1460849Y343327D03*
X1445777Y362021D03*
X1460600Y352742D03*
X1449777Y362021D03*
X1456700Y369642D03*
X1449296Y410497D03*
Y407347D03*
X1449600Y402322D03*
X1460814Y654892D03*
X1457176Y656992D03*
D03*
X1460814Y654892D03*
Y666892D03*
X1457176Y668992D03*
X1454889Y658712D03*
X1454439Y670262D03*
X1460814Y666892D03*
X1457176Y668992D03*
X1460814Y678892D03*
X1457176Y680992D03*
X1460814Y690892D03*
X1454439Y682562D03*
X1460814Y678892D03*
X1457176Y680992D03*
Y704992D03*
Y692992D03*
X1460814Y702892D03*
X1454751Y694392D03*
Y706392D03*
X1460814Y690892D03*
X1457176Y704992D03*
Y692992D03*
X1460814Y702892D03*
Y714892D03*
X1457176Y716992D03*
X1454439Y718362D03*
X1457176Y716992D03*
X1460814Y714892D03*
X1459057Y733545D03*
X1457597Y739035D03*
X1456237Y726945D03*
X1457620Y736195D03*
X1460187Y729805D03*
X1457714Y741622D03*
X1458911Y1161569D03*
X1447149D03*
X1449649D03*
X1447299Y1153369D03*
X1449799D03*
X1458911Y1170069D03*
X1447149D03*
X1449649D03*
X1449176Y1256866D03*
X1446666Y1256896D03*
X1449188Y1259373D03*
X1446678Y1259403D03*
X1459960Y1259351D03*
Y1256851D03*
X1449106Y1267358D03*
X1459886Y1267218D03*
X1446556Y1267298D03*
X1446678Y1261903D03*
X1449188Y1261873D03*
Y1264373D03*
X1446678Y1264403D03*
X1459960Y1261851D03*
X1459972Y1264358D03*
X1453366Y1287198D03*
X1458766D03*
X1461766D03*
X1450366D03*
X1446482Y1306208D03*
X1449082D03*
X1451682D03*
X1456882D03*
X1460082D03*
X1454282D03*
X1450956Y1321671D03*
X1448476D03*
X1453436Y1316071D03*
Y1321671D03*
X1446482Y1309315D03*
X1451882Y1312422D03*
X1449082Y1309315D03*
X1451682D03*
X1454482Y1312422D03*
X1454282Y1309315D03*
X1450956Y1316071D03*
X1448476D03*
X1457026Y1321177D03*
X1461686D03*
X1459356Y1321927D03*
X1453303Y1334095D03*
X1455436Y1335598D03*
X1450622Y1329329D03*
X1446622Y1328591D03*
X1454832Y1330819D03*
X1453360Y1328361D03*
X1446622Y1331647D03*
X1459968Y1402765D03*
X1451176Y1399026D03*
X1461377Y1417844D03*
X1460224Y1407545D03*
X1458138Y1409955D03*
X1454829Y1439732D03*
X1459135Y1439627D03*
X1459136Y1442241D03*
X1455006Y1447938D03*
X1459111Y1445669D03*
Y1448669D03*
X1457577Y1526689D03*
X1457817Y1542509D03*
X1457967Y1553729D03*
X1458200Y1565037D03*
Y1560037D03*
X1462295Y1578182D03*
X1461517Y1575686D03*
Y1580678D03*
X1462295Y1590094D03*
X1446600Y1595400D03*
X1461517Y1587598D03*
Y1592590D03*
X1456030Y1590302D03*
X1456120Y1586262D03*
X1453600Y1595662D03*
X1460441Y1602441D03*
X1446786Y1610639D03*
X1451500Y1612800D03*
X1451580Y1627990D03*
X1454167Y1638302D03*
X1459127D03*
X1448507Y1638212D03*
X1452757Y1671399D03*
X1446380Y1676291D03*
X1474142Y61767D03*
X1470220Y145362D03*
X1462000Y153362D03*
X1470220Y169862D03*
X1465179Y213102D03*
X1470101Y207751D03*
X1472335Y209362D03*
X1466940Y230272D03*
X1463833Y230448D03*
X1477700Y236522D03*
X1463808Y244948D03*
X1463833Y235566D03*
X1468620Y258857D03*
X1467230Y252472D03*
X1471510Y252878D03*
X1463950Y258172D03*
X1463330Y264060D03*
X1463510Y273878D03*
X1475452Y289708D03*
X1475352Y306308D03*
X1476826Y312177D03*
X1462777Y362021D03*
X1470877Y374496D03*
X1463277Y406446D03*
X1470954D03*
X1475790Y404842D03*
X1473310Y418502D03*
X1469777Y418396D03*
X1469951Y429251D03*
X1469720Y434542D03*
X1469760Y452622D03*
X1471460Y633402D03*
X1468060D03*
X1466292Y631634D03*
X1473228D03*
X1472076Y657392D03*
X1475714Y659492D03*
X1463639Y653662D03*
X1469651Y655992D03*
X1462010Y645842D03*
X1465171Y647132D03*
X1469020Y647102D03*
X1472076Y657392D03*
Y671892D03*
X1475714Y673992D03*
X1463639Y665662D03*
X1478139Y660892D03*
X1469439Y670262D03*
X1472076Y671892D03*
X1475714Y659492D03*
Y673992D03*
Y688492D03*
X1472076Y686392D03*
X1463639Y677562D03*
X1463239Y689492D03*
X1478139Y689892D03*
X1469651Y684992D03*
X1472076Y686392D03*
X1475714Y688492D03*
X1472076Y700892D03*
X1475714Y702992D03*
X1463239Y701492D03*
X1478139Y704392D03*
X1469477Y699475D03*
X1472076Y700892D03*
X1475714Y702992D03*
Y717492D03*
X1472076Y715392D03*
X1463239Y713492D03*
X1478139Y718892D03*
X1469651Y713992D03*
X1472076Y715392D03*
X1475714Y717492D03*
X1468876Y728392D03*
X1472514Y730492D03*
X1474100Y735662D03*
X1466451Y726992D03*
X1474939Y731892D03*
X1468876Y728392D03*
X1472514Y730492D03*
X1464999Y1259317D03*
X1476369Y1259237D03*
X1465059Y1256747D03*
X1462470Y1259321D03*
Y1256821D03*
X1476291Y1275224D03*
X1464946Y1267248D03*
X1464989Y1261927D03*
X1464981Y1264624D03*
X1476339Y1264467D03*
Y1267037D03*
X1476309Y1261807D03*
X1476279Y1269637D03*
X1476291Y1272344D03*
X1462396Y1267188D03*
X1462470Y1261821D03*
X1462482Y1264328D03*
X1476291Y1278104D03*
X1472592Y1306345D03*
X1474180Y1300407D03*
X1471180D03*
X1463026Y1306224D03*
X1465696Y1303480D03*
X1467046Y1305980D03*
X1468296Y1303480D03*
X1465696Y1300880D03*
X1468296D03*
X1472361Y1322440D03*
X1472592Y1308945D03*
Y1316745D03*
Y1314145D03*
Y1311545D03*
X1462926Y1312427D03*
X1463026Y1309331D03*
X1464016Y1321927D03*
X1466819Y1324018D03*
X1469019Y1322618D03*
X1473956Y1341068D03*
X1472460Y1330493D03*
Y1333043D03*
X1475576Y1338799D03*
X1469019Y1325518D03*
X1464680Y1325772D03*
X1469019Y1328418D03*
X1466919Y1327018D03*
X1464680Y1328672D03*
X1475599Y1349468D03*
X1475959Y1385027D03*
X1476000Y1393027D03*
X1465747Y1401405D03*
X1475935Y1439627D03*
X1475936Y1442241D03*
X1467550Y1439642D03*
X1467536Y1442241D03*
X1467567Y1445669D03*
Y1448669D03*
X1475967Y1445669D03*
Y1448669D03*
X1474355Y1578182D03*
X1477755D03*
X1465695D03*
X1473577Y1580678D03*
Y1575686D03*
X1466473D03*
Y1580678D03*
X1477755Y1578182D03*
X1462295D03*
X1474355D03*
X1465695D03*
X1477755Y1590094D03*
X1474355D03*
X1465695D03*
X1467595Y1602380D03*
X1470995D03*
X1479655D03*
X1471773Y1599884D03*
X1466817D03*
X1473577Y1592590D03*
Y1587598D03*
X1466473D03*
Y1592590D03*
X1477755Y1590094D03*
X1462295D03*
X1474355D03*
X1465695D03*
X1467595Y1614292D03*
X1470995D03*
X1479655D03*
X1466817Y1611796D03*
X1471773D03*
X1466817Y1604876D03*
X1471773D03*
Y1616788D03*
X1466817D03*
X1467595Y1614292D03*
X1470995D03*
X1467595Y1602380D03*
X1470995D03*
X1472565Y1623635D03*
X1463767Y1638302D03*
X1476570Y1657974D03*
Y1661124D03*
X1482650Y-29811D03*
Y-33211D03*
Y-29811D03*
Y-33211D03*
X1480154Y-29033D03*
Y-33989D03*
X1491661Y-27972D03*
X1491676Y-25457D03*
X1488393Y-27958D03*
X1488378Y-25443D03*
X1485383Y-26666D03*
X1491661Y-38001D03*
X1491676Y-35486D03*
X1488393Y-37987D03*
X1488378Y-35472D03*
Y-31598D03*
X1491676Y-31612D03*
X1485383Y-36695D03*
X1482650Y-19811D03*
Y-23211D03*
Y-13211D03*
Y-9811D03*
Y-19811D03*
Y-23211D03*
Y-9811D03*
Y-13211D03*
X1480154Y-9033D03*
Y-13989D03*
Y-19033D03*
Y-23989D03*
X1491661Y-17943D03*
X1491676Y-15428D03*
X1488393Y-17929D03*
X1488378Y-15414D03*
Y-11540D03*
X1491676Y-11554D03*
X1485383Y-16637D03*
X1488378Y-21569D03*
X1491676Y-21583D03*
X1482650Y-3211D03*
Y189D03*
D03*
Y-3211D03*
X1480154Y967D03*
Y-3989D03*
X1485383Y3421D03*
X1491661Y2115D03*
X1491676Y4630D03*
X1488393Y2129D03*
X1488378Y4644D03*
X1491661Y-7914D03*
X1491676Y-5399D03*
X1488393Y-7900D03*
X1488378Y-5385D03*
Y-1511D03*
X1491676Y-1525D03*
X1485383Y-6608D03*
X1488378Y14673D03*
X1488393Y12158D03*
Y22687D03*
X1491661Y22673D03*
X1491676Y14659D03*
X1491661Y12144D03*
X1485383Y13450D03*
X1488378Y8518D03*
X1491676Y8504D03*
X1488378Y19047D03*
X1491676Y19033D03*
X1485383Y23979D03*
X1488378Y25202D03*
X1491646Y25188D03*
X1478609Y49388D03*
X1487958Y236062D03*
X1490060Y255378D03*
X1485320Y260362D03*
X1487058Y281456D03*
X1478745Y281508D03*
X1493289Y280027D03*
X1484958Y289656D03*
X1487658D03*
X1478526Y289677D03*
X1481445Y289708D03*
X1484758Y312356D03*
X1487458D03*
X1484858Y305956D03*
X1487558D03*
X1479745Y312208D03*
X1478426Y306277D03*
X1481345Y306308D03*
X1481360Y358792D03*
X1481484Y361688D03*
X1486884Y374338D03*
X1479207D03*
X1478203Y406207D03*
X1488500Y410152D03*
X1493384Y419263D03*
X1481384Y419392D03*
X1484805Y427577D03*
X1478539Y675462D03*
X1481539Y1259377D03*
X1478999Y1259257D03*
X1481479Y1261947D03*
X1481419Y1264547D03*
X1481431Y1267254D03*
X1478939Y1261827D03*
X1478879Y1264427D03*
X1478891Y1267134D03*
X1481359Y1271447D03*
X1492039D03*
X1481359Y1274144D03*
X1492091D03*
X1478859Y1271417D03*
Y1274114D03*
X1481361Y1280054D03*
X1492101D03*
X1478821D03*
X1481359Y1277024D03*
X1492091D03*
X1478859Y1276994D03*
X1491840Y1300447D03*
X1486410Y1322741D03*
X1483810D03*
X1486410Y1319634D03*
X1483810D03*
X1481210Y1322741D03*
Y1319634D03*
X1492210D03*
X1489010D03*
X1478610Y1322741D03*
Y1319634D03*
X1484010Y1325848D03*
X1486610D03*
X1485564Y1335097D03*
X1483084D03*
X1485564Y1329497D03*
X1483084D03*
X1480604Y1335097D03*
Y1329497D03*
X1489154Y1334603D03*
X1493814D03*
X1491484Y1335353D03*
X1485523Y1347521D03*
X1487386Y1349258D03*
X1482750Y1342755D03*
X1478750Y1342017D03*
X1486960Y1344245D03*
X1485488Y1341787D03*
X1478750Y1345073D03*
X1481155Y1387742D03*
X1481255Y1382042D03*
X1478559Y1385027D03*
X1481159Y1384727D03*
X1481155Y1396342D03*
Y1398942D03*
Y1390342D03*
X1478600Y1393027D03*
X1481107Y1393095D03*
X1479658Y1405397D03*
X1485301Y1409442D03*
X1485274Y1406911D03*
X1485380Y1412202D03*
X1479671Y1410411D03*
Y1412911D03*
Y1407911D03*
X1482201Y1409442D03*
X1482174Y1406911D03*
X1482280Y1412202D03*
X1485387Y1420002D03*
X1484395Y1439598D03*
X1484336Y1442241D03*
X1484442Y1445557D03*
Y1448557D03*
X1486415Y1578182D03*
X1489815D03*
X1490593Y1580678D03*
Y1575686D03*
X1485637D03*
Y1580678D03*
X1478533D03*
Y1575686D03*
X1489815Y1578182D03*
X1486415D03*
X1489815Y1590094D03*
X1486415D03*
X1491715Y1602380D03*
X1483055D03*
X1495115D03*
X1490937Y1599884D03*
X1478877D03*
X1483833D03*
X1490593Y1587598D03*
X1485637D03*
Y1592590D03*
X1490593D03*
X1478533D03*
Y1587598D03*
X1489815Y1590094D03*
X1486415D03*
X1491715Y1614292D03*
X1483055D03*
X1495115D03*
X1490937Y1604876D03*
Y1611796D03*
Y1616788D03*
X1483833D03*
X1478877D03*
Y1611796D03*
X1483833D03*
X1478877Y1604876D03*
X1483833D03*
X1491715Y1614292D03*
X1479655D03*
X1483055D03*
X1491715Y1602380D03*
X1479655D03*
X1483055D03*
X1478724Y1637189D03*
X1480800Y1663600D03*
X1491866Y1737108D03*
X1498609Y49388D03*
X1510500Y125992D03*
X1505821Y215802D03*
X1503020D03*
X1505378Y225502D03*
X1496720Y225292D03*
X1509571Y239053D03*
X1507860Y249792D03*
X1504650Y254392D03*
X1508049Y280056D03*
X1508558Y291175D03*
X1504602Y312867D03*
X1509539Y308467D03*
X1496200Y359522D03*
X1497880Y373062D03*
X1495150Y369842D03*
X1503450Y382693D03*
Y385843D03*
X1497770Y732502D03*
X1509638Y738627D03*
X1509350Y741315D03*
X1504747Y747293D03*
X1503514Y801361D03*
Y797961D03*
X1497199Y1275667D03*
X1497259Y1273097D03*
X1494629Y1271477D03*
X1494631Y1274144D03*
X1506569Y1285947D03*
X1508819Y1284797D03*
X1506539Y1288557D03*
X1508759Y1287367D03*
X1508699Y1289967D03*
X1494641Y1280054D03*
X1494631Y1277024D03*
X1506551Y1291254D03*
X1497199Y1278277D03*
X1497161Y1280974D03*
X1506689Y1283377D03*
X1494840Y1300447D03*
X1506591Y1297014D03*
Y1294134D03*
X1508711Y1295554D03*
Y1298434D03*
Y1292674D03*
X1495154Y1322757D03*
Y1319650D03*
X1499048Y1319946D03*
X1504720Y1329143D03*
X1495054Y1325853D03*
X1503786Y1326076D03*
X1504518Y1335982D03*
X1496784Y1341147D03*
X1498924Y1334882D03*
X1498950Y1339517D03*
X1501149Y1336287D03*
X1496784Y1338247D03*
X1496144Y1335353D03*
X1504720Y1342143D03*
Y1344743D03*
X1504588Y1353316D03*
Y1355816D03*
X1501033Y1341462D03*
X1498959Y1342930D03*
X1505116Y1369724D03*
X1505570Y1364212D03*
X1507704Y1361597D03*
X1507617Y1424045D03*
X1498475Y1578182D03*
X1501875D03*
X1510535D03*
X1509757Y1575686D03*
Y1580678D03*
X1502653D03*
X1497697D03*
X1502653Y1575686D03*
X1497697D03*
X1501875Y1578182D03*
X1498475D03*
X1510535Y1590094D03*
X1498475D03*
X1501875D03*
X1503775Y1602380D03*
X1507175D03*
X1502997Y1599884D03*
X1507953D03*
X1495893D03*
X1509757Y1587598D03*
Y1592590D03*
X1502653D03*
X1497697D03*
X1502653Y1587598D03*
X1497697D03*
X1501875Y1590094D03*
X1498475D03*
X1503775Y1614292D03*
X1507175D03*
X1502997Y1616788D03*
X1507953D03*
X1502997Y1604876D03*
Y1611796D03*
X1507953Y1604876D03*
Y1611796D03*
X1495893Y1604876D03*
Y1611796D03*
Y1616788D03*
X1503775Y1614292D03*
X1507175D03*
X1495115D03*
X1503775Y1602380D03*
X1507175D03*
X1495115D03*
X1518608Y49377D03*
X1522920Y116180D03*
X1513900Y117762D03*
X1524770Y195792D03*
X1521115Y193262D03*
X1521201Y215551D03*
X1513110Y247412D03*
X1514593Y249698D03*
Y235116D03*
X1513759Y263676D03*
X1519758Y265161D03*
X1522786Y262558D03*
X1522258Y265161D03*
X1516683Y278437D03*
X1519833Y277297D03*
X1511624Y291175D03*
X1522258Y288956D03*
X1522883Y305187D03*
X1519336Y303426D03*
X1520094Y306543D03*
X1514369Y308467D03*
X1526216Y306909D03*
X1524505Y748912D03*
X1515940Y795815D03*
Y799215D03*
X1513789Y1290037D03*
X1511289Y1287397D03*
X1511199Y1290007D03*
X1513791Y1292704D03*
X1516351D03*
X1513791Y1298464D03*
Y1295584D03*
X1516351D03*
Y1298464D03*
X1511251Y1292704D03*
Y1298464D03*
Y1295584D03*
X1522066Y1312808D03*
X1526066D03*
X1518066D03*
X1515066D03*
X1511066D03*
X1510738Y1345539D03*
Y1342432D03*
X1518538Y1345539D03*
Y1342432D03*
X1515938Y1345539D03*
Y1342432D03*
X1513338Y1345539D03*
Y1342432D03*
X1521138D03*
X1524338D03*
X1518738Y1348646D03*
X1516138D03*
X1515212Y1352295D03*
X1512732D03*
X1517692D03*
X1521282Y1357401D03*
X1525942D03*
X1515212Y1357895D03*
X1512732D03*
X1517692D03*
X1518451Y1369919D03*
X1514878Y1365553D03*
X1510878Y1364815D03*
X1519088Y1367043D03*
X1517616Y1364585D03*
X1510878Y1367871D03*
X1523612Y1358151D03*
X1512177Y1427795D03*
X1513657Y1429985D03*
X1522595Y1578182D03*
X1525995D03*
X1513935D03*
X1521817Y1580678D03*
Y1575686D03*
X1514713D03*
Y1580678D03*
X1525995Y1578182D03*
X1513935D03*
X1522595D03*
X1510535D03*
X1525995Y1590094D03*
X1522595D03*
X1513935D03*
X1519235Y1602380D03*
X1515835D03*
X1527895D03*
X1520013Y1599884D03*
X1515057D03*
X1521817Y1592590D03*
Y1587598D03*
X1514713D03*
Y1592590D03*
X1525995Y1590094D03*
X1513935D03*
X1522595D03*
X1510535D03*
X1519235Y1614292D03*
X1515835D03*
X1527895D03*
X1520013Y1604876D03*
X1515057D03*
X1520013Y1611796D03*
X1515057D03*
Y1616788D03*
X1520013D03*
X1515835Y1614292D03*
X1519235D03*
X1515835Y1602380D03*
X1519235D03*
X1511866Y1737108D03*
X1529002Y32290D03*
X1536310Y47492D03*
X1535596Y69297D03*
X1538996D03*
X1534818Y66801D03*
Y71793D03*
X1539774Y66801D03*
Y71793D03*
X1541774Y69297D03*
X1532818D03*
X1538996D03*
X1535596D03*
X1534774Y103093D03*
X1529818D03*
X1534060Y100162D03*
X1530660D03*
X1533520Y110662D03*
X1535575Y118862D03*
X1529500Y129602D03*
X1540090Y122782D03*
X1536925Y129937D03*
X1529500Y125862D03*
X1535520Y151562D03*
X1531750Y199762D03*
X1534720Y199803D03*
X1528720Y199862D03*
X1529610Y211614D03*
X1532590Y225432D03*
X1529670Y225522D03*
X1528716Y306909D03*
X1533716D03*
X1536216D03*
X1534899Y310447D03*
X1540958Y307756D03*
X1540937Y576522D03*
X1536527Y589012D03*
X1539720Y589862D03*
Y581862D03*
X1540377Y634165D03*
X1535052Y1325904D03*
X1532552Y1334504D03*
X1535052D03*
X1529952D03*
X1532552Y1339704D03*
X1529952D03*
X1537652Y1325904D03*
Y1334504D03*
X1532552Y1337104D03*
X1529952D03*
X1538510Y1346392D03*
X1531302Y1342204D03*
X1535892Y1346354D03*
Y1343754D03*
X1527282Y1345555D03*
Y1342448D03*
X1538757Y1356355D03*
X1527182Y1348651D03*
X1538757Y1360855D03*
Y1365355D03*
X1533178Y1360815D03*
X1530978Y1359315D03*
X1528912Y1361045D03*
X1531078Y1362315D03*
X1533178Y1363715D03*
X1528912Y1363945D03*
X1533178Y1357915D03*
X1528272Y1358151D03*
X1534655Y1578182D03*
X1538055D03*
X1533877Y1575592D03*
X1538833D03*
X1533877Y1580678D03*
X1538833D03*
X1526773D03*
Y1575686D03*
X1538055Y1578182D03*
X1534655D03*
X1538055Y1590094D03*
X1534655D03*
X1539955Y1602380D03*
X1531295D03*
X1543355D03*
X1539177Y1599790D03*
X1527117Y1599884D03*
X1532073D03*
X1533877Y1587598D03*
X1538833D03*
X1533877Y1592590D03*
X1538833D03*
X1526773D03*
Y1587598D03*
X1538055Y1590094D03*
X1534655D03*
X1539955Y1614292D03*
X1531295D03*
X1543355D03*
X1539177Y1611796D03*
Y1604876D03*
Y1616788D03*
X1527117D03*
Y1604876D03*
Y1611796D03*
X1532073Y1616788D03*
Y1604876D03*
Y1611796D03*
X1527895Y1614292D03*
X1539955D03*
X1531295D03*
X1527895Y1602380D03*
X1539955D03*
X1531295D03*
X1531866Y1737108D03*
X1547768Y3010D03*
X1556413Y19495D03*
X1559813D03*
X1555635Y16999D03*
Y21991D03*
X1553635Y19495D03*
X1556413D03*
X1552708Y26431D03*
X1549308D03*
X1553486Y23935D03*
X1548530D03*
X1546530Y25931D03*
X1555486D03*
X1547429Y28406D03*
Y37106D03*
X1554515Y28406D03*
Y37106D03*
X1549308Y26431D03*
X1552708D03*
X1554515Y40020D03*
Y48720D03*
X1547429Y40020D03*
Y48720D03*
X1560996Y69297D03*
X1557596D03*
X1554818D03*
X1556818Y66801D03*
Y71793D03*
X1557596Y69297D03*
X1546596Y75297D03*
X1549996D03*
X1543818D03*
X1552774D03*
X1550774Y77793D03*
Y72801D03*
X1545818Y77793D03*
Y72801D03*
X1546596Y75297D03*
X1549996D03*
X1553189Y127781D03*
X1556049Y147711D03*
X1545763Y159305D03*
X1554723Y200375D03*
X1557560Y196912D03*
X1557320Y203297D03*
X1554723Y224529D03*
Y248945D03*
X1545668Y305266D03*
X1545768Y302766D03*
X1543958Y307556D03*
X1546458Y307856D03*
X1543858Y310056D03*
X1547312Y579080D03*
X1543720Y581862D03*
X1548720D03*
X1552720Y589862D03*
Y581862D03*
X1554727Y631527D03*
X1554753Y628860D03*
X1553312Y636815D03*
X1559354Y655716D03*
Y659116D03*
X1550417Y677045D03*
X1550057Y693485D03*
X1548479Y706088D03*
X1558775Y1578182D03*
X1550115D03*
X1546715D03*
X1557997Y1575686D03*
Y1580678D03*
X1550893D03*
X1545937D03*
X1550893Y1575686D03*
X1545937D03*
X1550115Y1578182D03*
X1558775D03*
X1546715D03*
X1558775Y1590094D03*
X1550115D03*
X1546715D03*
X1552015Y1602380D03*
X1555415D03*
X1556193Y1599884D03*
X1551237D03*
X1544133Y1599790D03*
X1557997Y1587598D03*
Y1592590D03*
X1545937D03*
X1550893D03*
Y1587598D03*
X1545937D03*
X1550115Y1590094D03*
X1558775D03*
X1546715D03*
X1555415Y1614292D03*
X1552015D03*
X1551237Y1616788D03*
X1556193D03*
Y1604876D03*
X1551237D03*
X1556193Y1611796D03*
X1551237D03*
X1544133Y1604876D03*
Y1611796D03*
Y1616788D03*
X1552015Y1614292D03*
X1555415D03*
X1543355D03*
X1552015Y1602380D03*
X1555415D03*
X1543355D03*
X1551866Y1737108D03*
X1567768Y3010D03*
X1570586Y19495D03*
X1573986D03*
X1560591Y16999D03*
Y21991D03*
X1569808Y16999D03*
Y21991D03*
X1574764Y16999D03*
Y21991D03*
X1562591Y19495D03*
X1567808D03*
X1570586D03*
X1573986D03*
X1559813D03*
X1577654Y26431D03*
X1563481D03*
X1566881D03*
X1567659Y23935D03*
X1562703D03*
X1560703Y25931D03*
X1569659D03*
X1574876D03*
X1561602Y28406D03*
Y37106D03*
X1568688Y28406D03*
Y37106D03*
X1563481Y26431D03*
X1566881D03*
X1568688Y40020D03*
Y48720D03*
X1561602Y40020D03*
Y48720D03*
X1563774Y69297D03*
X1561774Y66801D03*
Y71793D03*
X1560996Y69297D03*
X1571996Y75297D03*
X1568596D03*
X1565818D03*
X1574774D03*
X1572774Y77793D03*
Y72801D03*
X1567818Y77793D03*
Y72801D03*
X1568596Y75297D03*
X1571996D03*
X1559860Y240002D03*
X1559722Y243110D03*
X1570675Y267857D03*
X1575169Y303929D03*
X1573246Y306650D03*
X1572396Y309450D03*
X1567114Y572792D03*
X1561494Y584292D03*
X1559557Y593290D03*
X1560717Y648522D03*
X1564768Y708159D03*
X1570720Y729362D03*
X1562871Y732316D03*
X1571577Y747145D03*
X1567547Y755485D03*
X1571920Y762662D03*
X1568490Y758162D03*
X1570374Y760093D03*
X1570835Y1578182D03*
X1574235D03*
X1562175D03*
X1570057Y1580678D03*
X1575013D03*
X1570057Y1575686D03*
X1575013D03*
X1562953D03*
Y1580678D03*
X1574235Y1578182D03*
X1562175D03*
X1570835D03*
X1574235Y1590094D03*
X1570835D03*
X1562175D03*
X1564075Y1602380D03*
X1567475D03*
X1576135D03*
X1575357Y1599884D03*
X1563297D03*
X1568253D03*
X1570057Y1592590D03*
X1575013D03*
X1570057Y1587598D03*
X1575013D03*
X1562953D03*
Y1592590D03*
X1574235Y1590094D03*
X1562175D03*
X1570835D03*
X1567475Y1614292D03*
X1564075D03*
X1576135D03*
X1575357Y1616788D03*
Y1604876D03*
Y1611796D03*
X1563297Y1604876D03*
Y1611796D03*
X1568253Y1604876D03*
Y1611796D03*
X1563297Y1616788D03*
X1568253D03*
X1564075Y1614292D03*
X1567475D03*
X1564075Y1602380D03*
X1567475D03*
X1587768Y3010D03*
X1584759Y19495D03*
X1588159D03*
X1583981Y16999D03*
Y21991D03*
X1588937Y16999D03*
Y21991D03*
X1576764Y19495D03*
X1581981D03*
X1590937D03*
X1584759D03*
X1588159D03*
X1591828Y26431D03*
X1581054D03*
X1576876Y23935D03*
X1581832D03*
X1591050D03*
X1583832Y25931D03*
X1589050D03*
X1575775Y28406D03*
Y37106D03*
X1582862Y28406D03*
Y37106D03*
X1589948Y28406D03*
Y37106D03*
X1577654Y26431D03*
X1591828D03*
X1581054D03*
X1589948Y40020D03*
Y48720D03*
X1582862Y40020D03*
Y48720D03*
X1575775Y40020D03*
Y48720D03*
X1579596Y69297D03*
X1582996D03*
X1576818D03*
X1585774D03*
X1578818Y66801D03*
Y71793D03*
X1583774Y66801D03*
Y71793D03*
X1582996Y69297D03*
X1579596D03*
X1590596Y75297D03*
X1593996D03*
X1587818D03*
X1589818Y77793D03*
Y72801D03*
X1590596Y75297D03*
X1576589Y300927D03*
X1588314Y592553D03*
X1585714D03*
X1583114D03*
X1590914D03*
X1588254Y595103D03*
X1588284Y597613D03*
X1585654Y595103D03*
X1585684Y597613D03*
X1583084D03*
X1583054Y595103D03*
X1588284Y608655D03*
X1585684D03*
X1583084D03*
X1590854Y595103D03*
X1590884Y597613D03*
Y608655D03*
X1588254Y613715D03*
X1588224Y611205D03*
X1585654Y613715D03*
X1585624Y611205D03*
X1583024D03*
X1583054Y613715D03*
X1590854D03*
X1590824Y611205D03*
X1591368Y628727D03*
X1591428Y626177D03*
X1588928D03*
X1588868Y628727D03*
X1591398Y631237D03*
X1588898D03*
X1591368Y650877D03*
X1591338Y648367D03*
X1591398Y645817D03*
X1588868Y650877D03*
X1588838Y648367D03*
X1588898Y645817D03*
X1591368Y653377D03*
X1588868D03*
X1591448Y657677D03*
X1588948D03*
Y660177D03*
X1591448D03*
X1588968Y665237D03*
X1591468D03*
X1588938Y662727D03*
X1591438D03*
X1588938Y679807D03*
X1588878Y682357D03*
X1588908Y684867D03*
X1591438Y679807D03*
X1591378Y682357D03*
X1591408Y684867D03*
X1591328Y696727D03*
X1591388Y694177D03*
X1588888D03*
X1588828Y696727D03*
X1591358Y699277D03*
X1588858D03*
X1591358Y718837D03*
X1591328Y716327D03*
X1591388Y713777D03*
X1588858Y718837D03*
X1588828Y716327D03*
X1588888Y713777D03*
X1590915Y755793D03*
X1582895Y1578182D03*
X1586295D03*
X1582117Y1575686D03*
X1587073D03*
X1582117Y1580678D03*
X1587073D03*
X1586295Y1578182D03*
X1582895D03*
Y1590094D03*
X1586295D03*
X1591595Y1602380D03*
X1588195D03*
X1579535D03*
X1587417Y1599884D03*
X1580313D03*
X1582117Y1587598D03*
X1587073D03*
X1582117Y1592590D03*
X1587073D03*
X1586295Y1590094D03*
X1582895D03*
X1588195Y1614292D03*
X1591595D03*
X1579535D03*
X1587417Y1604876D03*
Y1611796D03*
Y1616788D03*
X1580313D03*
Y1604876D03*
Y1611796D03*
X1588195Y1614292D03*
X1576135D03*
X1591595D03*
X1579535D03*
X1588195Y1602380D03*
X1576135D03*
X1591595D03*
X1579535D03*
X1591866Y1737108D03*
X1607768Y3010D03*
X1602333Y19495D03*
X1598933D03*
X1598155Y16999D03*
Y21991D03*
X1603111Y16999D03*
Y21991D03*
X1596155Y19495D03*
X1605111D03*
X1598933D03*
X1602333D03*
X1595228Y26431D03*
X1596006Y23935D03*
X1598006Y25931D03*
X1597035Y28406D03*
Y37106D03*
X1604122Y28406D03*
Y37106D03*
X1595228Y26431D03*
X1604122Y40020D03*
Y48720D03*
X1597035Y40020D03*
Y48720D03*
X1601596Y69297D03*
X1604996D03*
X1598818D03*
X1607774D03*
X1600818Y66801D03*
Y71793D03*
X1605774Y66801D03*
Y71793D03*
X1604996Y69297D03*
X1601596D03*
X1596774Y75297D03*
X1594774Y77793D03*
Y72801D03*
X1593996Y75297D03*
X1603778Y189943D03*
X1603726Y198061D03*
X1603747Y192951D03*
X1596444Y215526D03*
X1603706Y211526D03*
X1603580Y206902D03*
X1603920Y222922D03*
X1604040Y219692D03*
X1604270Y231490D03*
X1598030Y251002D03*
X1604290Y242472D03*
X1602980Y560002D03*
X1593514Y592553D03*
X1601830Y590685D03*
X1604430D03*
X1607200Y583962D03*
X1593484Y597613D03*
X1593454Y595103D03*
X1593484Y608655D03*
X1593424Y611205D03*
X1593454Y613715D03*
X1601830Y615201D03*
X1604430D03*
X1598868Y628727D03*
X1598928Y626177D03*
X1593868Y628727D03*
X1593928Y626177D03*
X1596428D03*
X1596368Y628727D03*
X1598898Y631237D03*
X1593898D03*
X1596398D03*
X1598868Y650877D03*
X1598838Y648367D03*
X1596368Y650877D03*
X1593868D03*
X1596338Y648367D03*
X1593838D03*
X1598898Y645817D03*
X1596398D03*
X1593898D03*
X1598868Y653377D03*
X1596368D03*
X1593868D03*
X1598948Y657677D03*
X1593948D03*
X1596448D03*
Y660177D03*
X1593948D03*
X1598948D03*
X1596468Y665237D03*
X1593968D03*
X1598968D03*
X1596438Y662727D03*
X1593938D03*
X1598938D03*
X1593938Y679807D03*
X1596438D03*
X1593878Y682357D03*
X1596378D03*
X1593908Y684867D03*
X1596408D03*
X1598878Y682357D03*
X1598908Y684867D03*
X1598938Y679807D03*
X1596288Y688902D03*
X1598888D03*
X1598828Y696727D03*
X1593828D03*
X1593888Y694177D03*
X1596388D03*
X1596328Y696727D03*
X1593858Y699277D03*
X1596358D03*
X1598888Y694177D03*
X1596288Y691502D03*
X1598858Y699277D03*
X1598888Y691502D03*
X1598858Y718837D03*
X1598828Y716327D03*
X1596358Y718837D03*
X1593858D03*
X1596328Y716327D03*
X1593828D03*
X1596388Y713777D03*
X1593888D03*
X1598888D03*
X1596250Y721452D03*
X1598850D03*
X1599010Y724002D03*
X1598440Y736692D03*
X1592760Y736652D03*
X1595600D03*
X1606788Y756199D03*
X1602788D03*
X1606980Y1449922D03*
X1607015Y1578182D03*
X1598355D03*
X1594955D03*
X1606237Y1575686D03*
Y1580678D03*
X1594177D03*
X1599133D03*
X1594177Y1575686D03*
X1599133D03*
X1598355Y1578182D03*
X1607015D03*
X1594955D03*
X1607015Y1590094D03*
X1594955D03*
X1598355D03*
X1603655Y1602380D03*
X1600255D03*
X1599477Y1599884D03*
X1604433D03*
X1592373D03*
X1606237Y1587598D03*
Y1592590D03*
X1594177D03*
X1599133D03*
X1594177Y1587598D03*
X1599133D03*
X1598355Y1590094D03*
X1607015D03*
X1594955D03*
X1603655Y1614292D03*
X1600255D03*
X1599477Y1616788D03*
X1604433D03*
X1599477Y1604876D03*
Y1611796D03*
X1604433Y1604876D03*
Y1611796D03*
X1592373Y1604876D03*
Y1611796D03*
Y1616788D03*
X1600255Y1614292D03*
X1603655D03*
X1600255Y1602380D03*
X1603655D03*
X1621920Y25962D03*
X1622220Y49862D03*
X1623596Y69297D03*
X1620818D03*
X1622818Y66801D03*
Y71793D03*
X1623596Y69297D03*
X1612596Y75297D03*
X1615996D03*
X1609818D03*
X1618774D03*
X1616774Y77793D03*
Y72801D03*
X1611818Y77793D03*
Y72801D03*
X1612596Y75297D03*
X1615996D03*
X1623881Y129627D03*
X1619980Y590685D03*
X1615800Y584062D03*
X1620170Y623762D03*
X1622770D03*
X1619980Y615201D03*
X1612980Y623762D03*
X1620170Y626362D03*
X1622770D03*
X1612980D03*
X1615580Y650092D03*
Y657762D03*
X1620170D03*
X1622770D03*
X1622109Y652469D03*
X1619509D03*
X1612980Y657762D03*
Y650092D03*
X1615580Y660362D03*
X1620170D03*
X1622770D03*
X1612980D03*
X1622109Y686469D03*
X1619509D03*
X1615580Y684092D03*
X1612980D03*
X1622770Y691762D03*
Y694362D03*
X1620170Y691762D03*
Y694362D03*
X1615580D03*
X1612980D03*
X1615580Y691762D03*
X1612980D03*
X1619509Y720469D03*
X1622109D03*
X1612980Y718092D03*
X1615580D03*
X1610100Y725152D03*
X1610788Y756199D03*
X1614788D03*
X1618788D03*
X1623448Y1420028D03*
Y1417428D03*
Y1414828D03*
Y1412228D03*
X1612630Y1418842D03*
X1615062Y1421241D03*
X1613047Y1415669D03*
X1615597Y1433669D03*
X1614927Y1426076D03*
Y1429896D03*
X1624353Y1431316D03*
X1617215Y1440822D03*
X1622475Y1578182D03*
X1619075D03*
X1610415D03*
X1618297Y1580678D03*
X1623253D03*
X1618297Y1575686D03*
X1623253D03*
X1611193D03*
Y1580678D03*
X1622475Y1578182D03*
X1610415D03*
X1619075D03*
X1622475Y1590094D03*
X1619075D03*
X1610415D03*
X1612315Y1602380D03*
X1615715D03*
X1624375D03*
X1623597Y1599884D03*
X1611537D03*
X1616493D03*
X1618297Y1592590D03*
X1623253D03*
X1618297Y1587598D03*
X1623253D03*
X1611193D03*
Y1592590D03*
X1622475Y1590094D03*
X1610415D03*
X1619075D03*
X1612315Y1614292D03*
X1615715D03*
X1624375D03*
X1623597Y1616788D03*
Y1604876D03*
Y1611796D03*
X1611537Y1604876D03*
Y1611796D03*
X1616493Y1604876D03*
Y1611796D03*
X1611537Y1616788D03*
X1616493D03*
X1612315Y1614292D03*
X1615715D03*
X1612315Y1602380D03*
X1615715D03*
X1611866Y1737108D03*
X1634799Y19495D03*
X1638199D03*
X1634021Y16999D03*
Y21991D03*
X1638977Y16999D03*
Y21991D03*
X1632021Y19495D03*
X1634799D03*
X1638199D03*
X1641867Y26431D03*
X1627694D03*
X1631094D03*
X1631872Y23935D03*
X1626916D03*
X1624916Y25931D03*
X1633872D03*
X1639089D03*
X1625814Y28406D03*
Y37106D03*
X1632901Y28406D03*
Y37106D03*
X1639988Y28406D03*
Y37106D03*
X1627694Y26431D03*
X1631094D03*
X1625814Y40020D03*
Y48720D03*
X1632901Y40020D03*
Y48720D03*
X1639988Y40020D03*
Y48720D03*
X1626996Y69297D03*
X1629774D03*
X1627774Y66801D03*
Y71793D03*
X1626996Y69297D03*
X1639200Y75297D03*
X1635800D03*
X1633022D03*
X1635022Y77793D03*
X1639978D03*
Y72801D03*
X1635022D03*
X1635800Y75297D03*
X1639200D03*
X1635032Y196188D03*
X1632899Y213012D03*
X1632342Y216015D03*
X1635835Y343002D03*
X1636800Y429982D03*
X1639800D03*
X1636800Y426982D03*
X1639800D03*
X1636800Y438982D03*
X1639800D03*
X1636800Y435982D03*
X1639800D03*
X1636800Y432982D03*
X1639800D03*
X1637667Y587844D03*
Y590444D03*
X1629867D03*
Y587844D03*
X1632467Y590444D03*
Y587844D03*
X1635067Y590444D03*
Y587844D03*
X1626606Y616576D03*
X1629206D03*
X1631806D03*
X1634406D03*
X1637006D03*
X1639606D03*
X1630570Y623762D03*
X1627970D03*
X1625370D03*
X1636412Y638451D03*
X1636417Y630007D03*
X1640061Y639497D03*
X1636412Y641051D03*
X1630570Y626362D03*
X1627970D03*
X1625370D03*
X1630198Y638651D03*
Y636051D03*
Y641251D03*
X1633305Y638651D03*
Y641251D03*
X1630198Y632851D03*
X1630214Y629907D03*
X1633321D03*
X1640061Y644457D03*
Y641977D03*
X1630570Y657762D03*
X1627970D03*
X1625370D03*
X1629909Y652469D03*
X1632509D03*
X1624709D03*
X1627309D03*
X1630198Y643851D03*
X1633305Y646451D03*
Y643851D03*
X1630198Y646451D03*
X1636412Y672451D03*
X1636417Y664007D03*
X1640061Y673497D03*
X1630570Y660362D03*
X1627970D03*
X1625370D03*
X1630198Y672651D03*
Y670051D03*
X1633305Y672651D03*
X1630198Y666851D03*
X1630214Y663907D03*
X1633321D03*
X1629909Y686469D03*
X1632509D03*
X1624709D03*
X1627309D03*
X1640061Y678457D03*
Y675977D03*
X1636412Y675051D03*
X1630198Y677851D03*
Y675251D03*
X1633305Y680451D03*
Y675251D03*
Y677851D03*
X1630198Y680451D03*
X1636417Y698007D03*
X1636412Y706451D03*
X1630214Y697907D03*
X1633321D03*
X1630198Y704051D03*
Y706651D03*
X1633305D03*
X1630198Y700851D03*
X1625370Y691762D03*
Y694362D03*
X1630570D03*
Y691762D03*
X1627970D03*
Y694362D03*
X1640061Y707497D03*
Y712457D03*
Y709977D03*
X1636412Y709051D03*
X1632509Y720469D03*
X1627309D03*
X1629909D03*
X1624709D03*
X1633305Y711851D03*
Y709251D03*
X1630198D03*
Y711851D03*
X1633305Y714451D03*
X1630198D03*
X1638928Y756199D03*
X1630928D03*
X1634928D03*
X1638277Y1269065D03*
X1640812Y1270020D03*
X1631203Y1367492D03*
X1628653D03*
X1626153D03*
X1628653Y1372492D03*
X1631203D03*
X1626153D03*
X1631203Y1369992D03*
X1628653D03*
X1626153D03*
X1628653Y1379992D03*
Y1382492D03*
Y1377492D03*
Y1374992D03*
X1631203Y1377492D03*
Y1374992D03*
Y1379992D03*
Y1382492D03*
X1626153Y1379992D03*
Y1382492D03*
Y1374992D03*
Y1377492D03*
X1637183Y1394411D03*
X1639683D03*
X1629262Y1394418D03*
X1634683Y1394411D03*
X1625948Y1417428D03*
Y1412228D03*
X1633103Y1417907D03*
X1630503D03*
X1635703D03*
X1633103Y1421014D03*
X1630503D03*
X1635703D03*
X1638303Y1417907D03*
Y1421014D03*
X1625948Y1414828D03*
Y1420028D03*
X1635903Y1424121D03*
X1638503D03*
X1632516Y1427753D03*
Y1433353D03*
X1634986Y1427753D03*
Y1433353D03*
X1637416Y1427753D03*
Y1433353D03*
X1627591Y1447796D03*
X1637478Y1445150D03*
X1624853Y1440875D03*
X1634643Y1442982D03*
X1638785Y1442483D03*
X1637042Y1440215D03*
X1630643Y1443090D03*
X1635315Y1465745D03*
Y1462745D03*
X1632315Y1468745D03*
X1629815D03*
X1632315Y1465745D03*
X1629815D03*
X1632315Y1462745D03*
X1629815D03*
X1635315Y1468745D03*
Y1460245D03*
X1629815D03*
X1632315D03*
X1629815Y1457745D03*
X1632315D03*
X1635315D03*
X1639645Y1473645D03*
X1634535Y1578182D03*
X1631135D03*
X1630357Y1575592D03*
X1635313D03*
X1630357Y1580678D03*
X1635313D03*
X1634535Y1578182D03*
X1631135D03*
X1634535Y1590094D03*
X1631135D03*
X1639835Y1602380D03*
X1636435D03*
X1627775D03*
X1640613Y1599790D03*
X1635657D03*
X1628553Y1599884D03*
X1630357Y1587598D03*
X1635313D03*
X1630357Y1592590D03*
X1635313D03*
X1634535Y1590094D03*
X1631135D03*
X1639835Y1614292D03*
X1636435D03*
X1627775D03*
X1640613Y1604876D03*
Y1611796D03*
X1635657Y1604876D03*
Y1611796D03*
X1640613Y1616788D03*
X1635657D03*
X1628553D03*
Y1604876D03*
Y1611796D03*
X1636435Y1614292D03*
X1624375D03*
X1639835D03*
X1627775D03*
X1636435Y1602380D03*
X1624375D03*
X1639835D03*
X1627775D03*
X1631866Y1737108D03*
X1648972Y19495D03*
X1652372D03*
X1648194Y16999D03*
Y21991D03*
X1653150Y16999D03*
Y21991D03*
X1640977Y19495D03*
X1646194D03*
X1655150D03*
X1648972D03*
X1652372D03*
X1645267Y26431D03*
X1641089Y23935D03*
X1646045D03*
X1648045Y25931D03*
X1654161Y28406D03*
Y37106D03*
X1647074Y28406D03*
Y37106D03*
X1641867Y26431D03*
X1645267D03*
X1647074Y40020D03*
Y48720D03*
X1654161Y40020D03*
Y48720D03*
X1650200Y69297D03*
X1646800D03*
X1644022D03*
X1652978D03*
X1646022Y66801D03*
Y71793D03*
X1650978Y66801D03*
Y71793D03*
X1650200Y69297D03*
X1646800D03*
X1657800Y75297D03*
X1655022D03*
X1641978D03*
X1657022Y77793D03*
Y72801D03*
X1652610Y394727D03*
X1652810Y407402D03*
X1650020Y408952D03*
X1647310Y408922D03*
X1650020Y411452D03*
X1647310Y411422D03*
X1652113Y527325D03*
X1652138Y524071D03*
X1651890Y520540D03*
X1651931Y540071D03*
Y536071D03*
X1651851Y532057D03*
X1651112Y545572D03*
X1653230Y549322D03*
X1642720Y560862D03*
X1656238Y592113D03*
X1649149Y607022D03*
X1653929Y604546D03*
X1649139Y604576D03*
X1653736Y607033D03*
X1649117Y602139D03*
X1653930Y602099D03*
X1642873Y604206D03*
Y607206D03*
X1645625Y600495D03*
Y603295D03*
X1642873Y601206D03*
Y598206D03*
X1645625Y597795D03*
Y594995D03*
X1642873Y595006D03*
X1649833Y594946D03*
X1653794Y594956D03*
X1653774Y598576D03*
X1649844Y598555D03*
X1649220Y620662D03*
X1642340Y618546D03*
X1642873Y610206D03*
X1656955Y611090D03*
X1653220Y620662D03*
X1645681Y624011D03*
X1648581D03*
X1651481D03*
X1645661Y639497D03*
X1654809Y638101D03*
X1652351Y639573D03*
X1648811Y628277D03*
X1647081Y626211D03*
X1645917Y628917D03*
Y633577D03*
X1645167Y631247D03*
Y635907D03*
X1650081Y626111D03*
X1651711Y628277D03*
X1656550Y653086D03*
X1645661Y644457D03*
Y641977D03*
X1651635Y651836D03*
X1652581Y646311D03*
X1643582Y652601D03*
X1655637Y646311D03*
X1641082Y652601D03*
X1645661Y673497D03*
X1654809Y672101D03*
X1652351Y673573D03*
X1645681Y658011D03*
X1648581D03*
X1648811Y662277D03*
X1647081Y660211D03*
X1645917Y662917D03*
Y667577D03*
X1645167Y665247D03*
Y669907D03*
X1650081Y660111D03*
X1651481Y658011D03*
X1651711Y662277D03*
X1656550Y687086D03*
X1645661Y678457D03*
Y675977D03*
X1641082Y686601D03*
X1651635Y685836D03*
X1652581Y680311D03*
X1653319Y676311D03*
X1643582Y686601D03*
X1655113Y680835D03*
X1654809Y706101D03*
X1648811Y696277D03*
X1645167Y703907D03*
X1645917Y701577D03*
X1645167Y699247D03*
X1645917Y696917D03*
X1650081Y694111D03*
X1645681Y692011D03*
X1647081Y694211D03*
X1648581Y692011D03*
X1651711Y696277D03*
X1651481Y692011D03*
X1645661Y707497D03*
Y709977D03*
Y712457D03*
X1641082Y720601D03*
X1651635Y719836D03*
X1652581Y714311D03*
X1653319Y710311D03*
X1652351Y707573D03*
X1643582Y720601D03*
X1655637Y714311D03*
X1651509Y756492D03*
X1650771Y1367492D03*
X1648271D03*
X1645721D03*
X1648271Y1372492D03*
X1650771D03*
X1645721D03*
X1650771Y1369992D03*
X1648271D03*
X1645721D03*
X1648271Y1379992D03*
Y1382492D03*
X1650771Y1379992D03*
Y1382492D03*
X1648271Y1377492D03*
Y1374992D03*
X1650771Y1377492D03*
Y1374992D03*
X1645721Y1377492D03*
Y1374992D03*
Y1379992D03*
Y1382492D03*
X1656188Y1394736D03*
X1647592Y1394418D03*
X1655779Y1417618D03*
Y1412418D03*
Y1415018D03*
X1644103Y1417907D03*
X1647047Y1417923D03*
Y1421030D03*
X1653279Y1412418D03*
X1650679D03*
X1653279Y1415018D03*
X1650679D03*
X1653168Y1417618D03*
X1650557D03*
X1640903Y1417907D03*
X1647016Y1424153D03*
X1641047Y1432876D03*
X1645707D03*
X1643377Y1433626D03*
X1648037D03*
X1655762Y1429794D03*
X1648677Y1436220D03*
X1653243Y1435690D03*
X1651043Y1434190D03*
X1653243Y1432790D03*
X1651143Y1437190D03*
X1653243Y1438590D03*
X1648677Y1439120D03*
X1655295Y1453879D03*
X1652295D03*
X1643065Y1462645D03*
Y1465645D03*
Y1468645D03*
Y1460145D03*
Y1457645D03*
X1655295Y1456899D03*
X1652295D03*
X1648947Y1476695D03*
X1642645Y1473645D03*
X1646958Y1501553D03*
X1646595Y1578182D03*
X1643195D03*
X1647373Y1580678D03*
X1642417D03*
X1647373Y1575686D03*
X1642417D03*
X1646595Y1578182D03*
X1643195D03*
X1646595Y1590094D03*
X1643195D03*
X1651895Y1602380D03*
X1648495D03*
X1647717Y1599884D03*
X1652673D03*
X1647373Y1592590D03*
X1642417D03*
X1647373Y1587598D03*
X1642417D03*
X1646595Y1590094D03*
X1643195D03*
X1651895Y1614292D03*
X1648495D03*
X1647717Y1616788D03*
X1652673D03*
X1647717Y1604876D03*
Y1611796D03*
X1652673Y1604876D03*
Y1611796D03*
X1651895Y1614292D03*
X1648495D03*
X1651895Y1602380D03*
X1648495D03*
X1651866Y1737108D03*
X1675228Y26431D03*
X1671828D03*
X1671050Y23935D03*
X1669050Y25931D03*
X1669948Y28406D03*
Y37106D03*
X1671828Y26431D03*
X1669948Y40020D03*
Y48720D03*
X1672200Y69297D03*
X1668800D03*
X1666022D03*
X1668022Y66801D03*
Y71793D03*
X1672978Y66801D03*
Y71793D03*
X1672200Y69297D03*
X1668800D03*
X1661200Y75297D03*
X1663978D03*
X1661978Y77793D03*
Y72801D03*
X1657800Y75297D03*
X1661200D03*
X1668030Y200580D03*
X1667739Y187187D03*
X1666074Y229710D03*
X1660176Y231100D03*
X1670400Y229462D03*
X1659610Y394727D03*
X1663610D03*
X1664970Y472112D03*
X1662447Y480619D03*
X1663376Y515531D03*
X1670004Y537065D03*
Y543065D03*
Y531065D03*
X1662262Y537334D03*
X1659740Y542222D03*
X1661872Y534703D03*
X1660243Y532071D03*
X1660866Y546749D03*
X1666902Y555115D03*
X1664040Y569642D03*
X1668040D03*
X1672040D03*
X1665700Y583462D03*
X1661510Y583442D03*
X1672770Y580512D03*
X1669770D03*
X1658738Y592113D03*
X1661238D03*
X1664997Y604762D03*
X1662120Y604782D03*
X1664197Y602191D03*
X1670700Y594562D03*
X1672500Y596462D03*
X1657220Y620662D03*
X1663720Y620434D03*
X1664410Y617953D03*
X1668920Y617637D03*
X1660754Y609837D03*
X1669397Y614064D03*
X1663471Y609837D03*
X1659458Y637149D03*
X1658085Y639511D03*
X1659914Y649681D03*
X1659458Y671149D03*
X1658085Y673511D03*
X1659914Y683681D03*
X1659458Y705149D03*
X1658085Y707511D03*
X1659914Y717681D03*
X1666686Y757162D03*
X1669303Y1372492D03*
X1664253D03*
X1666753D03*
X1669303Y1367492D03*
Y1369992D03*
X1666753Y1367492D03*
X1664253D03*
Y1369992D03*
X1666753D03*
X1669303Y1379992D03*
Y1382492D03*
Y1377492D03*
Y1374992D03*
X1666753Y1379992D03*
X1664253D03*
X1666753Y1382492D03*
X1664253D03*
X1666753Y1377492D03*
X1664253D03*
Y1374992D03*
X1666753D03*
X1673226Y1394411D03*
X1667405Y1394418D03*
X1659260Y1394693D03*
X1658390Y1420218D03*
Y1415018D03*
Y1412418D03*
Y1417618D03*
X1663590Y1420218D03*
X1660990D03*
Y1415018D03*
Y1417618D03*
Y1412418D03*
X1663590Y1415018D03*
Y1417618D03*
Y1412418D03*
X1668646Y1417907D03*
Y1421014D03*
X1671246Y1417907D03*
Y1421014D03*
X1670659Y1427753D03*
X1673129D03*
X1670659Y1433353D03*
X1673129D03*
X1657438Y1438156D03*
X1662496Y1428791D03*
Y1431291D03*
X1660428Y1447566D03*
X1667577Y1447545D03*
X1662996Y1440922D03*
X1672786Y1442982D03*
X1668786Y1440290D03*
Y1443256D03*
X1657920Y1453405D03*
X1660920D03*
X1657860Y1466545D03*
Y1464045D03*
X1657950Y1456210D03*
X1657860Y1459045D03*
Y1461545D03*
X1660950Y1456210D03*
X1660860Y1466545D03*
Y1464045D03*
Y1459045D03*
Y1461545D03*
X1666123Y1497362D03*
Y1493362D03*
Y1501362D03*
X1666110Y1504662D03*
X1666123Y1533862D03*
Y1520862D03*
Y1541862D03*
Y1545862D03*
X1671673Y1550815D03*
X1666123Y1557557D03*
X1666198Y1561557D03*
Y1581321D03*
X1671866Y1737108D03*
X1682333Y19495D03*
X1678933D03*
X1678155Y16999D03*
Y21991D03*
X1683111Y16999D03*
Y21991D03*
X1676155Y19495D03*
X1685111D03*
X1678933D03*
X1682333D03*
X1689401Y26431D03*
X1686001D03*
X1676006Y23935D03*
X1685223D03*
X1678006Y25931D03*
X1683223D03*
X1677035Y28406D03*
Y37106D03*
X1684122Y28406D03*
Y37106D03*
X1686001Y26431D03*
X1689401D03*
X1675228D03*
X1677035Y40020D03*
Y48720D03*
X1684122Y40020D03*
Y48720D03*
X1690934Y69297D03*
X1688156D03*
X1674978D03*
X1683334Y75297D03*
X1679934D03*
X1677156D03*
X1686112D03*
X1684112Y77793D03*
Y72801D03*
X1679156Y77793D03*
Y72801D03*
X1679934Y75297D03*
X1683334D03*
X1676300Y219762D03*
X1681900Y227962D03*
X1686154Y434160D03*
X1683394Y469878D03*
X1683476Y473378D03*
X1684356Y476290D03*
X1682810Y465940D03*
X1684940Y463030D03*
X1681602Y485180D03*
X1684356Y485628D03*
X1677464Y491790D03*
X1685779Y491230D03*
X1687238Y485496D03*
X1681612Y499290D03*
X1682004Y537065D03*
X1682180Y543065D03*
X1676004D03*
X1682004Y531065D03*
X1676004D03*
X1676040Y569627D03*
X1683369Y566098D03*
X1676644Y655345D03*
Y652745D03*
X1679244Y655345D03*
X1681864Y655286D03*
X1679244Y652745D03*
X1676624Y642404D03*
X1676644Y644945D03*
Y647545D03*
Y650145D03*
X1679244Y642345D03*
X1681864Y642286D03*
X1679244Y644945D03*
Y647545D03*
X1681864Y644886D03*
Y647486D03*
Y650086D03*
Y652686D03*
X1679244Y650145D03*
X1688301Y722158D03*
X1683121D03*
X1680401D03*
X1673860Y726522D03*
X1681810Y752955D03*
X1688912Y1372492D03*
X1686362D03*
Y1367492D03*
Y1369992D03*
X1688912Y1367492D03*
Y1369992D03*
Y1377492D03*
Y1374992D03*
Y1382492D03*
Y1379992D03*
X1686362D03*
Y1382492D03*
Y1374992D03*
Y1377492D03*
X1686135Y1394418D03*
X1675926Y1394411D03*
X1678426D03*
X1687860Y1415179D03*
X1689210Y1417679D03*
X1687860Y1412579D03*
X1685190Y1417923D03*
X1676446Y1417907D03*
X1679046D03*
X1682246D03*
X1676446Y1421014D03*
X1685190Y1421030D03*
X1673846Y1417907D03*
Y1421014D03*
X1676646Y1424121D03*
X1685159Y1424153D03*
X1675559Y1427753D03*
Y1433353D03*
X1674046Y1424121D03*
X1679190Y1432876D03*
X1683850D03*
X1681520Y1433626D03*
X1686180D03*
X1686820Y1436520D03*
X1688886Y1434790D03*
X1688986Y1437790D03*
X1675621Y1445150D03*
X1676928Y1442483D03*
X1675185Y1440215D03*
X1686820Y1439420D03*
X1679508Y1503421D03*
Y1498303D03*
Y1517803D03*
Y1522921D03*
Y1543921D03*
Y1538803D03*
Y1563380D03*
Y1583880D03*
X1674220Y1585321D03*
X1693106Y19495D03*
X1696506D03*
X1692328Y16999D03*
Y21991D03*
X1697284Y16999D03*
Y21991D03*
X1690328Y19495D03*
X1699284D03*
X1696506D03*
X1693106D03*
X1703617Y26459D03*
X1700217D03*
X1690179Y23935D03*
X1692179Y25931D03*
X1691208Y28406D03*
Y37106D03*
X1698295Y28406D03*
Y37106D03*
X1705381Y28406D03*
Y37106D03*
X1703570Y50649D03*
X1700170D03*
X1698295Y48720D03*
X1697824Y39974D03*
X1691208Y40020D03*
Y48720D03*
X1705381D03*
X1694334Y69297D03*
X1697112D03*
X1690156Y66801D03*
Y71793D03*
X1695112Y66801D03*
Y71793D03*
X1694334Y69297D03*
X1690934D03*
X1705334Y75297D03*
X1701934D03*
X1699156D03*
X1701156Y77793D03*
Y72801D03*
X1705334Y75297D03*
X1701934D03*
X1695950Y96437D03*
X1697725Y205120D03*
X1702490Y204780D03*
X1704223Y209707D03*
Y212207D03*
X1701164Y209758D03*
X1698566Y214904D03*
X1696066D03*
X1693725Y217409D03*
X1698566Y212404D03*
X1696066D03*
X1698725Y217409D03*
X1696225D03*
X1701164Y212258D03*
X1704264Y217458D03*
X1701264D03*
X1704264Y214958D03*
X1701264D03*
X1698566Y209704D03*
X1696066D03*
X1693466Y209504D03*
Y214704D03*
Y212204D03*
X1693987Y233174D03*
X1693725Y219909D03*
X1698725D03*
X1696225D03*
X1704264Y219958D03*
X1701264D03*
X1704185Y222710D03*
X1704444Y407045D03*
X1699809Y403985D03*
X1695579D03*
X1697914Y427155D03*
X1698014Y424055D03*
X1701124Y433650D03*
X1697214Y433655D03*
X1704624Y433650D03*
X1690140Y434160D03*
X1700846Y455894D03*
X1697220Y455862D03*
X1693648Y463724D03*
X1702760Y478207D03*
X1696760D03*
X1693236Y472650D03*
X1702760Y490207D03*
X1696760D03*
Y484207D03*
X1691151Y493678D03*
X1689943Y479304D03*
X1696120Y506937D03*
X1703720Y509362D03*
X1701635Y497177D03*
X1699300Y498632D03*
X1694050Y501422D03*
X1691129Y501697D03*
X1699265Y525507D03*
X1696851Y515607D03*
X1693701D03*
X1699265Y521507D03*
X1690999Y525507D03*
X1699291Y537507D03*
X1699251Y529507D03*
X1699666Y541507D03*
X1699251Y533642D03*
X1691104Y530503D03*
X1691445Y535011D03*
X1704886Y534564D03*
X1689769Y537339D03*
X1699297Y549507D03*
X1702270Y552742D03*
X1703452Y639381D03*
X1700852D03*
X1698232Y639440D03*
X1700852Y655141D03*
X1703452Y647341D03*
Y649941D03*
Y652541D03*
Y644741D03*
X1700852Y647341D03*
Y649941D03*
Y652541D03*
Y644741D03*
X1698232Y655200D03*
Y644800D03*
Y647400D03*
Y650000D03*
Y652600D03*
X1703452Y641981D03*
X1700852D03*
X1698232Y642040D03*
X1700922Y657781D03*
X1698302Y657840D03*
X1698048Y705662D03*
X1698920Y698562D03*
X1698020Y702962D03*
X1695227Y722325D03*
X1699307Y722465D03*
X1698137Y718345D03*
X1701087Y719055D03*
X1695367Y719345D03*
X1691021Y722158D03*
X1699110Y727452D03*
X1704973Y753019D03*
X1703310Y749455D03*
X1698537Y766015D03*
X1690620Y760702D03*
X1691412Y1372492D03*
Y1367492D03*
Y1369992D03*
Y1377492D03*
Y1374992D03*
Y1382492D03*
Y1379992D03*
X1690809Y1393970D03*
X1699150Y1393613D03*
X1690460Y1415179D03*
Y1412579D03*
X1691918Y1417676D03*
X1692960Y1415179D03*
Y1412579D03*
X1693404Y1421939D03*
X1699593Y1428384D03*
X1697820Y1423616D03*
X1699545Y1425868D03*
X1699437Y1431295D03*
X1691086Y1436290D03*
Y1433390D03*
X1693392Y1429808D03*
X1699457Y1439185D03*
Y1447805D03*
X1691086Y1439190D03*
X1691988Y1498303D03*
X1704723Y1500862D03*
Y1520362D03*
Y1541362D03*
X1705003Y1564057D03*
X1691866Y1737108D03*
X1707220Y15662D03*
X1714589Y21562D03*
X1714520Y37162D03*
X1719589Y25862D03*
X1717089D03*
X1710106Y48720D03*
Y40020D03*
X1716875Y68062D03*
X1710920Y82162D03*
X1708112Y75297D03*
X1706112Y77793D03*
Y72801D03*
X1708000Y99122D03*
X1712520Y117862D03*
X1719943Y112667D03*
Y116667D03*
X1713418Y130862D03*
X1721418Y135327D03*
X1717418D03*
X1714490Y142920D03*
X1717140Y148910D03*
X1711700Y140200D03*
X1717619Y165909D03*
X1718110Y159040D03*
X1719530Y162950D03*
X1717280Y174970D03*
X1722078Y189483D03*
X1720310Y191252D03*
X1707159Y217580D03*
Y215080D03*
Y210080D03*
Y222580D03*
Y225080D03*
Y220080D03*
X1721400Y374462D03*
X1713720Y381152D03*
X1717220D03*
X1719200Y371162D03*
X1713720Y391652D03*
Y384652D03*
Y388152D03*
X1717220Y391652D03*
Y388152D03*
Y384652D03*
X1707444Y407045D03*
X1709000Y413362D03*
X1706500D03*
X1711144Y425945D03*
X1709000Y415862D03*
X1706500D03*
X1711477Y465229D03*
Y468379D03*
X1708760Y478031D03*
X1721936Y469263D03*
X1716134Y478443D03*
X1715711Y474399D03*
X1708760Y490207D03*
Y484207D03*
X1707552Y503331D03*
X1709844Y516106D03*
X1710500Y538162D03*
X1707610Y534113D03*
X1716110Y532632D03*
X1707346Y547504D03*
X1717987Y569705D03*
X1709027Y655141D03*
X1706720Y703762D03*
X1710550Y691327D03*
X1712824Y696476D03*
X1713920Y700962D03*
X1709107Y728449D03*
X1713450Y728222D03*
X1719727Y1472088D03*
X1720174Y1505895D03*
Y1513945D03*
X1714988Y1520951D03*
X1708988D03*
X1714988Y1530445D03*
X1708988D03*
X1711866Y1737108D03*
X1727768Y3010D03*
X1732320Y28162D03*
X1728820D03*
X1725320D03*
X1726720Y49862D03*
X1733720D03*
X1730220D03*
X1736040Y41792D03*
X1732810Y52482D03*
X1736040Y44292D03*
X1730140Y52552D03*
X1727600Y52582D03*
X1729520Y61762D03*
X1729620Y57262D03*
X1725320Y67962D03*
X1730820Y76362D03*
X1726918Y101967D03*
X1723018Y101667D03*
X1723218Y93267D03*
X1738220Y98862D03*
X1736720Y101862D03*
X1737020Y112177D03*
Y109677D03*
X1733378Y134907D03*
X1736508D03*
X1730765Y151362D03*
X1723670Y149102D03*
X1723240Y185200D03*
X1737704Y183139D03*
X1723090Y173072D03*
Y177072D03*
X1734857Y184865D03*
X1738200Y193862D03*
X1737500Y217962D03*
Y214962D03*
Y211962D03*
Y208962D03*
Y226962D03*
Y223962D03*
Y220962D03*
X1737260Y368132D03*
X1732660Y372692D03*
X1725400Y372062D03*
X1728300Y377787D03*
X1725500Y383662D03*
X1733780Y390620D03*
X1737434Y398990D03*
X1727760Y420415D03*
X1727700Y417265D03*
X1725473Y474859D03*
X1730954Y478062D03*
X1725522Y482869D03*
X1733354Y490869D03*
Y486869D03*
X1738014Y1287344D03*
X1724431Y1336311D03*
X1734717Y1404340D03*
X1729700Y1462932D03*
X1733200D03*
X1736700D03*
X1736400Y1458942D03*
Y1455442D03*
X1731600Y1457230D03*
X1726120Y1490262D03*
X1726149Y1496270D03*
X1724649Y1513945D03*
Y1505895D03*
X1727674D03*
X1726310Y1530445D03*
X1732310D03*
X1726310Y1520951D03*
X1732310D03*
X1731866Y1737108D03*
X1747768Y3010D03*
X1754090Y16302D03*
X1753388Y28360D03*
X1748400Y37262D03*
X1751065Y39017D03*
X1754620Y39062D03*
X1747720Y31862D03*
Y34362D03*
X1753398Y48720D03*
X1740858Y72330D03*
Y79830D03*
Y74830D03*
Y82330D03*
X1754398Y100307D03*
X1745220Y98862D03*
X1741720D03*
X1743720Y101862D03*
X1740220D03*
X1745485Y119539D03*
X1747650Y109677D03*
Y112177D03*
X1744106Y109677D03*
Y112177D03*
X1740563Y109677D03*
Y112177D03*
X1747482Y121367D03*
X1741222Y151527D03*
X1738520Y151362D03*
X1751220Y147562D03*
X1748465D03*
X1754120Y171562D03*
X1750920Y171662D03*
X1751084Y190928D03*
X1752200Y197762D03*
X1748500Y193862D03*
X1745500D03*
X1741200D03*
X1754234Y190836D03*
X1752078Y216728D03*
X1740500Y217962D03*
Y214962D03*
Y211962D03*
Y208962D03*
X1747600Y209062D03*
X1744600D03*
X1751800Y206762D03*
X1752078Y226728D03*
Y224228D03*
Y221728D03*
Y219228D03*
X1740500Y226962D03*
Y223962D03*
Y220962D03*
X1754307Y262186D03*
X1751068Y266048D03*
X1754307Y266111D03*
X1754414Y275329D03*
X1752165Y273901D03*
X1749565D03*
X1751006Y269661D03*
X1749595Y276711D03*
X1752195D03*
X1745000Y299862D03*
X1749450Y293862D03*
X1752000Y306562D03*
X1748989Y380206D03*
X1740831Y489362D03*
X1752316Y703969D03*
Y695669D03*
X1752217Y692988D03*
X1752276Y720529D03*
X1752316Y712269D03*
X1747814Y1287344D03*
X1742714Y1287244D03*
X1754165Y1304422D03*
Y1307422D03*
Y1301422D03*
Y1295422D03*
Y1298422D03*
Y1310422D03*
X1746970Y1451872D03*
X1738740Y1451742D03*
X1750970Y1459172D03*
Y1456172D03*
X1740200Y1462932D03*
X1745111Y1463262D03*
X1744677Y1507388D03*
X1744304Y1524976D03*
X1751866Y1737108D03*
X1767768Y3010D03*
X1762420Y21562D03*
X1765238Y22062D03*
X1758672Y26431D03*
X1755272D03*
X1760475Y28360D03*
X1769900Y37732D03*
X1767220Y26962D03*
X1758669Y50649D03*
X1755269D03*
X1760485Y48720D03*
X1762738Y53262D03*
X1767220Y53342D03*
X1767400Y39915D03*
X1769274Y50742D03*
X1759700Y57662D03*
X1764400Y57462D03*
X1758063Y68637D03*
X1758573Y87107D03*
Y83607D03*
X1768168Y80497D03*
X1758568Y79697D03*
X1765068Y80397D03*
X1758063Y72623D03*
X1770368Y72691D03*
X1766278Y93627D03*
X1757978Y116727D03*
X1760978D03*
X1763678Y106127D03*
X1769278Y108027D03*
Y110927D03*
Y113727D03*
X1755978Y108427D03*
Y111027D03*
X1760478Y106127D03*
X1764678Y122927D03*
X1758300Y128242D03*
X1763435Y166862D03*
X1765870Y179392D03*
X1755078Y216928D03*
X1761500Y214062D03*
X1765000D03*
X1768500D03*
X1766880Y234842D03*
Y231842D03*
X1758500Y231822D03*
Y234822D03*
X1755378Y233528D03*
X1755078Y219428D03*
Y221928D03*
Y224428D03*
X1763731Y283817D03*
X1766725Y282981D03*
X1763731Y279517D03*
X1760398Y279548D03*
X1766765Y279433D03*
X1757439Y279611D03*
X1760398Y283848D03*
X1759509Y292434D03*
X1762549Y286704D03*
X1757439Y283911D03*
X1768045Y295238D03*
X1765053Y295188D03*
X1762285Y295137D03*
X1759629Y295164D03*
X1767309Y290994D03*
X1763045Y289691D03*
X1759529Y289864D03*
X1766655Y286531D03*
X1767455Y302651D03*
X1764955Y301951D03*
X1758563Y310478D03*
X1754963D03*
X1761936Y310709D03*
X1769230Y310478D03*
X1756800Y364048D03*
X1770520Y368148D03*
X1768757Y380498D03*
X1756800Y368048D03*
X1770280Y372452D03*
X1770220Y377452D03*
Y382952D03*
X1757066Y435721D03*
X1767300Y461393D03*
X1757650D03*
X1768560Y539042D03*
X1766060D03*
X1764112Y703948D03*
X1761612D03*
X1764112Y695648D03*
X1763570Y693192D03*
X1761612Y695648D03*
X1755112Y703948D03*
Y695648D03*
X1755013Y692967D03*
X1757612Y703948D03*
Y695648D03*
X1764072Y720508D03*
X1761572D03*
X1764112Y712248D03*
X1761612D03*
X1755072Y720508D03*
X1755112Y712248D03*
X1757572Y720508D03*
X1757612Y712248D03*
X1757165Y1304422D03*
X1760165D03*
Y1307422D03*
X1757165D03*
X1769165Y1301422D03*
X1766165D03*
X1763165D03*
X1757165D03*
X1760165D03*
X1769165Y1295422D03*
X1766165D03*
X1763165D03*
X1760165D03*
X1757165D03*
X1760165Y1298422D03*
X1757165D03*
X1763165D03*
X1766165D03*
X1769165D03*
X1757165Y1310422D03*
X1760165D03*
X1759987Y1325375D03*
Y1328275D03*
X1763829Y1337548D03*
X1766829D03*
Y1340448D03*
X1769829Y1337548D03*
Y1340448D03*
X1766829Y1343348D03*
X1769829Y1346248D03*
Y1343348D03*
Y1349148D03*
Y1351858D03*
X1760160Y1476032D03*
X1763730Y1483712D03*
Y1480712D03*
X1763830Y1490782D03*
Y1487782D03*
X1782305Y13647D03*
X1777754Y37746D03*
X1781774Y54462D03*
X1774274Y50742D03*
X1776710Y53562D03*
X1774328Y60087D03*
X1779778Y70027D03*
X1785178Y86927D03*
X1779778Y72927D03*
X1785178Y89927D03*
X1778578Y97927D03*
X1778478Y90627D03*
X1784178Y108227D03*
Y111127D03*
Y113927D03*
X1782000Y128455D03*
X1771915Y128393D03*
X1782000Y125955D03*
Y123455D03*
X1771915Y125893D03*
Y123393D03*
X1784238Y150744D03*
X1780320Y177602D03*
X1777520Y178403D03*
Y173903D03*
X1778778Y216928D03*
X1783878D03*
X1772000Y214062D03*
X1786690Y234782D03*
Y231782D03*
X1783800Y231762D03*
Y234762D03*
X1775140Y234792D03*
Y231792D03*
X1778778Y219428D03*
Y221928D03*
X1783878Y224428D03*
Y226928D03*
Y219428D03*
Y221928D03*
X1779226Y275604D03*
X1783563Y273471D03*
X1786089D03*
X1771029Y295164D03*
X1771229Y291064D03*
X1786089Y287641D03*
X1783563D03*
X1772863Y310478D03*
X1783018Y301729D03*
X1782324Y410432D03*
Y403932D03*
Y425432D03*
Y418932D03*
X1782420Y447137D03*
X1781470Y452065D03*
X1776160Y592792D03*
X1778310Y591152D03*
X1778165Y1307422D03*
Y1304422D03*
Y1301422D03*
X1775165D03*
X1772165D03*
X1778165Y1295422D03*
X1775165D03*
X1772165D03*
Y1298422D03*
X1775165D03*
X1778165D03*
X1784165Y1307422D03*
Y1304422D03*
X1781165Y1307422D03*
Y1304422D03*
X1784165Y1301422D03*
Y1295422D03*
Y1298422D03*
X1781165Y1301422D03*
Y1295422D03*
Y1298422D03*
X1781829Y1324448D03*
X1784829D03*
X1778829D03*
X1778165Y1310422D03*
Y1312922D03*
X1784165Y1310422D03*
Y1312922D03*
X1781165Y1310422D03*
Y1312922D03*
X1781829Y1333148D03*
Y1330248D03*
Y1327348D03*
X1784829Y1333148D03*
Y1330248D03*
Y1327348D03*
X1781829Y1337548D03*
Y1340448D03*
X1784829Y1337548D03*
Y1340448D03*
X1778829Y1333148D03*
Y1330248D03*
Y1327348D03*
Y1337548D03*
X1772829D03*
X1775829D03*
X1778829Y1340448D03*
X1775829D03*
X1772829D03*
X1781829Y1346248D03*
Y1343348D03*
Y1349148D03*
Y1351858D03*
Y1354758D03*
X1772829Y1346248D03*
X1775829D03*
X1778829D03*
X1772829Y1343348D03*
X1775829D03*
X1778829D03*
X1772829Y1349148D03*
X1775829D03*
X1778829D03*
X1772829Y1351858D03*
X1775829D03*
X1778829D03*
X1772829Y1354758D03*
X1775829D03*
X1778829D03*
X1771866Y1737108D03*
X1787768Y3010D03*
X1793061Y24659D03*
X1794910Y44573D03*
X1799920Y52594D03*
X1788238Y82292D03*
Y78062D03*
Y74912D03*
X1803215Y154032D03*
X1797663Y269571D03*
X1800189D03*
X1790563Y273471D03*
X1793089D03*
X1793269Y287641D03*
X1790743D03*
X1791619Y294441D03*
X1789093D03*
X1802763Y308671D03*
X1795763D03*
X1798289D03*
X1788763D03*
X1791289D03*
X1800160Y362542D03*
X1800340Y387062D03*
X1791494Y386536D03*
X1795479Y408056D03*
X1795468Y421334D03*
X1796020Y451162D03*
X1791888Y683805D03*
X1800107Y1256426D03*
X1798450Y1524830D03*
X1801450D03*
Y1527830D03*
X1814322Y49388D03*
X1807549Y56415D03*
X1807580Y59397D03*
X1806365Y154032D03*
X1807220Y179897D03*
X1814349Y269634D03*
X1811823D03*
X1807249D03*
X1804723D03*
X1812349Y308734D03*
X1809823D03*
X1805289Y308671D03*
X1817157Y373829D03*
X1816224Y410432D03*
X1816994Y398052D03*
X1815724Y423932D03*
X1812161Y472521D03*
X1803517Y1495567D03*
X1813700Y1494762D03*
X1818289Y1501591D03*
X1811494Y1505349D03*
X1813994Y1507891D03*
X1812250Y1521830D03*
X1811250Y1524830D03*
Y1527830D03*
X1807850D03*
X1804650D03*
Y1524830D03*
X1807850D03*
X1814370Y1528900D03*
X1814210Y1525815D03*
X1818524Y1528991D03*
X1834322Y49388D03*
X1828777Y156520D03*
X1823508Y158868D03*
X1825762Y167662D03*
X1835760Y185772D03*
X1829695Y226333D03*
X1832295D03*
X1827095D03*
X1824095D03*
X1834895D03*
Y223733D03*
X1824095D03*
X1827095D03*
X1832295D03*
X1829695D03*
X1832295Y233933D03*
X1829695D03*
X1827095D03*
X1824095D03*
X1829695Y231433D03*
X1832295D03*
X1829695Y228933D03*
X1832295D03*
X1827095Y231433D03*
X1824095D03*
X1827095Y228933D03*
X1824095D03*
X1834895Y233933D03*
Y231433D03*
Y228933D03*
X1829026Y367701D03*
X1829434Y406348D03*
X1834005Y401421D03*
X1821280Y413432D03*
X1834600Y406442D03*
X1826914Y431718D03*
X1829514Y1498198D03*
Y1500807D03*
X1832114Y1498198D03*
Y1500807D03*
X1824995Y1502201D03*
X1823426Y1507916D03*
X1831994Y1525977D03*
X1835334Y1520921D03*
X1821710Y1525915D03*
X1830466Y1606658D03*
X1828880Y1626595D03*
Y1646595D03*
Y1666595D03*
Y1686595D03*
X1846691Y166450D03*
X1848435Y172187D03*
X1838880Y195162D03*
X1837895Y226333D03*
Y223733D03*
Y233933D03*
Y231433D03*
Y228933D03*
X1843134Y244362D03*
X1850331Y311946D03*
X1840691Y329470D03*
Y349470D03*
Y369470D03*
X1836750Y373632D03*
X1836294Y383592D03*
X1840691Y389470D03*
Y409470D03*
Y429470D03*
Y449470D03*
X1838020Y459121D03*
X1838379Y453921D03*
X1840691Y469470D03*
Y489470D03*
Y509470D03*
Y529470D03*
Y549470D03*
Y569470D03*
Y589470D03*
Y669470D03*
Y1329470D03*
Y1409470D03*
Y1429470D03*
Y1449470D03*
Y1469470D03*
Y1489470D03*
Y1509470D03*
Y1529470D03*
Y1549470D03*
Y1569470D03*
Y1589470D03*
X1854096Y52383D03*
X1854470Y112379D03*
Y152379D03*
Y172379D03*
Y192379D03*
Y212379D03*
Y232379D03*
Y252379D03*
Y272379D03*
Y292379D03*
X1957430Y3107172D03*
X1955500Y3374622D03*
X1954950Y3664362D03*
X1969030Y2649912D03*
X2822321Y1759029D03*
X2828490Y3387175D03*
X2831830Y2616682D03*
X2832826Y2880599D03*
X2832836Y3131169D03*
X2833595Y3672637D03*
X3682620Y3698022D03*
G54D20*
X70472Y173228D03*
Y236220D03*
X2822321Y754329D03*
G54D21*
X159474Y1320753D03*
Y1328627D03*
X183847Y1320778D03*
Y1328652D03*
X208247Y1320778D03*
Y1328652D03*
X275289Y575702D03*
Y583576D03*
Y599861D03*
Y607735D03*
Y624015D03*
Y631889D03*
Y648169D03*
Y656043D03*
X270252Y676260D03*
Y700414D03*
X278126Y676260D03*
Y700414D03*
X387897Y1242785D03*
X395771D03*
X420171D03*
X412297D03*
X436619D03*
X444493D03*
X468893D03*
X461019D03*
X485419D03*
X493293D03*
X673093Y1320778D03*
Y1328652D03*
X697466Y1320803D03*
Y1328677D03*
X721866Y1320803D03*
Y1328677D03*
X1100800Y251488D03*
Y259362D03*
X1100700Y275788D03*
Y283662D03*
X1131100Y1357088D03*
Y1364962D03*
X1155500Y1357088D03*
Y1364962D03*
X1179900Y1357088D03*
Y1364962D03*
X1364038Y1242785D03*
X1371912D03*
X1396312D03*
X1388438D03*
X1412760D03*
X1420634D03*
X1445034D03*
X1437160D03*
X1461560D03*
X1469434D03*
X1577000Y591888D03*
Y599762D03*
Y616388D03*
Y624262D03*
Y640888D03*
Y648762D03*
Y665288D03*
Y673162D03*
Y689788D03*
Y697662D03*
Y714288D03*
Y722162D03*
X1634259Y1354374D03*
Y1362248D03*
X1658632Y1354399D03*
Y1362273D03*
X1683032Y1354399D03*
Y1362273D03*
X2822321Y1286229D03*
G54D30*
X676508Y224606D03*
X2822321Y577029D03*
G54D12*
X14092Y287115D03*
X16925Y203366D03*
X17061Y196368D03*
X24720Y216362D03*
Y232362D03*
Y224362D03*
Y240362D03*
X29962Y401000D03*
X33500Y200862D03*
X33670Y192862D03*
Y208362D03*
Y232362D03*
X42500Y224409D03*
X33670Y240362D03*
X40000Y298707D03*
X36000Y295952D03*
X40000Y293392D03*
X36255Y304972D03*
X39320Y392269D03*
X40940Y387302D03*
X48269Y1672771D03*
X54920Y185039D03*
Y177165D03*
X62020Y295952D03*
X53825Y421746D03*
X57595Y603476D03*
X56777Y1314165D03*
X54478Y1663669D03*
X54535Y1658447D03*
X53333Y1671862D03*
X65000Y1681900D03*
X58325Y1679275D03*
X65881Y305426D03*
X71772Y421746D03*
X75490Y432519D03*
X72981Y466385D03*
X80300Y641862D03*
X80241Y659011D03*
X80123Y664031D03*
X80135Y667933D03*
X74559Y667814D03*
X76565Y717949D03*
X65600Y1318588D03*
X65240Y1326068D03*
X77040Y1601102D03*
X65120Y1609909D03*
X65520Y1615972D03*
X74100Y1613300D03*
X77833Y1678902D03*
X73833Y1674252D03*
X69833Y1678582D03*
X86490Y200787D03*
Y208661D03*
X85960Y224409D03*
X85788Y240157D03*
X87620Y285321D03*
X87845Y278798D03*
Y295798D03*
X87820Y302821D03*
X87654Y376026D03*
X87520Y386502D03*
X85826Y420319D03*
X84410Y438519D03*
X94811Y510173D03*
X91027Y643276D03*
X95725Y654540D03*
X95860Y659622D03*
X83165Y652564D03*
X91078Y649584D03*
X83208Y646436D03*
X86433Y688160D03*
X83004Y705141D03*
X97295Y699786D03*
X95849Y716358D03*
X91610Y721414D03*
X81900Y1613300D03*
X85800D03*
X81833Y1674526D03*
X96420Y1693803D03*
X113490Y216596D03*
X113400Y232128D03*
X107200Y393562D03*
X107301Y388071D03*
X101317Y431727D03*
X113597Y488434D03*
X107419Y487807D03*
X112480Y507792D03*
X110689Y498271D03*
X99773Y515606D03*
X102269Y634466D03*
X107045Y661917D03*
X99021Y663732D03*
X103397Y667272D03*
X98134Y722501D03*
X112270Y1518907D03*
X103902Y1584337D03*
X104318Y1589352D03*
X100620Y1596367D03*
X100020Y1615821D03*
X104400Y1632385D03*
X104318Y1637862D03*
X99600Y1668332D03*
X99645Y1663217D03*
X99980Y1698921D03*
X115850Y186362D03*
X122000Y207362D03*
X116920Y207462D03*
X114087Y285495D03*
X118920Y278875D03*
X114087Y302854D03*
X119220Y306236D03*
X125007Y384071D03*
Y396071D03*
X119457Y392071D03*
X114507Y404571D03*
X125070Y486736D03*
X124124Y495883D03*
X118652Y528860D03*
X129762Y531942D03*
X121400Y638062D03*
X114021Y669409D03*
X122575Y671930D03*
X123220Y1324662D03*
X116798Y1589352D03*
X119500Y1622380D03*
X124795Y1681846D03*
X128195Y1674362D03*
X127195Y1696362D03*
Y1704362D03*
X117426Y1726622D03*
X125720Y1719262D03*
X132490Y420062D03*
X138042Y480238D03*
X132833D03*
X136982Y497090D03*
X131737Y496295D03*
X131295Y487822D03*
X138878Y512550D03*
X138408Y507366D03*
X139153Y516453D03*
X133160Y532002D03*
X132600Y537072D03*
X131740Y640103D03*
X131600Y646861D03*
X144263Y1412275D03*
X137420Y1708362D03*
X144520Y1717562D03*
X134557Y1722778D03*
X137852Y1726572D03*
X154220Y375682D03*
X160090Y391170D03*
Y397470D03*
X152826Y439397D03*
Y434362D03*
X156306Y449045D03*
X161267Y503143D03*
X151378Y526924D03*
X149568Y1395145D03*
X152684Y1403451D03*
X152026Y1614138D03*
X158335Y1614452D03*
X161310Y1708022D03*
X148145Y1701862D03*
X173275Y393497D03*
X164000Y415362D03*
X163926Y425383D03*
X164000Y420362D03*
X163926Y430883D03*
Y443319D03*
X178546Y453806D03*
X171262Y1443390D03*
X164920Y1712017D03*
X163060Y1717017D03*
X178226Y1726517D03*
X172962Y1721234D03*
X169777Y1726517D03*
X178142Y1720652D03*
X187371Y425383D03*
Y430883D03*
X194440Y433895D03*
Y439565D03*
X190827Y1403451D03*
X193293Y1722197D03*
X188794Y1725092D03*
X204699Y423242D03*
Y428742D03*
X204610Y571097D03*
X198336Y608271D03*
X204610Y605097D03*
X199164Y616481D03*
X204610Y639097D03*
X200654Y646271D03*
X200018Y677492D03*
X203120Y1624782D03*
X208115Y1624217D03*
X195590Y1714517D03*
X196010Y1709017D03*
X208295Y1703362D03*
X199050Y1726431D03*
X224210Y431501D03*
X224305Y422977D03*
X219995Y426267D03*
X224210Y436619D03*
X218140Y440735D03*
X218010Y432735D03*
X223664Y443125D03*
X220000Y448735D03*
X212891Y566632D03*
X219660Y1260492D03*
X214120Y1713462D03*
X235701Y21582D03*
X241310Y20322D03*
X238063Y26232D03*
X239820Y54362D03*
X239720Y71862D03*
X239010Y78542D03*
X242215Y151788D03*
X230359Y461683D03*
X246510Y20362D03*
X246360Y26852D03*
X249885Y69623D03*
X245220Y67862D03*
X253910Y115722D03*
X249735Y152694D03*
X259933Y141122D03*
X245490Y159702D03*
X255810Y405582D03*
X252500Y415862D03*
X258066Y426735D03*
X259845Y461117D03*
X257750Y450842D03*
X259510Y757822D03*
X263240Y38122D03*
X266990Y41832D03*
X275120Y28562D03*
X275900Y48872D03*
X263320Y87662D03*
X273620Y96662D03*
X263550Y120922D03*
X269191Y121092D03*
X275797Y120245D03*
X265910Y125492D03*
X260600Y151062D03*
X264578Y159203D03*
X263430Y422235D03*
X262963Y443735D03*
X272500Y447735D03*
X263040Y448752D03*
X272500Y452862D03*
X268331Y738029D03*
X272208Y768516D03*
X271057Y762425D03*
X287000Y20862D03*
X290799Y28362D03*
X289400Y54222D03*
X287000Y139862D03*
X276825Y140462D03*
X290685Y165447D03*
X277046Y735442D03*
X283350Y728483D03*
X289137Y735275D03*
X285046Y737964D03*
X299500Y22862D03*
X295520Y26362D03*
X300248Y28362D03*
X302720Y38182D03*
X293161Y50522D03*
X298550Y51602D03*
X303715Y50857D03*
X305247Y71567D03*
X301600Y82457D03*
X302310Y75673D03*
X295357Y88903D03*
X307820Y95724D03*
X305025Y144202D03*
X299628Y149203D03*
Y158703D03*
X295685Y165447D03*
X300520Y552262D03*
X307987Y577658D03*
X293805Y565997D03*
X298000Y587890D03*
X308417Y585158D03*
X308447Y592255D03*
X306144Y602225D03*
X294679Y685046D03*
X293027Y755985D03*
X306667Y1361597D03*
X310400Y50362D03*
X323040Y73122D03*
X322875Y84318D03*
X316364Y89212D03*
X310459Y75892D03*
X320430Y78002D03*
X324733Y148598D03*
X309756Y177449D03*
X320270Y200462D03*
X323314Y210645D03*
X322658Y229254D03*
X319718Y223750D03*
X316444Y559125D03*
X317860Y572322D03*
X319520Y577658D03*
X312007Y588675D03*
X319520Y582658D03*
X316127Y592785D03*
X318560Y587632D03*
X311820Y598762D03*
X317386Y623207D03*
X317967Y771875D03*
X335575Y214170D03*
X328588Y209677D03*
X328939Y229139D03*
X335385Y235309D03*
X335412Y222176D03*
X341295Y290239D03*
X336270Y402992D03*
X329050Y607402D03*
X338667Y772452D03*
X341527Y778362D03*
X338042Y849978D03*
X343040Y122522D03*
X343450Y131167D03*
X355189Y144267D03*
X351100Y150412D03*
X356295Y219362D03*
X353145Y228362D03*
X354145Y290591D03*
X343354Y391643D03*
X354100Y720743D03*
X348730Y735098D03*
X345178Y854584D03*
X348878Y880219D03*
X366775Y127662D03*
X366675Y158702D03*
X364014Y366391D03*
X371370Y373622D03*
X364014Y378649D03*
X370200Y409582D03*
X373720Y431362D03*
X365720Y440562D03*
X359669Y686744D03*
X359639Y690114D03*
X363101Y693948D03*
X360990Y726862D03*
X358902Y739755D03*
Y773352D03*
X363679Y893036D03*
X371850Y1534062D03*
X380930Y122022D03*
X379295Y131002D03*
X385720Y320902D03*
X376500Y366391D03*
Y378649D03*
X376770Y387272D03*
X390220Y392062D03*
X389920Y461362D03*
X387500Y495362D03*
X389020Y522862D03*
X381010Y734732D03*
X375211Y1099017D03*
X386827Y1429525D03*
X374900Y1534102D03*
X384600Y1595100D03*
X375430Y1676462D03*
X399240Y62722D03*
X404910Y62562D03*
X402700Y234167D03*
X396294Y281585D03*
X395520Y448362D03*
X402500Y495362D03*
X394500Y522862D03*
X400589Y575236D03*
X393279Y893036D03*
X404378Y899445D03*
X406229Y915466D03*
X402529Y921875D03*
X400679Y944304D03*
X402529Y966735D03*
Y960326D03*
X401111Y1028523D03*
X406662Y1057361D03*
X402962Y1063770D03*
X401111Y1054157D03*
X400888Y1395508D03*
X392947Y1397827D03*
X400924Y1408227D03*
X390777Y1435152D03*
X396946Y1537632D03*
X404920Y1539362D03*
X394360Y1616380D03*
X396824Y1673662D03*
X413459Y129061D03*
X420865Y215067D03*
X420752Y239562D03*
X412720Y439362D03*
X417880Y461942D03*
X418520Y473562D03*
X409929Y896240D03*
X415478Y893036D03*
X422878D03*
X419178Y899445D03*
X422878Y912262D03*
X411779Y918670D03*
X415911Y1047749D03*
X408511D03*
X417762Y1057361D03*
X421462Y1050952D03*
X417762Y1063770D03*
Y1076587D03*
X412211Y1073383D03*
X417762Y1070178D03*
X412211Y1066974D03*
X419612Y1099017D03*
X414061Y1095813D03*
X418320Y1383862D03*
X422320D03*
X414333Y1385292D03*
X410933Y1384648D03*
X414909Y1395658D03*
X408915Y1402606D03*
X411150Y1408163D03*
X411162Y1414126D03*
X416926Y1426471D03*
X412416Y1431645D03*
X419861Y1429718D03*
X419302Y1434700D03*
X422708Y1437560D03*
X410074Y1424993D03*
X416999Y1441908D03*
X413599D03*
X409140Y1566892D03*
X416020Y1620862D03*
X412456Y1649838D03*
X417960Y1650072D03*
X421320Y1671699D03*
X410249Y1673082D03*
X427120Y59862D03*
X428500Y65016D03*
Y70016D03*
X435340Y125346D03*
X429780Y149373D03*
Y153477D03*
X433695Y209862D03*
X429395Y236562D03*
X426490Y244262D03*
X428720Y439362D03*
X437720Y435362D03*
X437520Y476337D03*
X431220Y496362D03*
Y507143D03*
Y512623D03*
Y501643D03*
X430278Y893036D03*
X437678D03*
X426578Y899445D03*
X433978D03*
Y905853D03*
X426578D03*
X430279Y925079D03*
X432130Y934692D03*
X435830Y928283D03*
X427012Y1041340D03*
X432561Y1057361D03*
X428862Y1050952D03*
X423311Y1060565D03*
X428861Y1063770D03*
X432560Y1070178D03*
X425162D03*
X426320Y1383862D03*
X430320D03*
X439030Y1383692D03*
X436467Y1391687D03*
X438458Y1402169D03*
X438645Y1426890D03*
X437299Y1436774D03*
X425030Y1434292D03*
X433897Y1434670D03*
X424820Y1552605D03*
X431620Y1541362D03*
X433350Y1579509D03*
X432200Y1607060D03*
X432500Y1613822D03*
X426728Y1636495D03*
X446640Y104552D03*
X443678Y145710D03*
X446746Y152662D03*
X452071Y254862D03*
X442220Y323362D03*
X448220Y323582D03*
X455000Y340362D03*
X450500Y358862D03*
X446730Y382432D03*
X443770Y371042D03*
X443300Y410962D03*
X447750Y414112D03*
X453020Y414262D03*
X443744Y429553D03*
X451421D03*
X442520Y476337D03*
Y484837D03*
X451520D03*
X453680Y515072D03*
X441378Y899445D03*
X445078Y893036D03*
X452479D03*
X448778Y899445D03*
X445079Y905853D03*
X452479D03*
X448780Y912262D03*
X441380D03*
X448779Y918670D03*
X454329Y915466D03*
X446930Y934692D03*
X443230Y928283D03*
X450630D03*
X439530Y934692D03*
X449211Y1054157D03*
X449213Y1060565D03*
X454762Y1050952D03*
Y1057361D03*
X451061Y1076587D03*
X451062Y1070178D03*
X443842Y1389106D03*
X448020Y1391862D03*
X443424Y1397869D03*
X441369Y1394260D03*
X448114Y1396812D03*
X445339Y1415731D03*
X445230Y1411719D03*
X445723Y1419730D03*
X443850Y1423404D03*
X445294Y1430415D03*
X449778Y1441606D03*
X452520Y1564862D03*
X454661Y1609235D03*
X448181Y1614401D03*
X443800Y1610712D03*
X444940Y1641842D03*
X462320Y115948D03*
X466992Y145888D03*
X461900Y215244D03*
X466300Y217803D03*
X461900Y222921D03*
X466300Y225480D03*
X458264Y254862D03*
X461736Y301098D03*
Y306098D03*
X463198Y311587D03*
X465000Y340362D03*
X469830Y366158D03*
X456660Y359172D03*
X455720Y404762D03*
X458600Y414262D03*
X466520Y475812D03*
X461520Y484837D03*
X457456Y522516D03*
X470880Y572692D03*
X467130Y600122D03*
X459878Y893036D03*
X467278D03*
X456178Y899445D03*
X463578D03*
X470978D03*
X470980Y912262D03*
X470978Y918670D03*
X467278Y905853D03*
X461729Y909057D03*
X459878Y918670D03*
X465429Y921875D03*
X467711Y1047750D03*
X460311D03*
X471411Y1041340D03*
X456611D03*
X464011D03*
Y1054157D03*
X460311Y1060565D03*
X458460Y1070178D03*
X464011Y1066974D03*
X469560Y1070178D03*
X464011Y1073383D03*
X459321Y1396409D03*
X458441Y1414893D03*
X468880Y1418400D03*
X467400Y1556700D03*
X466520Y1574862D03*
X457220Y1603562D03*
X455681Y1622492D03*
X458978Y1634481D03*
X463344Y1637622D03*
X469580Y1640272D03*
X466460Y1672332D03*
X466180Y1678392D03*
X484396Y161364D03*
X476220Y158772D03*
X486800Y259162D03*
X478500Y258862D03*
X474736Y302098D03*
X479736Y303598D03*
Y308598D03*
X486720Y360862D03*
X482920Y398060D03*
X485020Y414162D03*
X480393Y429412D03*
X471920Y416687D03*
X474169Y476196D03*
X479169D03*
X472960Y602152D03*
X482780Y607012D03*
X476529Y896240D03*
X478380Y912262D03*
X478379Y918670D03*
X478378Y905853D03*
X480228Y960326D03*
X482078Y982756D03*
X478379Y969939D03*
X475111Y1047749D03*
X478811Y1034931D03*
Y1066974D03*
X475111Y1073383D03*
X482511D03*
X485141Y1405430D03*
X477968Y1548122D03*
X486210Y1547960D03*
X482400Y1558320D03*
X477905Y1659242D03*
X475150Y1654302D03*
X498700Y212685D03*
Y220362D03*
X503100Y215244D03*
Y222921D03*
X496028Y258590D03*
X495136Y300398D03*
X495036Y310398D03*
X492150Y336810D03*
X498720Y360862D03*
X497568Y397632D03*
X489520Y411862D03*
X494020Y414262D03*
X492970Y409252D03*
X502070Y424787D03*
X488070Y429412D03*
X493169Y476196D03*
X498169D03*
X493169Y484696D03*
X490307Y1421499D03*
X510600Y92782D03*
X513700Y117862D03*
X510900Y111962D03*
X519010Y147912D03*
X518186Y139821D03*
X514850Y168443D03*
X519236Y202404D03*
X518670Y219192D03*
X508500Y232862D03*
X508502Y298813D03*
X508500Y303362D03*
X508136Y309398D03*
X507160Y332452D03*
X514720Y360862D03*
X513720Y390362D03*
X513173Y408740D03*
X505777Y1425579D03*
X529720Y43054D03*
X534720Y42922D03*
X523978Y59074D03*
X529078Y59282D03*
X523220Y170362D03*
X534765Y161067D03*
X526920Y161362D03*
X529480Y183921D03*
X536127Y247652D03*
X531298Y284280D03*
X536420Y309422D03*
X526980Y322582D03*
X521820Y336762D03*
X531720Y360862D03*
X535220Y383552D03*
X525720Y390362D03*
X528145Y408705D03*
X526941Y447802D03*
X532650Y442376D03*
Y450330D03*
Y454270D03*
X536000Y520362D03*
X524820Y545319D03*
X530178Y893036D03*
X528975Y1369724D03*
X542050Y47452D03*
X539720Y42862D03*
X550971Y42902D03*
X544720Y42892D03*
X548609Y48082D03*
X543083Y146338D03*
X544390Y236512D03*
X550390Y231742D03*
X548390Y236512D03*
X546390Y231742D03*
X542050Y231722D03*
X539830Y274912D03*
X537720Y278212D03*
X549220Y339687D03*
X546758Y360502D03*
X550024Y369123D03*
Y401023D03*
X563482Y40826D03*
X565184Y47982D03*
X558058Y46352D03*
X553650Y48842D03*
X567865Y92656D03*
X564890Y142173D03*
X555220Y167937D03*
X561324Y301149D03*
X555520Y309827D03*
X557701Y369123D03*
X569080Y414002D03*
X559300Y422732D03*
X563700Y538477D03*
X565849Y1346968D03*
X566510Y1352217D03*
X573190Y42912D03*
X575330Y47672D03*
X570208Y47982D03*
X579930Y72052D03*
X570150Y102862D03*
X573360Y140532D03*
X581175Y164717D03*
X569965Y161232D03*
X569470Y171702D03*
X579481Y194378D03*
X578450Y218562D03*
X578390Y225362D03*
X577676Y300268D03*
X570440Y331930D03*
X571830Y348772D03*
X570200Y372229D03*
X571720Y381862D03*
X575050Y383602D03*
X577720Y381862D03*
X574491Y376549D03*
X581090Y426970D03*
X571930Y421232D03*
X571110Y442656D03*
Y446706D03*
X577220Y449462D03*
X583220Y493212D03*
X584173Y498422D03*
X577470Y505592D03*
X586260Y52222D03*
X599800Y43152D03*
X597955Y48047D03*
X593369Y45682D03*
X590680Y83591D03*
X598295Y171862D03*
X599720Y184887D03*
X593220D03*
X595415Y246515D03*
X593763Y293999D03*
X588850Y291622D03*
X593120Y342782D03*
X586070Y352302D03*
X591720Y430787D03*
X595380Y416660D03*
X599220Y444362D03*
X597220Y458688D03*
X590210Y484132D03*
X589260Y519421D03*
X611810Y34400D03*
X606880Y44682D03*
X614400Y46012D03*
X603063Y48023D03*
X606020Y84562D03*
X603720Y98362D03*
X608620Y94162D03*
X617585Y97257D03*
X613020Y94162D03*
X617409D03*
X603880Y93902D03*
X602580Y151052D03*
X603019Y146399D03*
X606260Y161652D03*
X605350Y293092D03*
X605870Y298172D03*
X605560Y303372D03*
X607590Y314732D03*
X614130Y328762D03*
X605305Y331162D03*
X615180Y336812D03*
X605898Y372984D03*
X609690Y402812D03*
X604779Y423862D03*
X604360Y452120D03*
X609520Y515162D03*
X613220Y654662D03*
X603276Y741375D03*
X602768Y758385D03*
X623300Y95762D03*
X620540Y100112D03*
X632300Y104472D03*
X627645Y236862D03*
X622730Y230362D03*
X629564Y256277D03*
X633150Y301457D03*
X627950Y298897D03*
X627600Y309134D03*
X632143Y306575D03*
X619474Y331162D03*
X622490Y402162D03*
X623220Y426362D03*
X625620Y447862D03*
Y442862D03*
X626400Y462812D03*
X625620Y457862D03*
Y452862D03*
X622860Y487310D03*
X623670Y507862D03*
X633000Y508700D03*
X632080Y1262074D03*
X628970Y1670880D03*
X643880Y42142D03*
X647447Y46322D03*
X641200Y46762D03*
X637000Y68142D03*
X634500Y73422D03*
X645330Y77132D03*
X640220Y85542D03*
X634690D03*
X639901Y103462D03*
X640000Y108542D03*
X639970Y113892D03*
X649870Y181942D03*
X645263Y235689D03*
X640295Y234237D03*
X636075Y389862D03*
X649075Y389937D03*
X638700Y400962D03*
X637220Y411362D03*
Y416362D03*
Y426362D03*
X640720Y452862D03*
X641235Y477377D03*
X640620Y483422D03*
X649218Y504277D03*
X642580Y508172D03*
X636960Y516002D03*
X648296Y528255D03*
X650599Y766798D03*
X647690Y1260812D03*
X643725Y1643467D03*
X648225Y1658482D03*
X642725Y1658562D03*
X635410Y1664220D03*
X637540Y1669480D03*
X645725Y1691182D03*
X640725Y1691452D03*
X650725Y1690682D03*
X642225Y1708457D03*
X648220Y1716912D03*
X636160Y1710662D03*
X648220Y1722921D03*
X651680Y73812D03*
X656500Y69662D03*
X661587D03*
X661600Y75562D03*
X657165Y79131D03*
X656426Y75431D03*
X652320Y123362D03*
X651730Y177212D03*
X652000Y402362D03*
X653100Y407862D03*
X667677Y441636D03*
X655820Y452662D03*
X655800Y461432D03*
X661865Y505334D03*
X656877Y514716D03*
X665990Y517131D03*
X661220Y526862D03*
X650794Y515039D03*
X666741Y1255381D03*
X664630Y1259442D03*
X661400Y1263522D03*
X663187Y1395170D03*
X666303Y1403476D03*
X651725Y1643397D03*
X677560Y40572D03*
X672250Y40812D03*
X682290Y46822D03*
X674035Y74522D03*
X673987Y87662D03*
X677820Y89462D03*
X680578Y75992D03*
X674540Y80652D03*
X670800Y85932D03*
X667940Y80142D03*
X671320Y91192D03*
X673720Y110362D03*
X668300Y132400D03*
X673713Y237725D03*
X683100Y369550D03*
X680928Y440061D03*
X671479Y443211D03*
X680928Y458959D03*
X677778Y468407D03*
X671479Y481006D03*
X667350Y470680D03*
X671479Y474707D03*
X675220Y508862D03*
X680220D03*
X673340Y530922D03*
X677980Y1262074D03*
X682160Y1548040D03*
X678621Y1571072D03*
X678619Y1579070D03*
X673420Y1650057D03*
X671610Y1673792D03*
X675120Y1716242D03*
X672270Y1721612D03*
X687120Y39632D03*
X692289Y40633D03*
X696800Y42108D03*
X696838Y47940D03*
X683440Y42832D03*
X687344Y46940D03*
X692389Y46439D03*
X690027Y70142D03*
X699475Y69982D03*
X688019Y109845D03*
X687034Y115896D03*
X697615Y123697D03*
X687238Y171071D03*
X683500Y381200D03*
X687500Y399402D03*
X685220Y391652D03*
X684077Y433761D03*
X687227Y458959D03*
X696676Y471557D03*
X693526Y477856D03*
X685220Y495887D03*
X695220D03*
X690220D03*
X695220Y508862D03*
X690330Y503530D03*
X695220Y516852D03*
X694100Y1261562D03*
X692233Y1252480D03*
X696810Y1300162D03*
X692280Y1302532D03*
X692100Y1567190D03*
X686220Y1640667D03*
X697595Y1666862D03*
X701838Y42202D03*
Y47940D03*
X710486Y77695D03*
X712340Y128093D03*
X707008Y125804D03*
X715600Y363900D03*
X705700Y361400D03*
X711200Y396500D03*
X707220Y399362D03*
X713220Y388362D03*
X701757Y521324D03*
X711220Y516852D03*
X705220Y530362D03*
X708090Y1262074D03*
X712222Y1570703D03*
X711102Y1575683D03*
X714162Y1574333D03*
X713052Y1579683D03*
X712582Y1584843D03*
X713102Y1601307D03*
X715775Y1599024D03*
X714380Y1589960D03*
X712512Y1596338D03*
X706103Y1617107D03*
X708857Y1613462D03*
X710570Y1629890D03*
X708830Y1623115D03*
X708999Y1646762D03*
X703719Y1646768D03*
X700460Y1660918D03*
X709678Y1658485D03*
X704759Y1677001D03*
X724620Y40062D03*
X728720Y43562D03*
X719820Y45862D03*
X729933Y108388D03*
X722500Y365500D03*
X727000D03*
X731400D03*
X725220Y380787D03*
X722500Y374100D03*
X727000D03*
X731400Y375000D03*
X728220Y388362D03*
X731322Y421163D03*
X728172Y424313D03*
X731322Y440061D03*
X718723Y462108D03*
X723220Y508882D03*
X717220D03*
X729220D03*
X729212Y531700D03*
X723450Y597072D03*
X720240Y598292D03*
X726141Y1255381D03*
X723700Y1258727D03*
X728977Y1574453D03*
X717402Y1574433D03*
X723942Y1574123D03*
X729052Y1602518D03*
X726092Y1598483D03*
X720987Y1599568D03*
X726810Y1652430D03*
X722630Y1655740D03*
X718758Y1673800D03*
X745900Y40362D03*
X733314Y40862D03*
X740100Y41162D03*
X746100Y46262D03*
X736620Y45262D03*
X736720Y101662D03*
X745035Y94632D03*
X735770Y94988D03*
X739823Y91052D03*
X741308Y108742D03*
X740220Y145362D03*
X732720Y231362D03*
X745685Y269322D03*
X741800Y363200D03*
X735800Y365500D03*
X732700Y351500D03*
X740200Y375100D03*
X735800Y375000D03*
X733220Y388362D03*
X737621Y424313D03*
X743980Y443482D03*
X741420Y494162D03*
X747600Y506592D03*
X735220Y508862D03*
X745220Y522362D03*
X735173Y521362D03*
X737580Y1262074D03*
X735300Y1648760D03*
X740840Y1655590D03*
X750700Y106642D03*
X754800Y97082D03*
X757340Y92562D03*
X758412Y298790D03*
X760469Y442647D03*
X757365Y459862D03*
X752500Y495762D03*
X757238Y483862D03*
X751220Y522362D03*
X755940Y516862D03*
X756650Y526072D03*
X761710Y517651D03*
X753000Y1261352D03*
X757720Y1375462D03*
Y1384062D03*
X758020Y1397862D03*
X758420Y1406862D03*
X758120Y1414762D03*
X749612Y1579023D03*
X749652Y1586407D03*
X749612Y1583023D03*
X749662Y1590733D03*
X749612Y1594683D03*
X758360Y1589661D03*
X750504Y1612521D03*
X758830Y1674823D03*
X751620Y1674312D03*
X774059Y68912D03*
X764850Y249792D03*
X766320Y264892D03*
X771490Y354942D03*
X768490D03*
X774490D03*
X765000Y354862D03*
X773245Y398212D03*
Y403212D03*
Y408212D03*
X771050Y416940D03*
X766195Y428212D03*
X774982Y446908D03*
X772365Y454862D03*
X768720Y459862D03*
X772365D03*
X765810Y506342D03*
X769745Y502600D03*
X775378Y502502D03*
X767080Y1262074D03*
X769452Y1584393D03*
X776922Y1590444D03*
X766603Y1721797D03*
X794057Y301569D03*
X793896Y309026D03*
X795520Y393462D03*
X781320Y398212D03*
X784730Y432682D03*
X787320Y444862D03*
Y439862D03*
Y454862D03*
Y449862D03*
Y459862D03*
X787360Y469862D03*
X796315Y469290D03*
X783340Y474802D03*
X782690Y488862D03*
X785800Y482762D03*
X783600Y502462D03*
X783450Y522462D03*
X791969Y618384D03*
X785541Y1255381D03*
X783130Y1259372D03*
X796880Y1262074D03*
X796280Y1254402D03*
X797052Y1611893D03*
X798204Y279146D03*
X802220Y393727D03*
X800352Y408389D03*
X803120Y428762D03*
X797720Y428412D03*
X798370Y439932D03*
X802790Y433832D03*
X801750Y444330D03*
X802810Y454862D03*
Y464862D03*
Y449862D03*
Y459862D03*
X802865Y474862D03*
X810815D03*
X812510Y486422D03*
X801567Y512942D03*
X810850Y770272D03*
X812440Y1258727D03*
X806323Y1343076D03*
X812130Y1343022D03*
X812652Y1577793D03*
X801652Y1584539D03*
X812698Y1587047D03*
X814570Y145952D03*
X814531Y139851D03*
X820900Y147112D03*
X815060Y280072D03*
X813490Y273862D03*
X825003Y389012D03*
X819220Y412264D03*
X821720Y428437D03*
X816810Y464862D03*
X816400Y472900D03*
X821720Y511082D03*
Y527082D03*
X815650Y516807D03*
X815241Y1255381D03*
X826750Y1262074D03*
X836779Y68008D03*
X839898Y87248D03*
X841584Y94181D03*
X845220Y135862D03*
Y129362D03*
X837160Y218212D03*
Y213207D03*
X844526Y204968D03*
X838820Y206872D03*
X840063Y285022D03*
X840850Y278948D03*
X838784Y392880D03*
X838220Y459562D03*
X838645Y492862D03*
X832590Y512888D03*
X829745Y498082D03*
X831705Y593877D03*
X842630Y1256912D03*
X832090Y1326862D03*
X839052Y1611893D03*
X850015Y87341D03*
X847472Y94754D03*
X860050Y215310D03*
X847580Y232222D03*
X861865Y273730D03*
X856243Y286447D03*
X859920Y308852D03*
X859740Y399081D03*
X856842Y410760D03*
X846490Y422131D03*
X857560Y417762D03*
X850610Y444352D03*
X857620Y492862D03*
X848620Y509752D03*
X853070Y515447D03*
X860345Y522162D03*
X859888Y593970D03*
X854777Y1586968D03*
X875169Y185113D03*
X873200Y194262D03*
X877971Y196652D03*
X867528Y231788D03*
X867700Y268262D03*
X863747Y280870D03*
X867237Y273325D03*
X868552Y285537D03*
X877322Y296051D03*
X868113Y409372D03*
X862320Y431462D03*
X863415Y445829D03*
X868110Y499142D03*
X866820Y736562D03*
X863925Y737697D03*
X883909Y281862D03*
X879587Y270004D03*
X883870Y272652D03*
X887338Y296760D03*
X893440Y336232D03*
X890820Y389362D03*
X887810Y582442D03*
X885310Y736442D03*
X884619Y916477D03*
X892317Y915872D03*
X888652Y1597793D03*
Y1609793D03*
X896540Y341132D03*
X896672Y1587073D03*
X896652Y1605793D03*
X922726Y176302D03*
X922100Y181791D03*
X917386Y184114D03*
X923836Y193563D03*
X923897Y445545D03*
X927034Y445594D03*
X912288Y472430D03*
X927154Y492103D03*
X918078Y495177D03*
X918212Y500777D03*
X926173Y512391D03*
X917980Y974952D03*
X914838Y985989D03*
X919488Y1660733D03*
X914500Y1671400D03*
X940424Y184190D03*
X936424D03*
X940410Y188852D03*
X935052Y812630D03*
X939740Y987762D03*
X933979Y1661327D03*
X942100Y1671100D03*
X957020Y264862D03*
X950660Y399472D03*
X949920Y404602D03*
X945100Y534464D03*
X957220Y582862D03*
X949560Y981392D03*
X956800Y1663725D03*
X962570Y282812D03*
X962882Y314512D03*
X967239Y320073D03*
X963854Y320113D03*
X975670Y392063D03*
X963720Y439862D03*
X970788Y501230D03*
X964347Y501262D03*
X969351Y512416D03*
X965904Y1554364D03*
X960904D03*
X962086Y1603984D03*
X990501Y152397D03*
X986369Y155358D03*
X985499Y168753D03*
X990115Y173039D03*
X987259Y276094D03*
X978000Y362462D03*
X988723Y369650D03*
X991934Y368443D03*
X986400Y383123D03*
X983770Y373962D03*
X979766Y377507D03*
X977949Y384205D03*
X980856Y392502D03*
X983629Y397628D03*
X979559Y399362D03*
X983970Y392562D03*
X991369Y408252D03*
X979240Y425212D03*
X980720Y512362D03*
X992306Y1295049D03*
X984270Y1554364D03*
X995180Y153689D03*
X1001101Y165510D03*
X996415Y172579D03*
X1002920Y174799D03*
X1008120Y198293D03*
X1000610Y211039D03*
X1005640Y210969D03*
X994743Y289843D03*
X1006201Y370004D03*
X999440Y371782D03*
X996922Y367764D03*
X1005123Y414662D03*
X997617Y412383D03*
X997394Y415578D03*
X997225Y419162D03*
X1005720Y498862D03*
X1003220Y512862D03*
X1005520Y510932D03*
X1008560Y589682D03*
X1001970Y1251522D03*
X1002070Y1256942D03*
X1007636Y1554364D03*
X993698Y1604000D03*
X1012791Y157596D03*
X1011320Y202169D03*
X1019355Y218423D03*
X1010005Y208424D03*
X1014500Y266862D03*
X1021118Y294290D03*
X1015520Y302862D03*
X1009800Y343800D03*
X1017163Y367963D03*
X1009883Y367955D03*
X1010420Y416062D03*
X1024200Y510362D03*
X1020392Y521826D03*
X1016360Y594682D03*
X1019000Y601042D03*
X1021654Y606302D03*
X1037618Y261200D03*
X1025862Y291727D03*
X1036278Y303993D03*
Y307393D03*
X1025004Y374662D03*
X1031153Y390152D03*
X1038294Y506504D03*
X1032155Y509737D03*
X1025530Y519627D03*
X1033040Y519852D03*
X1038130Y518417D03*
X1040720Y591862D03*
X1029630Y601252D03*
X1030830Y1261302D03*
X1030270Y1256042D03*
X1030780Y1266532D03*
X1031002Y1554364D03*
X1025298Y1604000D03*
X1043720Y363462D03*
X1045720Y591672D03*
X1045760Y596272D03*
X1051680Y614772D03*
X1047010Y1259222D03*
X1044930Y1263492D03*
X1054368Y1554364D03*
X1056898Y1604000D03*
X1072310Y364422D03*
X1062120Y477462D03*
X1058220Y585862D03*
X1061470D03*
X1061330Y1262074D03*
X1059410Y1252272D03*
X1059086Y1579240D03*
X1077270Y374131D03*
X1076598Y477087D03*
X1081930Y477132D03*
X1076739Y506461D03*
X1077751Y522235D03*
X1076520Y1259072D03*
X1088262Y1252293D03*
X1074480Y1263742D03*
X1074010Y1510650D03*
X1077734Y1554364D03*
X1084000Y1647110D03*
X1105580Y132822D03*
X1100630Y130376D03*
X1105553Y356475D03*
X1091000Y1262074D03*
X1106200Y1250162D03*
X1103530Y1263602D03*
X1105480Y1517982D03*
X1101600Y1554364D03*
X1104750Y1549346D03*
X1092436Y1603944D03*
X1118486Y208942D03*
X1111918Y234718D03*
X1120190Y255652D03*
X1120800Y1262074D03*
X1106740Y1267902D03*
X1110725Y1518046D03*
X1115802Y1615010D03*
X1117182Y1625460D03*
X1114150Y1715726D03*
X1132547Y64864D03*
X1129997Y69864D03*
X1124858Y197309D03*
X1128485Y198159D03*
X1124360Y259712D03*
X1125409Y305797D03*
X1124120Y643762D03*
X1136720Y641362D03*
X1133720Y642862D03*
X1133200Y1255702D03*
X1122879Y1431474D03*
X1125995Y1439780D03*
X1132187Y1582738D03*
X1127377Y1628485D03*
X1147700Y362731D03*
X1140465Y379592D03*
X1147700Y368041D03*
X1150140Y610362D03*
X1144810Y613762D03*
X1152241Y766798D03*
X1138783Y1255381D03*
X1150400Y1262074D03*
X1148563Y1257097D03*
X1153465Y1550301D03*
X1142187Y1582738D03*
X1152187D03*
X1140750Y1604330D03*
X1139392Y1620851D03*
X1159460Y194090D03*
X1159753Y361281D03*
X1159460Y366025D03*
X1156790Y373231D03*
X1158300Y585862D03*
X1170740Y602132D03*
X1168483Y1255381D03*
X1164138Y1439780D03*
X1163308Y1524187D03*
X1155433D03*
X1169213Y1550301D03*
X1161339D03*
X1161595Y1574738D03*
Y1582738D03*
X1169460Y1606630D03*
Y1616630D03*
Y1611630D03*
X1164830Y1628830D03*
X1163970Y1620600D03*
X1164830Y1645632D03*
X1169325Y1642600D03*
X1158325D03*
X1162383Y1652505D03*
X1161613Y1669112D03*
X1187413Y143132D03*
X1181420Y157962D03*
X1181700Y186962D03*
X1173314Y176452D03*
X1184510Y188962D03*
X1183460Y205342D03*
X1181470Y208802D03*
X1181500Y222162D03*
X1172795Y222174D03*
X1186653Y302242D03*
X1174120Y355362D03*
X1177570Y602052D03*
X1175217Y595762D03*
X1181941Y766798D03*
X1177222Y1255567D03*
X1179180Y1265872D03*
X1171595Y1582738D03*
X1174595Y1590738D03*
X1184200Y1599900D03*
X1185030Y1624660D03*
X1186830Y1645632D03*
X1175830D03*
X1180325Y1642600D03*
X1173383Y1652505D03*
X1184383D03*
X1183613Y1669112D03*
X1172613D03*
X1193532Y132644D03*
X1194800Y143112D03*
X1197414Y161592D03*
X1191020Y170862D03*
X1194840Y240672D03*
X1188810Y296088D03*
X1193590Y1267912D03*
X1195470Y1262802D03*
X1187830Y1522188D03*
X1198546Y1524688D03*
X1187720Y1536362D03*
X1198485Y1534313D03*
X1187720Y1553692D03*
X1198436Y1546492D03*
X1187720Y1544292D03*
X1198436Y1551192D03*
Y1556192D03*
Y1561062D03*
X1187720Y1558682D03*
Y1563182D03*
X1201600Y1633790D03*
X1197400Y1645942D03*
X1190895Y1642910D03*
X1194183Y1669422D03*
X1197240Y1691422D03*
X1190735Y1688390D03*
X1194793Y1698295D03*
X1201505Y1688435D03*
X1194023Y1714902D03*
X1215763Y114363D03*
X1206114Y132962D03*
X1206694Y139512D03*
X1214415Y153962D03*
X1214054Y186092D03*
X1208518Y174162D03*
X1213720Y195362D03*
X1215720Y204862D03*
X1219060Y213312D03*
X1206660Y224742D03*
X1213540Y224792D03*
X1207220Y247148D03*
X1210900Y265300D03*
X1205165Y380962D03*
X1218870Y418082D03*
X1214000Y599262D03*
X1208980Y598462D03*
X1208750Y1266546D03*
X1210457Y1658415D03*
X1205820Y1652910D03*
X1213980Y1676500D03*
X1217210Y1684520D03*
X1218810Y1691732D03*
X1208010Y1691467D03*
X1212305Y1688700D03*
X1216363Y1698605D03*
X1205563Y1698340D03*
X1215593Y1715212D03*
X1204793Y1714947D03*
X1225100Y91500D03*
X1225700Y108962D03*
X1223500Y111162D03*
X1229500Y125100D03*
X1225574Y188662D03*
X1229720Y197302D03*
X1225320Y200162D03*
X1233282Y201875D03*
X1233780Y214572D03*
X1231720Y217862D03*
Y209862D03*
X1232000Y248332D03*
X1230720Y380362D03*
X1232720Y377862D03*
X1224300Y380400D03*
X1224189Y1259155D03*
X1244200Y112862D03*
X1249362Y111600D03*
X1241100Y145842D03*
X1246272Y164889D03*
X1243100Y160181D03*
X1243184Y182422D03*
X1245593Y237462D03*
X1240500Y244332D03*
X1252040Y306480D03*
X1256093Y149462D03*
X1265010Y162222D03*
X1261899Y174648D03*
X1267315Y220701D03*
X1259703Y209808D03*
X1253440Y230552D03*
X1253860Y235622D03*
X1253950Y246692D03*
X1266715Y244692D03*
X1254370Y241302D03*
X1265065Y249982D03*
X1258883Y280558D03*
X1258250Y292986D03*
X1263150Y294726D03*
X1267150Y305998D03*
X1256220Y434362D03*
X1261220Y454362D03*
X1253220Y451362D03*
X1267220D03*
X1255920Y511362D03*
X1257586Y1334649D03*
X1275820Y87962D03*
X1271284Y108971D03*
X1278949Y123567D03*
X1282764Y135398D03*
X1277820Y140682D03*
X1281093Y144516D03*
X1271954Y159143D03*
X1271593Y165962D03*
X1278093Y184462D03*
X1278183Y201262D03*
X1272893Y191262D03*
X1271315Y220701D03*
X1273093Y213962D03*
X1277661Y225685D03*
X1278783Y221386D03*
X1282654Y226309D03*
X1276800Y276562D03*
X1269960Y294536D03*
X1272530Y429362D03*
X1284220D03*
X1280270Y434362D03*
X1272220D03*
X1278380Y463362D03*
X1276220Y477362D03*
X1283220D03*
X1269012Y1371693D03*
X1293454Y81232D03*
X1298640Y93062D03*
X1292880Y93162D03*
X1292899Y98519D03*
X1288093Y125962D03*
X1291478Y137745D03*
X1286150Y131092D03*
X1296999Y179649D03*
Y190749D03*
Y201849D03*
X1300393Y235762D03*
X1285710Y249182D03*
X1290293Y247562D03*
X1288637Y240448D03*
X1292630Y240462D03*
X1295540Y440902D03*
X1301310Y440862D03*
X1291220Y463362D03*
X1294440Y477267D03*
X1300220Y477362D03*
X1297298Y790982D03*
X1311260Y83032D03*
X1314406Y97756D03*
X1308274Y104162D03*
X1302080Y117032D03*
X1302060Y113852D03*
X1306617Y177799D03*
X1303407Y190749D03*
X1313025Y188899D03*
X1309833Y220349D03*
X1306627Y214799D03*
X1316242Y209249D03*
X1317100Y553900D03*
X1303576Y659671D03*
X1305187Y735630D03*
X1305117Y797125D03*
X1314184Y849978D03*
X1311952Y1321945D03*
X1304066Y1323578D03*
X1322248Y68487D03*
X1322415Y75480D03*
X1322906Y94212D03*
X1319968Y98266D03*
X1322906Y109733D03*
X1329062Y164849D03*
X1326918Y161161D03*
X1332268Y174099D03*
X1325857Y218499D03*
X1323912Y245111D03*
X1320387Y258901D03*
X1325769Y259001D03*
X1321320Y854584D03*
X1325020Y880219D03*
X1347640Y101950D03*
X1343034Y141698D03*
X1342903Y170399D03*
X1343521Y893036D03*
X1366369Y83820D03*
X1360186Y226264D03*
X1356220Y581862D03*
X1361727Y680665D03*
X1351354Y1099017D03*
X1364860Y1455172D03*
X1375619Y236261D03*
X1370207Y682245D03*
X1373121Y893036D03*
X1380520Y899445D03*
X1378671Y921875D03*
Y966735D03*
Y960326D03*
X1377253Y1028523D03*
Y1047749D03*
X1377255Y1060565D03*
X1380953Y1054157D03*
X1377254Y1066974D03*
X1379192Y1325373D03*
X1370577Y1421899D03*
X1377075Y1425014D03*
X1386684Y145017D03*
X1386404Y149008D03*
X1394182Y171470D03*
X1398182D03*
X1399020Y905853D03*
X1384220Y918670D03*
X1391621D03*
X1395753Y1047749D03*
X1384653D03*
X1390204Y1050952D03*
X1393904Y1057361D03*
X1382804Y1063770D03*
X1393904D03*
Y1076587D03*
X1388353Y1073383D03*
X1393904Y1070178D03*
X1388353Y1066974D03*
X1395754Y1099017D03*
X1390203Y1095813D03*
X1396311Y1385712D03*
X1398680Y1380582D03*
X1390474Y1385142D03*
X1387074Y1384272D03*
X1390513Y1395452D03*
X1387066Y1401734D03*
X1387291Y1408163D03*
X1390170Y1423942D03*
X1393630Y1426562D03*
X1388557Y1431645D03*
X1395907Y1430227D03*
X1395443Y1434700D03*
X1398569Y1437860D03*
X1383429Y1427652D03*
X1389220Y1446708D03*
X1391655Y1570037D03*
X1391055Y1565037D03*
X1393000Y1590300D03*
X1413900Y225212D03*
X1406420Y873810D03*
Y905853D03*
X1411971Y934691D03*
X1406420Y925079D03*
Y931488D03*
X1411971Y928283D03*
X1403154Y1041340D03*
X1408703Y1057361D03*
Y1063770D03*
X1399453Y1054157D03*
X1405004Y1050952D03*
X1401304Y1063770D03*
X1399453Y1073383D03*
X1405004Y1070178D03*
X1411320Y1325373D03*
X1401655Y1384676D03*
X1406461Y1383862D03*
X1415171Y1383692D03*
X1412608Y1391687D03*
X1414362Y1402191D03*
X1414786Y1426890D03*
X1413440Y1436774D03*
X1409680Y1430613D03*
X1401371Y1434592D03*
X1410477Y1440117D03*
X1410038Y1434670D03*
X1403350Y1516435D03*
X1400695Y1570037D03*
X1400715Y1565037D03*
X1401300Y1619917D03*
X1400000Y1626362D03*
X1410500Y1638862D03*
X1415340Y231812D03*
X1431430Y251265D03*
Y256383D03*
Y264060D03*
X1430471Y909057D03*
X1424921Y905853D03*
X1415671Y909057D03*
X1421222Y912262D03*
X1424921Y918670D03*
X1430471Y915466D03*
X1424921Y931488D03*
X1419371Y928283D03*
X1424921Y925079D03*
X1419371Y934691D03*
X1425353Y1054157D03*
X1425355Y1060565D03*
X1430903Y1050952D03*
X1430904Y1057361D03*
X1427203Y1076587D03*
X1427204Y1070178D03*
X1418990Y1387452D03*
X1415620Y1396652D03*
X1419055Y1392497D03*
X1423256Y1403728D03*
X1424255Y1396612D03*
X1421480Y1415731D03*
X1421371Y1411719D03*
X1421864Y1419730D03*
X1419991Y1423404D03*
X1416272Y1433949D03*
X1421435Y1430415D03*
X1426020Y1521535D03*
X1427120Y1537355D03*
X1427320Y1548575D03*
X1416800Y1564862D03*
X1425620Y1556662D03*
X1428403Y1581378D03*
X1416060Y1574922D03*
X1447340Y157402D03*
X1436270Y312592D03*
X1436335Y309407D03*
X1436050Y321352D03*
X1447120Y899445D03*
X1443420Y912262D03*
X1437871Y909057D03*
X1436020Y918670D03*
X1443420Y905853D03*
X1441571Y921875D03*
X1447553Y1041340D03*
X1436453Y1047750D03*
X1443853D03*
X1432753Y1041340D03*
X1440153D03*
Y1054157D03*
X1436453Y1060565D03*
Y1073383D03*
Y1066974D03*
X1442002Y1070178D03*
X1447553Y1066974D03*
X1443448Y1325373D03*
X1444997Y1392885D03*
X1435462Y1396409D03*
X1443112Y1417929D03*
X1445020Y1412672D03*
X1443676Y1432624D03*
X1439742Y1436924D03*
X1434720Y1454862D03*
X1440440Y1454892D03*
X1436330Y1521152D03*
X1436570Y1536972D03*
X1436720Y1548192D03*
X1437140Y1576012D03*
X1446700Y1598400D03*
X1438320Y1668292D03*
X1438220Y1673955D03*
X1446715Y1679957D03*
X1450270Y143022D03*
X1450720Y153362D03*
X1448820Y148092D03*
X1450720Y161862D03*
X1449740Y166912D03*
X1450720Y173862D03*
X1462561Y205982D03*
X1457361D03*
X1459961Y210432D03*
X1456150Y214382D03*
X1456770Y342942D03*
X1462790Y359042D03*
X1462870Y355012D03*
X1459900Y370823D03*
X1455920Y373941D03*
X1463600Y374462D03*
X1449777Y371039D03*
X1455642Y409646D03*
X1456777Y418596D03*
Y426546D03*
X1455692Y731401D03*
X1452671Y896240D03*
X1454521Y918670D03*
X1454522Y912262D03*
X1448970Y915466D03*
X1454520Y905853D03*
X1456370Y960326D03*
X1458220Y982756D03*
X1454521Y969939D03*
X1451253Y1047749D03*
X1454953Y1034931D03*
X1453104Y1076587D03*
Y1070178D03*
X1458653Y1073383D03*
X1451198Y1403047D03*
X1461062Y1413246D03*
X1448620Y1556162D03*
X1448920Y1675062D03*
X1464200Y67802D03*
X1473090Y204502D03*
X1467761Y205982D03*
X1476858Y225448D03*
X1471308Y230640D03*
X1466958Y244948D03*
X1474660Y252878D03*
X1473820Y265962D03*
X1471690Y259862D03*
X1466660Y273878D03*
X1467700Y370953D03*
X1472758Y370817D03*
X1465836Y408668D03*
X1470942Y409718D03*
X1475250Y401812D03*
X1470841Y721493D03*
X1466448Y1421499D03*
X1478320Y1522962D03*
X1478061Y1633864D03*
X1493120Y240412D03*
X1481766Y372288D03*
X1489443D03*
X1494784Y374188D03*
X1486040Y368392D03*
X1481766Y406238D03*
X1490384Y407292D03*
X1493384Y411313D03*
X1482650Y411190D03*
X1495527Y406215D03*
X1486880Y416863D03*
X1489310Y426822D03*
X1481918Y1425579D03*
X1482830Y1525162D03*
X1508959Y215802D03*
X1499922Y211240D03*
X1504484Y234562D03*
X1508410Y230842D03*
X1510017Y225516D03*
X1501840Y225502D03*
X1512420Y239116D03*
X1510810Y249742D03*
X1509040Y243362D03*
X1504890Y249862D03*
X1506600Y239092D03*
X1498984Y282797D03*
X1512244Y311522D03*
X1505922Y304583D03*
X1498184Y361723D03*
Y369798D03*
X1506320Y893036D03*
X1510027Y1425825D03*
X1522920Y113030D03*
X1518575Y138662D03*
X1526675Y140117D03*
X1526083Y146225D03*
X1524539Y215551D03*
X1522009Y210825D03*
X1518110Y215551D03*
X1526998Y209645D03*
X1527732Y219488D03*
X1514520Y231116D03*
X1526152Y225114D03*
X1517669Y291516D03*
X1516137Y1432135D03*
X1544010Y27552D03*
X1535320Y113062D03*
X1529500Y122122D03*
X1529233Y153162D03*
X1535450Y155262D03*
X1542401Y141561D03*
X1545447Y156035D03*
X1537262Y197834D03*
X1533385Y193108D03*
X1533148Y211614D03*
X1531824Y207677D03*
X1534194Y217519D03*
X1535561Y225393D03*
X1531110Y264862D03*
X1539150Y267132D03*
X1540989Y616587D03*
X1541211Y646178D03*
X1554239Y138263D03*
X1552960Y124359D03*
X1551160Y189342D03*
X1557900Y220362D03*
X1557760Y214792D03*
X1550353Y217352D03*
X1559400Y229832D03*
X1559387Y589340D03*
X1550487Y681565D03*
X1550320Y696562D03*
X1550917Y704332D03*
X1550390Y709885D03*
X1573560Y245078D03*
X1574760Y251032D03*
X1563714Y572792D03*
X1564690Y663302D03*
X1562871Y735716D03*
X1603530Y202402D03*
X1604200Y234642D03*
X1604240Y227892D03*
Y238242D03*
X1608000Y1261662D03*
X1623881Y117627D03*
X1611475Y1259227D03*
X1624600Y1262074D03*
X1623930Y1252242D03*
X1614116Y1411169D03*
X1624353Y1428766D03*
X1636393Y181778D03*
X1633111Y206693D03*
X1642135Y414202D03*
X1630643Y1440290D03*
X1627469Y1437072D03*
X1647110Y434177D03*
X1654110D03*
X1657755Y517910D03*
X1649291Y556057D03*
X1645530Y549160D03*
X1645300Y612202D03*
X1653319Y642311D03*
X1649363Y649485D03*
Y683485D03*
Y717485D03*
X1654600Y1262742D03*
X1668100Y180852D03*
X1666690Y193290D03*
X1674432Y216981D03*
X1672596Y220541D03*
X1668426Y222432D03*
X1664866Y225162D03*
X1660861Y227548D03*
X1661110Y434177D03*
X1667376Y515531D03*
X1665790Y523417D03*
X1668917Y549992D03*
X1663502Y555115D03*
X1669222Y604490D03*
X1660660Y602273D03*
X1665612Y1437072D03*
X1665940Y1512862D03*
X1666123Y1524862D03*
Y1537862D03*
Y1553557D03*
X1666198Y1565557D03*
X1671660Y1569412D03*
X1666198Y1585321D03*
X1678994Y217231D03*
X1690208Y421855D03*
X1689095Y462640D03*
X1690229Y481845D03*
X1681817Y495290D03*
X1675664Y513802D03*
X1690999Y513107D03*
X1683702Y514687D03*
X1676600Y523902D03*
X1688768Y518107D03*
X1689544Y543874D03*
X1689506Y539882D03*
X1679941Y552222D03*
X1678860Y556752D03*
X1683369Y562698D03*
X1683578Y1253780D03*
X1683500Y1264312D03*
X1680720Y1487062D03*
X1678340Y1500862D03*
X1677930Y1520362D03*
X1678340Y1541362D03*
X1678230Y1590542D03*
X1693987Y230174D03*
X1703487Y232174D03*
X1698220Y369652D03*
X1702959Y404243D03*
X1707780Y410738D03*
X1697161Y406602D03*
X1692429Y403985D03*
X1701124Y423802D03*
X1694050Y416643D03*
X1695455Y422287D03*
X1707544Y431745D03*
X1707568Y420370D03*
X1697648Y463724D03*
X1693720Y455862D03*
X1702127Y468719D03*
X1701811Y501318D03*
X1697210Y500802D03*
X1693711Y498527D03*
X1707200Y498962D03*
X1699553Y513107D03*
X1707552Y506731D03*
X1707716Y513562D03*
X1702930Y526102D03*
X1701726Y518107D03*
X1699107Y555783D03*
X1703306Y550064D03*
X1692883Y703943D03*
X1701320Y705678D03*
X1696402Y709533D03*
X1705035Y729210D03*
X1699089Y1258842D03*
X1699030Y1263912D03*
X1691988Y1517803D03*
Y1538803D03*
Y1558262D03*
X1705723Y1583821D03*
X1715210Y18282D03*
X1709589Y26062D03*
X1720895Y68062D03*
X1712720Y111862D03*
X1714180Y154790D03*
X1721220Y458362D03*
X1713977Y457137D03*
X1708977Y458542D03*
X1713977Y470804D03*
X1708977D03*
X1716148Y483720D03*
X1716087Y495665D03*
X1716156Y487685D03*
X1716278Y491676D03*
X1709356Y541144D03*
X1709680Y545432D03*
X1716480Y691410D03*
X1710122Y703509D03*
X1709828Y719283D03*
X1713930Y1262074D03*
X1714440Y1255381D03*
X1718149Y1496270D03*
X1717149Y1505895D03*
X1717988Y1520951D03*
X1711988D03*
X1717149Y1513945D03*
X1717988Y1530445D03*
X1711988D03*
X1729080Y118132D03*
X1739720Y120892D03*
X1728999Y112895D03*
X1733920Y151362D03*
X1728320Y169862D03*
X1737470Y177147D03*
X1725344Y359334D03*
X1729810Y390620D03*
X1737660D03*
X1734290Y423820D03*
X1739316Y480939D03*
X1727674Y1513945D03*
X1729310Y1520951D03*
X1735310D03*
X1729310Y1530445D03*
X1735310D03*
X1748720Y97362D03*
X1745010Y122952D03*
X1750820Y119972D03*
X1747591Y171733D03*
X1751068Y262123D03*
X1754245Y269724D03*
X1746484Y279682D03*
X1756204Y301695D03*
X1756933Y372452D03*
X1744380Y382892D03*
X1744510Y377452D03*
X1747080Y435870D03*
X1746720Y464862D03*
X1740886Y493960D03*
X1743710Y1262074D03*
X1742337Y1252300D03*
X1747677Y1507388D03*
X1747304Y1524976D03*
X1768026Y24165D03*
X1769669Y15244D03*
X1761998Y15187D03*
X1765260Y18262D03*
X1757320Y15872D03*
X1767185Y48817D03*
X1771774Y53682D03*
X1767170Y83607D03*
X1767990Y76797D03*
X1760478Y90027D03*
X1768483Y166260D03*
X1765820Y182282D03*
X1767300Y174587D03*
X1760104Y301648D03*
X1770520Y364148D03*
X1765670Y458012D03*
X1767300Y465893D03*
X1768317Y686375D03*
X1758352Y1317368D03*
Y1322168D03*
X1775556Y21471D03*
X1775830Y26522D03*
X1779411Y50692D03*
X1774328Y62987D03*
X1775580Y73330D03*
X1787790Y85132D03*
X1781485Y88192D03*
X1785142Y76032D03*
X1773611Y88293D03*
X1780320Y153162D03*
X1774950Y167392D03*
X1779500Y171692D03*
X1782600Y175932D03*
X1777354Y295489D03*
X1782420Y443987D03*
X1773870Y438222D03*
X1781720Y592742D03*
X1788219Y1259312D03*
X1773390Y1262074D03*
X1773480Y1253692D03*
X1788360Y1264522D03*
X1797324Y161465D03*
X1803129Y362293D03*
X1802929Y385293D03*
X1792450Y410615D03*
X1792507Y403932D03*
X1792220Y425432D03*
X1792335Y418775D03*
X1803100Y1262074D03*
X1795484Y1496401D03*
X1800450Y1505230D03*
X1792645Y1511423D03*
X1795561Y1524729D03*
X1806920Y150862D03*
X1808910Y143902D03*
X1813335Y155435D03*
X1810835Y163986D03*
X1819939Y177243D03*
X1813325Y177257D03*
X1820307Y373829D03*
X1820144Y398052D03*
X1819374Y410432D03*
X1818874Y423932D03*
X1810792Y417432D03*
X1818816Y468872D03*
X1821083Y1252034D03*
X1814537Y1322105D03*
X1807150Y1505675D03*
X1818410Y1525815D03*
X1828204Y328654D03*
X1829189Y363731D03*
X1829920Y1258322D03*
X1829940Y1263662D03*
X1828510Y1525915D03*
X1841257Y151402D03*
X1838910Y185772D03*
X1844157Y182210D03*
X2822321Y1818129D03*
Y1995429D03*
G54D31*
X705760Y-26500D03*
Y-16500D03*
D03*
Y-6500D03*
X730760Y-26500D03*
Y-16500D03*
D03*
Y-6500D03*
X822720Y3500D03*
Y13500D03*
D03*
Y23500D03*
X847720Y3500D03*
Y13500D03*
D03*
Y23500D03*
X973180Y-26500D03*
Y-16500D03*
D03*
Y-6500D03*
Y3500D03*
Y13500D03*
Y23500D03*
Y13500D03*
X998180Y-26500D03*
Y-16500D03*
D03*
Y-6500D03*
Y3500D03*
Y13500D03*
Y23500D03*
Y13500D03*
X1015152Y-26511D03*
Y-36511D03*
Y-26511D03*
Y-16511D03*
D03*
Y-6511D03*
D03*
Y3489D03*
D03*
Y13489D03*
D03*
Y23489D03*
X1040152Y-26511D03*
Y-36511D03*
Y-26511D03*
Y-16511D03*
D03*
Y-6511D03*
D03*
Y3489D03*
D03*
Y13489D03*
D03*
Y23489D03*
X1282572Y-36511D03*
Y-26511D03*
D03*
Y-16511D03*
D03*
Y-6511D03*
Y3489D03*
Y-6511D03*
Y3489D03*
Y13489D03*
Y23489D03*
Y13489D03*
X1307572Y-36511D03*
Y-26511D03*
D03*
Y-16511D03*
D03*
Y-6511D03*
Y3489D03*
Y-6511D03*
Y3489D03*
Y13489D03*
Y23489D03*
Y13489D03*
X1324471Y-26511D03*
Y-36511D03*
Y-26511D03*
Y-16511D03*
D03*
Y-6511D03*
D03*
Y3489D03*
D03*
Y13489D03*
D03*
Y23489D03*
X1349471Y-26511D03*
Y-36511D03*
Y-26511D03*
Y-16511D03*
D03*
Y-6511D03*
D03*
Y3489D03*
D03*
Y13489D03*
D03*
Y23489D03*
X1474931Y-36511D03*
Y-26511D03*
D03*
Y-16511D03*
D03*
Y-6511D03*
Y3489D03*
Y-6511D03*
Y3489D03*
Y13489D03*
Y23489D03*
Y13489D03*
X1499931Y-36511D03*
Y-26511D03*
D03*
Y-16511D03*
D03*
Y-6511D03*
Y3489D03*
Y-6511D03*
Y3489D03*
Y13489D03*
Y23489D03*
Y13489D03*
X1565236Y184783D03*
Y264035D03*
X2822321Y695229D03*
G54D13*
X19685Y-29134D03*
Y1803261D03*
X1837795Y-29134D03*
Y1803261D03*
X2081889Y-29134D03*
Y1803261D03*
G54D22*
X174685Y637367D03*
Y647210D03*
X174393Y668511D03*
Y678354D03*
X205159Y1430034D03*
X195316D03*
X383224Y1354446D03*
X393067D03*
X412990D03*
X422833D03*
X453169D03*
X443326D03*
X468443Y1379662D03*
X458600D03*
X482543Y1353962D03*
X472700D03*
X526478Y1439952D03*
Y1449795D03*
X708795Y1429579D03*
X718638D03*
X1077638Y133866D03*
X1168627Y1466363D03*
X1178470D03*
X1359365Y1353946D03*
X1369208D03*
X1389131D03*
X1398974D03*
X1429310D03*
X1419467D03*
X1444043Y1379362D03*
X1434200D03*
X1459076Y1353946D03*
X1449233D03*
X1502956Y1439530D03*
Y1449373D03*
X1670101Y1463655D03*
X1682882Y618174D03*
Y628017D03*
Y669109D03*
Y678952D03*
X1679944Y1463655D03*
X1769790Y194789D03*
Y204632D03*
X1799350Y194789D03*
Y204632D03*
X1836248Y269763D03*
X1826405D03*
X1836248Y299056D03*
X1826405D03*
X2822321Y1463529D03*
Y1522629D03*
G54D40*
X1131715Y1532913D03*
X1175215D03*
X2822321Y813429D03*
G54D23*
X250326Y185236D03*
X368437D03*
X2822321Y-132171D03*
G54D41*
X1247638Y269488D03*
X1405118Y112008D03*
X1766929Y1714960D03*
X2822321Y399729D03*
G54D14*
X27699Y770144D03*
Y783530D03*
Y776837D03*
Y800263D03*
Y793570D03*
Y820341D03*
Y813648D03*
Y806955D03*
Y830381D03*
Y850459D03*
Y843766D03*
Y837074D03*
Y867192D03*
Y857152D03*
Y880577D03*
Y873885D03*
Y893963D03*
Y887270D03*
Y917389D03*
Y910696D03*
Y904003D03*
Y930774D03*
Y924081D03*
Y947507D03*
Y940814D03*
Y964239D03*
Y954200D03*
Y977625D03*
Y970932D03*
Y991011D03*
Y984318D03*
Y1031168D03*
Y1024475D03*
Y1017782D03*
Y1044554D03*
Y1037861D03*
Y1057940D03*
Y1051247D03*
Y1078018D03*
Y1071326D03*
Y1064633D03*
Y1094751D03*
Y1088058D03*
Y1108137D03*
Y1101444D03*
Y1124869D03*
Y1114829D03*
Y1144948D03*
Y1138255D03*
Y1131562D03*
Y1161680D03*
Y1151641D03*
Y1175066D03*
Y1168373D03*
Y1188452D03*
Y1181759D03*
Y1205184D03*
Y1198491D03*
Y1225263D03*
Y1218570D03*
Y1211877D03*
Y1241995D03*
Y1235302D03*
Y1248688D03*
Y1258727D03*
Y1255381D03*
Y1265420D03*
Y1262074D03*
X43841Y766798D03*
X36399Y770144D03*
X43841Y780184D03*
Y773491D03*
X36399Y783530D03*
Y776837D03*
X43841Y803609D03*
Y796916D03*
Y790223D03*
X36399Y800263D03*
Y793570D03*
X43841Y816995D03*
Y810302D03*
X36399Y820341D03*
Y813648D03*
Y806955D03*
X43841Y833727D03*
Y827034D03*
X36399Y830381D03*
X43841Y847113D03*
Y840420D03*
X36399Y850459D03*
Y843766D03*
Y837074D03*
X43841Y863845D03*
Y853806D03*
X36399Y867192D03*
Y857152D03*
X43841Y883924D03*
Y877231D03*
Y870538D03*
X36399Y880577D03*
Y873885D03*
X43841Y900656D03*
Y890617D03*
X36399Y893963D03*
Y887270D03*
X43841Y914042D03*
Y907349D03*
X36399Y917389D03*
Y910696D03*
Y904003D03*
X43841Y927428D03*
Y920735D03*
X36399Y930774D03*
Y924081D03*
X43841Y944160D03*
Y937467D03*
X36399Y947507D03*
Y940814D03*
Y960892D03*
Y957546D03*
Y967585D03*
X43841Y960892D03*
Y950853D03*
X36399Y964239D03*
Y954200D03*
Y960892D03*
Y957546D03*
X43841Y980971D03*
Y974278D03*
Y967585D03*
X36399Y977625D03*
Y970932D03*
Y967585D03*
X43841Y987664D03*
X36399Y991011D03*
Y984318D03*
X43841Y994357D03*
Y1027822D03*
Y1017782D03*
X36399Y1031168D03*
Y1024475D03*
Y1017782D03*
X43841Y1047900D03*
Y1041207D03*
Y1034515D03*
X36399Y1044554D03*
Y1037861D03*
Y1054593D03*
X43841Y1061286D03*
Y1054593D03*
X36399Y1057940D03*
Y1051247D03*
Y1054593D03*
X43841Y1074672D03*
Y1067979D03*
X36399Y1078018D03*
Y1071326D03*
Y1064633D03*
X43841Y1091404D03*
Y1084711D03*
X36399Y1094751D03*
Y1088058D03*
X43841Y1111483D03*
Y1104790D03*
Y1098097D03*
X36399Y1108137D03*
Y1101444D03*
X43841Y1128215D03*
Y1121522D03*
X36399Y1124869D03*
Y1114829D03*
X43841Y1141601D03*
Y1134908D03*
X36399Y1144948D03*
Y1138255D03*
Y1131562D03*
X43841Y1158333D03*
Y1148294D03*
X36399Y1161680D03*
Y1151641D03*
X43841Y1171719D03*
Y1165026D03*
X36399Y1175066D03*
Y1168373D03*
X43841Y1185105D03*
Y1178412D03*
X36399Y1188452D03*
Y1181759D03*
X43841Y1208530D03*
Y1201837D03*
Y1195144D03*
X36399Y1205184D03*
Y1198491D03*
X43841Y1221916D03*
Y1215223D03*
X36399Y1225263D03*
Y1218570D03*
Y1211877D03*
X43841Y1238648D03*
Y1231955D03*
X36399Y1241995D03*
Y1235302D03*
X43841Y1245341D03*
X36399Y1248688D03*
X36449Y1257262D03*
X43841Y1255381D03*
Y1258727D03*
Y1252034D03*
X33546Y1273364D03*
X30746D03*
X43841Y1262074D03*
Y1265420D03*
X57399Y770144D03*
X52541Y766798D03*
X57299D03*
X57399Y783530D03*
Y776837D03*
X52541Y780184D03*
Y773491D03*
X57399Y800263D03*
Y793570D03*
X52541Y803609D03*
Y796916D03*
Y790223D03*
X57399Y820341D03*
Y813648D03*
Y806955D03*
X52541Y816995D03*
Y810302D03*
X57399Y830381D03*
X52541Y833727D03*
Y827034D03*
X57399Y850459D03*
Y843766D03*
Y837074D03*
X52541Y847113D03*
Y840420D03*
X57399Y867192D03*
Y857152D03*
X52541Y863845D03*
Y853806D03*
X57399Y880577D03*
Y873885D03*
X52541Y883924D03*
Y877231D03*
Y870538D03*
X57399Y893963D03*
Y887270D03*
X52541Y900656D03*
Y890617D03*
X57399Y917389D03*
Y910696D03*
Y904003D03*
X52541Y914042D03*
Y907349D03*
X57399Y930774D03*
Y924081D03*
X52541Y927428D03*
Y920735D03*
X57399Y947507D03*
Y940814D03*
X52541Y944160D03*
Y937467D03*
Y964239D03*
X57399D03*
Y954200D03*
X52541Y960892D03*
Y950853D03*
Y964239D03*
Y957546D03*
Y954200D03*
X57399Y977625D03*
Y970932D03*
X52541Y980971D03*
Y974278D03*
Y967585D03*
X57399Y991011D03*
Y984318D03*
X52541Y987664D03*
Y1024475D03*
Y1021129D03*
X57399Y1031168D03*
Y1024475D03*
Y1017782D03*
X52541Y1027822D03*
Y1017782D03*
Y1021129D03*
Y1024475D03*
X57399Y1044554D03*
Y1037861D03*
X52541Y1047900D03*
Y1041207D03*
Y1034515D03*
Y1051247D03*
X57399Y1057940D03*
Y1051247D03*
X52541Y1061286D03*
Y1054593D03*
Y1051247D03*
X57399Y1078018D03*
Y1071326D03*
Y1064633D03*
X52541Y1074672D03*
Y1067979D03*
X57399Y1094751D03*
Y1088058D03*
X52541Y1091404D03*
Y1084711D03*
X57399Y1108137D03*
Y1101444D03*
X52541Y1111483D03*
Y1104790D03*
Y1098097D03*
X57399Y1124869D03*
Y1114829D03*
X52541Y1128215D03*
Y1121522D03*
X57399Y1144948D03*
Y1138255D03*
Y1131562D03*
X52541Y1141601D03*
Y1134908D03*
X57399Y1161680D03*
Y1151641D03*
X52541Y1158333D03*
Y1148294D03*
X57399Y1175066D03*
Y1168373D03*
X52541Y1171719D03*
Y1165026D03*
X57399Y1188452D03*
Y1181759D03*
X52541Y1185105D03*
Y1178412D03*
X57399Y1205184D03*
Y1198491D03*
X52541Y1208530D03*
Y1201837D03*
Y1195144D03*
X57399Y1225263D03*
Y1218570D03*
Y1211877D03*
X52541Y1221916D03*
Y1215223D03*
X57399Y1241995D03*
Y1235302D03*
X52541Y1238648D03*
Y1231955D03*
Y1248688D03*
X57399D03*
X52541Y1245341D03*
X57399Y1258727D03*
X52820Y1253862D03*
X60446Y1273364D03*
X49546D03*
X46746D03*
X57399Y1265420D03*
Y1262074D03*
X66099Y773491D03*
X73541Y766798D03*
X66099Y770144D03*
Y780184D03*
Y786877D03*
X73541Y780184D03*
Y773491D03*
X66099Y783530D03*
Y776837D03*
Y780184D03*
Y773491D03*
Y786877D03*
Y803609D03*
Y790223D03*
Y796916D03*
X73541Y803609D03*
Y796916D03*
Y790223D03*
X66099Y800263D03*
Y793570D03*
Y803609D03*
Y796916D03*
Y790223D03*
Y816995D03*
Y810302D03*
X73541Y816995D03*
Y810302D03*
X66099Y820341D03*
Y813648D03*
Y806955D03*
Y816995D03*
Y810302D03*
Y833727D03*
Y823688D03*
Y827034D03*
X73541Y833727D03*
Y827034D03*
X66099Y830381D03*
Y833727D03*
Y823688D03*
Y827034D03*
Y847113D03*
Y840420D03*
Y853806D03*
X73541Y847113D03*
Y840420D03*
X66099Y850459D03*
Y843766D03*
Y837074D03*
Y847113D03*
Y840420D03*
Y863845D03*
Y860499D03*
Y870538D03*
X73541Y863845D03*
Y853806D03*
X66099Y867192D03*
Y857152D03*
Y853806D03*
Y860499D03*
Y863845D03*
Y877231D03*
Y883924D03*
X73541D03*
Y877231D03*
Y870538D03*
X66099Y880577D03*
Y873885D03*
Y883924D03*
Y877231D03*
Y870538D03*
Y900656D03*
Y897310D03*
Y890617D03*
X73541Y900656D03*
Y890617D03*
X66099Y893963D03*
Y887270D03*
Y890617D03*
Y897310D03*
Y900656D03*
Y907349D03*
Y914042D03*
X73541D03*
Y907349D03*
X66099Y917389D03*
Y910696D03*
Y904003D03*
Y914042D03*
Y907349D03*
Y934121D03*
Y920735D03*
Y927428D03*
X73541D03*
Y920735D03*
X66099Y930774D03*
Y924081D03*
Y927428D03*
Y920735D03*
Y934121D03*
Y937467D03*
Y944160D03*
Y950853D03*
X73541Y944160D03*
Y937467D03*
X66099Y947507D03*
Y940814D03*
Y944160D03*
Y937467D03*
Y960892D03*
Y957546D03*
Y967585D03*
X73541Y960892D03*
Y950853D03*
X66099Y964239D03*
Y954200D03*
Y960892D03*
Y950853D03*
Y957546D03*
Y974278D03*
Y980971D03*
X73541D03*
Y974278D03*
Y967585D03*
X66099Y977625D03*
Y970932D03*
Y980971D03*
Y974278D03*
Y967585D03*
Y987664D03*
Y994357D03*
X73541Y987664D03*
X66099Y991011D03*
Y984318D03*
Y994357D03*
Y987664D03*
Y1021129D03*
Y1027822D03*
X73541D03*
Y1017782D03*
X66099Y1031168D03*
Y1024475D03*
Y1017782D03*
Y1027822D03*
Y1021129D03*
Y1041207D03*
Y1047900D03*
Y1034515D03*
X73541Y1047900D03*
Y1041207D03*
Y1034515D03*
X66099Y1044554D03*
Y1037861D03*
Y1047900D03*
Y1041207D03*
Y1034515D03*
Y1054593D03*
X73541Y1061286D03*
Y1054593D03*
X66099Y1057940D03*
Y1051247D03*
Y1061286D03*
Y1054593D03*
Y1074672D03*
Y1067979D03*
Y1081365D03*
X73541Y1074672D03*
Y1067979D03*
X66099Y1078018D03*
Y1071326D03*
Y1064633D03*
Y1074672D03*
Y1067979D03*
Y1091404D03*
Y1084711D03*
Y1098097D03*
X73541Y1091404D03*
Y1084711D03*
X66099Y1094751D03*
Y1088058D03*
Y1091404D03*
Y1081365D03*
Y1084711D03*
Y1104790D03*
Y1111483D03*
X73541D03*
Y1104790D03*
Y1098097D03*
X66099Y1108137D03*
Y1101444D03*
Y1098097D03*
Y1111483D03*
Y1104790D03*
Y1121522D03*
Y1128215D03*
Y1118176D03*
X73541Y1128215D03*
Y1121522D03*
X66099Y1124869D03*
Y1114829D03*
Y1128215D03*
Y1118176D03*
Y1121522D03*
Y1141601D03*
Y1134908D03*
X73541Y1141601D03*
Y1134908D03*
X66099Y1144948D03*
Y1138255D03*
Y1131562D03*
Y1141601D03*
Y1134908D03*
Y1148294D03*
Y1158333D03*
Y1154987D03*
X73541Y1158333D03*
Y1148294D03*
X66099Y1161680D03*
Y1151641D03*
Y1148294D03*
Y1154987D03*
Y1158333D03*
Y1171719D03*
Y1165026D03*
Y1178412D03*
X73541Y1171719D03*
Y1165026D03*
X66099Y1175066D03*
Y1168373D03*
Y1171719D03*
Y1165026D03*
Y1191798D03*
Y1185105D03*
Y1195144D03*
X73541Y1185105D03*
Y1178412D03*
X66099Y1188452D03*
Y1181759D03*
Y1185105D03*
Y1178412D03*
Y1191798D03*
Y1208530D03*
Y1201837D03*
X73541Y1208530D03*
Y1201837D03*
Y1195144D03*
X66099Y1205184D03*
Y1198491D03*
Y1208530D03*
Y1201837D03*
Y1195144D03*
Y1215223D03*
Y1221916D03*
Y1228609D03*
X73541Y1221916D03*
Y1215223D03*
X66099Y1225263D03*
Y1218570D03*
Y1211877D03*
Y1221916D03*
Y1215223D03*
Y1238648D03*
Y1231955D03*
Y1245341D03*
X73541Y1238648D03*
Y1231955D03*
X66099Y1241995D03*
Y1235302D03*
Y1238648D03*
Y1228609D03*
Y1231955D03*
X66189Y1257488D03*
X73541Y1245341D03*
X66099Y1248688D03*
Y1245341D03*
X73541Y1255381D03*
Y1258727D03*
Y1252034D03*
X76446Y1273364D03*
X63246D03*
X73541Y1265420D03*
Y1262074D03*
X82241Y770144D03*
X87099D03*
X82241Y766798D03*
Y770144D03*
X86999Y766798D03*
X82241Y783530D03*
Y776837D03*
Y786877D03*
X87099Y783530D03*
Y776837D03*
X82241Y780184D03*
Y773491D03*
Y776837D03*
Y786877D03*
Y783530D03*
Y800263D03*
Y793570D03*
X87099Y800263D03*
Y793570D03*
X82241Y803609D03*
Y796916D03*
Y790223D03*
Y800263D03*
Y793570D03*
Y820341D03*
Y813648D03*
Y806955D03*
X87099Y820341D03*
Y813648D03*
Y806955D03*
X82241Y816995D03*
Y810302D03*
Y813648D03*
Y806955D03*
Y820341D03*
Y830381D03*
Y823688D03*
Y837074D03*
X87099Y830381D03*
X82241Y833727D03*
Y827034D03*
Y830381D03*
Y823688D03*
Y843766D03*
Y850459D03*
X87099D03*
Y843766D03*
Y837074D03*
X82241Y847113D03*
Y840420D03*
Y850459D03*
Y843766D03*
Y837074D03*
Y860499D03*
Y857152D03*
Y867192D03*
X87099D03*
Y857152D03*
X82241Y863845D03*
Y853806D03*
Y867192D03*
Y860499D03*
Y857152D03*
Y880577D03*
Y873885D03*
Y887270D03*
X87099Y880577D03*
Y873885D03*
X82241Y883924D03*
Y877231D03*
Y870538D03*
Y873885D03*
Y880577D03*
Y897310D03*
Y893963D03*
Y904003D03*
X87099Y893963D03*
Y887270D03*
X82241Y900656D03*
Y890617D03*
Y887270D03*
Y897310D03*
Y893963D03*
Y917389D03*
Y910696D03*
X87099Y917389D03*
Y910696D03*
Y904003D03*
X82241Y914042D03*
Y907349D03*
Y917389D03*
Y910696D03*
Y904003D03*
Y924081D03*
Y930774D03*
Y934121D03*
X87099Y930774D03*
Y924081D03*
X82241Y927428D03*
Y920735D03*
Y924081D03*
Y934121D03*
Y930774D03*
Y947507D03*
Y940814D03*
X87099Y947507D03*
Y940814D03*
X82241Y944160D03*
Y937467D03*
Y947507D03*
Y940814D03*
Y964239D03*
X95799Y960892D03*
Y957546D03*
Y967585D03*
X87099Y964239D03*
Y954200D03*
X82241Y960892D03*
Y950853D03*
Y964239D03*
Y957546D03*
Y954200D03*
Y970932D03*
Y977625D03*
Y984318D03*
X87099Y977625D03*
Y970932D03*
X82241Y980971D03*
Y974278D03*
Y967585D03*
Y977625D03*
Y970932D03*
Y991011D03*
X87099D03*
Y984318D03*
X82241Y987664D03*
Y991011D03*
Y984318D03*
Y994357D03*
Y1021129D03*
Y1024475D03*
Y1031168D03*
X87099D03*
Y1024475D03*
Y1017782D03*
X82241Y1027822D03*
Y1017782D03*
Y1021129D03*
Y1024475D03*
Y1031168D03*
Y1044554D03*
Y1037861D03*
X87099Y1044554D03*
Y1037861D03*
X82241Y1047900D03*
Y1041207D03*
Y1034515D03*
Y1044554D03*
Y1037861D03*
Y1051247D03*
X95799Y1054593D03*
X82241Y1064633D03*
X87099Y1057940D03*
Y1051247D03*
X82241Y1061286D03*
Y1054593D03*
Y1051247D03*
Y1078018D03*
Y1071326D03*
Y1081365D03*
X87099Y1078018D03*
Y1071326D03*
Y1064633D03*
X82241Y1074672D03*
Y1067979D03*
Y1071326D03*
Y1064633D03*
Y1078018D03*
Y1094751D03*
Y1088058D03*
X87099Y1094751D03*
Y1088058D03*
X82241Y1091404D03*
Y1084711D03*
Y1094751D03*
Y1088058D03*
Y1081365D03*
Y1108137D03*
Y1101444D03*
Y1114829D03*
X87099Y1108137D03*
Y1101444D03*
X82241Y1111483D03*
Y1104790D03*
Y1098097D03*
Y1108137D03*
Y1101444D03*
Y1124869D03*
Y1118176D03*
Y1131562D03*
X87099Y1124869D03*
Y1114829D03*
X82241Y1128215D03*
Y1121522D03*
Y1124869D03*
Y1118176D03*
Y1114829D03*
Y1138255D03*
Y1144948D03*
X87099D03*
Y1138255D03*
Y1131562D03*
X82241Y1141601D03*
Y1134908D03*
Y1144948D03*
Y1138255D03*
Y1131562D03*
Y1154987D03*
Y1161680D03*
Y1151641D03*
X87099Y1161680D03*
Y1151641D03*
X82241Y1158333D03*
Y1148294D03*
Y1161680D03*
Y1154987D03*
Y1151641D03*
Y1175066D03*
Y1168373D03*
X87099Y1175066D03*
Y1168373D03*
X82241Y1171719D03*
Y1165026D03*
Y1175066D03*
Y1168373D03*
Y1188452D03*
Y1191798D03*
Y1181759D03*
X87099Y1188452D03*
Y1181759D03*
X82241Y1185105D03*
Y1178412D03*
Y1181759D03*
Y1191798D03*
Y1188452D03*
Y1205184D03*
Y1198491D03*
Y1211877D03*
X87099Y1205184D03*
Y1198491D03*
X82241Y1208530D03*
Y1201837D03*
Y1195144D03*
Y1205184D03*
Y1198491D03*
Y1225263D03*
Y1218570D03*
Y1228609D03*
X87099Y1225263D03*
Y1218570D03*
Y1211877D03*
X82241Y1221916D03*
Y1215223D03*
Y1218570D03*
Y1211877D03*
Y1225263D03*
Y1235302D03*
Y1241995D03*
X87099D03*
Y1235302D03*
X82241Y1238648D03*
Y1231955D03*
Y1241995D03*
Y1235302D03*
Y1228609D03*
X87099Y1248688D03*
X82241Y1245341D03*
X87099Y1258727D03*
X82241Y1248688D03*
X84334Y1254263D03*
X92946Y1273364D03*
X90146D03*
X79246D03*
X87099Y1265420D03*
Y1262074D03*
X103241Y766798D03*
X95799Y770144D03*
X103241Y780184D03*
Y773491D03*
X95799Y783530D03*
Y776837D03*
X103241Y803609D03*
Y796916D03*
Y790223D03*
X95799Y800263D03*
Y793570D03*
X103241Y816995D03*
Y810302D03*
X95799Y820341D03*
Y813648D03*
Y806955D03*
X103241Y833727D03*
Y827034D03*
X95799Y830381D03*
X103241Y847113D03*
Y840420D03*
X95799Y850459D03*
Y843766D03*
Y837074D03*
X103241Y863845D03*
Y853806D03*
X95799Y867192D03*
Y857152D03*
X103241Y883924D03*
Y877231D03*
Y870538D03*
X95799Y880577D03*
Y873885D03*
X103241Y900656D03*
Y890617D03*
X95799Y893963D03*
Y887270D03*
X103241Y914042D03*
Y907349D03*
X95799Y917389D03*
Y910696D03*
Y904003D03*
X103241Y927428D03*
Y920735D03*
X95799Y930774D03*
Y924081D03*
X103241Y944160D03*
Y937467D03*
X95799Y947507D03*
Y940814D03*
X111941Y964239D03*
X103241Y960892D03*
Y950853D03*
X95799Y964239D03*
Y954200D03*
Y960892D03*
Y957546D03*
X103241Y980971D03*
Y974278D03*
Y967585D03*
X95799Y977625D03*
Y970932D03*
Y967585D03*
X103241Y987664D03*
X95799Y991011D03*
Y984318D03*
X103241Y994357D03*
X111941Y1021129D03*
Y1024475D03*
X103241Y1027822D03*
Y1017782D03*
X95799Y1031168D03*
Y1024475D03*
Y1017782D03*
X103241Y1047900D03*
Y1041207D03*
Y1034515D03*
X95799Y1044554D03*
Y1037861D03*
X111941Y1051247D03*
X103241Y1061286D03*
Y1054593D03*
X95799Y1057940D03*
Y1051247D03*
Y1054593D03*
X103241Y1074672D03*
Y1067979D03*
X95799Y1078018D03*
Y1071326D03*
Y1064633D03*
X103241Y1091404D03*
Y1084711D03*
X95799Y1094751D03*
Y1088058D03*
X103241Y1111483D03*
Y1104790D03*
Y1098097D03*
X95799Y1108137D03*
Y1101444D03*
X103241Y1128215D03*
Y1121522D03*
X95799Y1124869D03*
Y1114829D03*
X103241Y1141601D03*
Y1134908D03*
X95799Y1144948D03*
Y1138255D03*
Y1131562D03*
X103241Y1158333D03*
Y1148294D03*
X95799Y1161680D03*
Y1151641D03*
X103241Y1171719D03*
Y1165026D03*
X95799Y1175066D03*
Y1168373D03*
X103241Y1185105D03*
Y1178412D03*
X95799Y1188452D03*
Y1181759D03*
X103241Y1208530D03*
Y1201837D03*
Y1195144D03*
X95799Y1205184D03*
Y1198491D03*
X103241Y1221916D03*
Y1215223D03*
X95799Y1225263D03*
Y1218570D03*
Y1211877D03*
X103241Y1238648D03*
Y1231955D03*
X95799Y1241995D03*
Y1235302D03*
X95849Y1257262D03*
X103241Y1245341D03*
X95799Y1248688D03*
X103241Y1255381D03*
Y1258727D03*
Y1252034D03*
X108946Y1273364D03*
X106146D03*
X103241Y1265420D03*
Y1262074D03*
X125499Y773491D03*
Y770144D03*
X116799D03*
X111941Y766798D03*
X116567Y766775D03*
X125499Y786877D03*
Y780184D03*
Y783530D03*
X116799D03*
X125499Y776837D03*
X116799D03*
X111941Y780184D03*
Y773491D03*
X125499Y780184D03*
Y773491D03*
Y786877D03*
Y790223D03*
Y796916D03*
Y803609D03*
Y800263D03*
X116799D03*
X125499Y793570D03*
X116799D03*
X111941Y803609D03*
Y796916D03*
Y790223D03*
X125499Y803609D03*
Y796916D03*
Y790223D03*
Y816995D03*
Y810302D03*
Y820341D03*
X116799D03*
X125499Y813648D03*
X116799D03*
X125499Y806955D03*
X116799D03*
X111941Y816995D03*
Y810302D03*
X125499Y816995D03*
Y810302D03*
Y833727D03*
Y823688D03*
Y827034D03*
Y830381D03*
X116799D03*
X111941Y833727D03*
Y827034D03*
X125499Y833727D03*
Y823688D03*
Y827034D03*
Y840420D03*
Y847113D03*
Y853806D03*
Y850459D03*
X116799D03*
X125499Y843766D03*
X116799D03*
X125499Y837074D03*
X116799D03*
X111941Y847113D03*
Y840420D03*
X125499Y847113D03*
Y840420D03*
Y860499D03*
Y863845D03*
Y870538D03*
Y867192D03*
X116799D03*
X125499Y857152D03*
X116799D03*
X111941Y863845D03*
Y853806D03*
X125499D03*
Y860499D03*
Y863845D03*
Y883924D03*
Y877231D03*
Y880577D03*
X116799D03*
X125499Y873885D03*
X116799D03*
X111941Y883924D03*
Y877231D03*
Y870538D03*
X125499Y883924D03*
Y877231D03*
Y870538D03*
Y897310D03*
Y900656D03*
Y890617D03*
Y893963D03*
X116799D03*
X125499Y887270D03*
X116799D03*
X111941Y900656D03*
Y890617D03*
X125499D03*
Y897310D03*
Y900656D03*
Y914042D03*
Y907349D03*
Y917389D03*
X116799D03*
X125499Y910696D03*
X116799D03*
X125499Y904003D03*
X116799D03*
X111941Y914042D03*
Y907349D03*
X125499Y914042D03*
Y907349D03*
Y927428D03*
Y920735D03*
Y934121D03*
Y930774D03*
X116799D03*
X125499Y924081D03*
X116799D03*
X111941Y927428D03*
Y920735D03*
X125499Y927428D03*
Y920735D03*
Y934121D03*
Y944160D03*
Y937467D03*
Y950853D03*
Y947507D03*
X116799D03*
X125499Y940814D03*
X116799D03*
X111941Y944160D03*
Y937467D03*
X125499Y944160D03*
Y937467D03*
Y960892D03*
Y957546D03*
Y967585D03*
Y964239D03*
X116799D03*
X125499Y954200D03*
X116799D03*
X111941Y960892D03*
Y950853D03*
X125499Y960892D03*
Y950853D03*
X111941Y964239D03*
X125499Y957546D03*
X111941D03*
Y954200D03*
X125499Y980971D03*
Y974278D03*
Y977625D03*
X116799D03*
X125499Y970932D03*
X116799D03*
X111941Y980971D03*
Y974278D03*
Y967585D03*
X125499Y980971D03*
Y974278D03*
Y967585D03*
Y994357D03*
Y987664D03*
Y991011D03*
X116799D03*
X125499Y984318D03*
X116799D03*
X111941Y987664D03*
X125499Y994357D03*
Y987664D03*
Y1027822D03*
Y1021129D03*
Y1031168D03*
X116799D03*
X125499Y1024475D03*
X116799D03*
X125499Y1017782D03*
X116799D03*
X111941Y1027822D03*
Y1017782D03*
Y1021129D03*
Y1024475D03*
X125499Y1027822D03*
Y1021129D03*
Y1047900D03*
Y1041207D03*
Y1034515D03*
Y1044554D03*
X116799D03*
X125499Y1037861D03*
X116799D03*
X111941Y1047900D03*
Y1041207D03*
Y1034515D03*
X125499Y1047900D03*
Y1041207D03*
Y1034515D03*
Y1054593D03*
Y1057940D03*
X116799D03*
X125499Y1051247D03*
X116799D03*
X111941Y1061286D03*
Y1054593D03*
X125499Y1061286D03*
X111941Y1051247D03*
X125499Y1054593D03*
Y1074672D03*
Y1067979D03*
Y1081365D03*
Y1078018D03*
X116799D03*
X125499Y1071326D03*
X116799D03*
X125499Y1064633D03*
X116799D03*
X111941Y1074672D03*
Y1067979D03*
X125499Y1074672D03*
Y1067979D03*
Y1091404D03*
Y1084711D03*
Y1098097D03*
Y1094751D03*
X116799D03*
X125499Y1088058D03*
X116799D03*
X111941Y1091404D03*
Y1084711D03*
X125499Y1091404D03*
Y1081365D03*
Y1084711D03*
Y1111483D03*
Y1104790D03*
Y1108137D03*
X116799D03*
X125499Y1101444D03*
X116799D03*
X111941Y1111483D03*
Y1104790D03*
Y1098097D03*
X125499D03*
Y1111483D03*
Y1104790D03*
Y1128215D03*
Y1121522D03*
Y1118176D03*
Y1124869D03*
X116799D03*
X125499Y1114829D03*
X116799D03*
X111941Y1128215D03*
Y1121522D03*
X125499Y1128215D03*
Y1118176D03*
Y1121522D03*
Y1141601D03*
Y1134908D03*
Y1144948D03*
X116799D03*
X125499Y1138255D03*
X116799D03*
X125499Y1131562D03*
X116799D03*
X111941Y1141601D03*
Y1134908D03*
X125499Y1141601D03*
Y1134908D03*
Y1154987D03*
Y1158333D03*
Y1148294D03*
Y1161680D03*
X116799D03*
X125499Y1151641D03*
X116799D03*
X111941Y1158333D03*
Y1148294D03*
X125499D03*
Y1154987D03*
Y1158333D03*
Y1171719D03*
Y1165026D03*
Y1178412D03*
Y1175066D03*
X116799D03*
X125499Y1168373D03*
X116799D03*
X111941Y1171719D03*
Y1165026D03*
X125499Y1171719D03*
Y1165026D03*
Y1191798D03*
Y1185105D03*
Y1195144D03*
Y1188452D03*
X116799D03*
X125499Y1181759D03*
X116799D03*
X111941Y1185105D03*
Y1178412D03*
X125499Y1185105D03*
Y1178412D03*
Y1191798D03*
Y1208530D03*
Y1201837D03*
Y1205184D03*
X116799D03*
X125499Y1198491D03*
X116799D03*
X111941Y1208530D03*
Y1201837D03*
Y1195144D03*
X125499Y1208530D03*
Y1201837D03*
Y1195144D03*
Y1221916D03*
Y1215223D03*
Y1228609D03*
Y1225263D03*
X116799D03*
X125499Y1218570D03*
X116799D03*
X125499Y1211877D03*
X116799D03*
X111941Y1221916D03*
Y1215223D03*
X125499Y1221916D03*
Y1215223D03*
Y1238648D03*
Y1231955D03*
Y1245341D03*
Y1241995D03*
X116799D03*
X125499Y1235302D03*
X116799D03*
X111941Y1238648D03*
Y1231955D03*
X125499Y1238648D03*
Y1228609D03*
Y1231955D03*
X125412Y1257102D03*
X125499Y1248688D03*
X116799D03*
X111941Y1245341D03*
X125499D03*
X116799Y1258727D03*
X111941Y1248688D03*
X114191Y1254604D03*
X119846Y1273364D03*
X122646D03*
X116799Y1265420D03*
Y1262074D03*
X141641Y770144D03*
Y766798D03*
X132941D03*
X141641Y770144D03*
Y786877D03*
Y776837D03*
Y783530D03*
Y773491D03*
X132941D03*
X141641Y780184D03*
X132941D03*
X141641Y776837D03*
Y786877D03*
Y783530D03*
Y800263D03*
Y793570D03*
Y803609D03*
X132941D03*
X141641Y790223D03*
X132941D03*
X141641Y796916D03*
X132941D03*
X141641Y800263D03*
Y793570D03*
Y806955D03*
Y813648D03*
Y820341D03*
Y816995D03*
X132941D03*
X141641Y810302D03*
X132941D03*
X141641Y813648D03*
Y806955D03*
Y820341D03*
Y830381D03*
Y823688D03*
Y837074D03*
Y833727D03*
X132941D03*
X141641Y827034D03*
X132941D03*
X141641Y830381D03*
Y823688D03*
Y843766D03*
Y850459D03*
Y840420D03*
X132941D03*
X141641Y847113D03*
X132941D03*
X141641Y850459D03*
Y843766D03*
Y837074D03*
Y860499D03*
Y857152D03*
Y867192D03*
X132941Y863845D03*
X141641D03*
Y853806D03*
X132941D03*
X141641Y867192D03*
Y860499D03*
Y857152D03*
Y873885D03*
Y880577D03*
Y887270D03*
X132941Y883924D03*
X141641D03*
X132941Y870538D03*
X141641D03*
X132941Y877231D03*
X141641D03*
Y873885D03*
Y880577D03*
Y897310D03*
Y893963D03*
Y904003D03*
X132941Y900656D03*
X141641D03*
X132941Y890617D03*
X141641D03*
Y887270D03*
Y897310D03*
Y893963D03*
Y910696D03*
Y917389D03*
X132941Y907349D03*
X141641D03*
X132941Y914042D03*
X141641D03*
Y917389D03*
Y910696D03*
Y904003D03*
Y930774D03*
Y934121D03*
Y924081D03*
X132941Y920735D03*
X141641D03*
X132941Y927428D03*
X141641D03*
Y924081D03*
Y934121D03*
Y930774D03*
Y947507D03*
Y940814D03*
X132941Y937467D03*
X141641D03*
X132941Y944160D03*
X141641D03*
Y947507D03*
Y940814D03*
Y964239D03*
X132941Y960892D03*
X141641D03*
X132941Y950853D03*
X141641D03*
Y964239D03*
Y957546D03*
Y954200D03*
Y970932D03*
Y977625D03*
Y984318D03*
X132941Y980971D03*
X141641D03*
X132941Y974278D03*
X141641D03*
X132941Y967585D03*
X141641D03*
Y977625D03*
Y970932D03*
Y991011D03*
X132941Y987664D03*
X141641D03*
Y991011D03*
Y984318D03*
Y994357D03*
Y1031168D03*
Y1024475D03*
Y1021129D03*
X132941Y1027822D03*
X141641D03*
X132941Y1017782D03*
X141641D03*
Y1021129D03*
Y1024475D03*
Y1031168D03*
Y1037861D03*
Y1044554D03*
X132941Y1047900D03*
X141641D03*
X132941Y1041207D03*
X141641D03*
X132941Y1034515D03*
X141641D03*
Y1044554D03*
Y1037861D03*
Y1051247D03*
Y1064633D03*
Y1061286D03*
X132941D03*
X141641Y1054593D03*
X132941D03*
X141641Y1051247D03*
Y1057940D03*
Y1078018D03*
Y1071326D03*
Y1081365D03*
Y1074672D03*
X132941D03*
X141641Y1067979D03*
X132941D03*
X141641Y1071326D03*
Y1064633D03*
Y1078018D03*
Y1088058D03*
Y1094751D03*
Y1091404D03*
X132941D03*
X141641Y1084711D03*
X132941D03*
X141641Y1094751D03*
Y1088058D03*
Y1081365D03*
Y1101444D03*
Y1108137D03*
Y1114829D03*
Y1111483D03*
X132941D03*
X141641Y1104790D03*
X132941D03*
X141641Y1098097D03*
X132941D03*
X141641Y1108137D03*
Y1101444D03*
Y1124869D03*
Y1118176D03*
Y1131562D03*
Y1128215D03*
X132941D03*
X141641Y1121522D03*
X132941D03*
X141641Y1124869D03*
Y1118176D03*
Y1114829D03*
Y1138255D03*
Y1144948D03*
Y1141601D03*
X132941D03*
X141641Y1134908D03*
X132941D03*
X141641Y1144948D03*
Y1138255D03*
Y1131562D03*
Y1161680D03*
Y1151641D03*
Y1154987D03*
Y1158333D03*
X132941D03*
X141641Y1148294D03*
X132941D03*
X141641Y1161680D03*
Y1154987D03*
Y1151641D03*
Y1175066D03*
Y1168373D03*
Y1171719D03*
X132941D03*
X141641Y1165026D03*
X132941D03*
X141641Y1175066D03*
Y1168373D03*
Y1191798D03*
Y1188452D03*
Y1181759D03*
Y1185105D03*
X132941D03*
X141641Y1178412D03*
X132941D03*
X141641Y1181759D03*
Y1191798D03*
Y1188452D03*
Y1198491D03*
Y1205184D03*
Y1211877D03*
Y1208530D03*
X132941D03*
X141641Y1201837D03*
X132941D03*
X141641Y1195144D03*
X132941D03*
X141641Y1205184D03*
Y1198491D03*
Y1225263D03*
Y1218570D03*
Y1228609D03*
X132941Y1221916D03*
X141641D03*
X132941Y1215223D03*
X141641D03*
Y1218570D03*
Y1211877D03*
Y1225263D03*
Y1235302D03*
Y1241995D03*
X132941Y1238648D03*
X141641D03*
X132941Y1231955D03*
X141641D03*
X129933Y1238461D03*
X141641Y1241995D03*
Y1235302D03*
Y1228609D03*
X132941Y1245341D03*
X141641D03*
X132941Y1255381D03*
Y1258727D03*
Y1252034D03*
X141641Y1248688D03*
X143675Y1255567D03*
X135846Y1273364D03*
X138646D03*
X132941Y1265420D03*
Y1262074D03*
X146499Y770144D03*
X155199D03*
X146367Y766775D03*
X146499Y783530D03*
X155199D03*
X146499Y776837D03*
X155199D03*
X146499Y800263D03*
X155199D03*
X146499Y793570D03*
X155199D03*
X146499Y820341D03*
X155199D03*
X146499Y813648D03*
X155199D03*
X146499Y806955D03*
X155199D03*
X146499Y830381D03*
X155199D03*
X146499Y850459D03*
X155199D03*
X146499Y843766D03*
X155199D03*
X146499Y837074D03*
X155199D03*
Y867192D03*
X146499D03*
Y857152D03*
X155199D03*
Y880577D03*
X146499D03*
X155199Y873885D03*
X146499D03*
X155199Y893963D03*
X146499D03*
X155199Y887270D03*
X146499D03*
X155199Y917389D03*
X146499D03*
X155199Y910696D03*
X146499D03*
X155199Y904003D03*
X146499D03*
X155199Y930774D03*
X146499D03*
X155199Y924081D03*
X146499D03*
X155199Y947507D03*
X146499D03*
X155199Y940814D03*
X146499D03*
X155199Y960892D03*
Y957546D03*
Y967585D03*
Y964239D03*
X146499D03*
X155199Y954200D03*
X146499D03*
X155199Y960892D03*
Y957546D03*
Y977625D03*
X146499D03*
X155199Y970932D03*
X146499D03*
X155199Y967585D03*
Y991011D03*
X146499D03*
X155199Y984318D03*
X146499D03*
X155199Y1031168D03*
X146499D03*
X155199Y1024475D03*
X146499D03*
X155199Y1017782D03*
X146499D03*
X155199Y1044554D03*
X146499D03*
X155199Y1037861D03*
X146499D03*
X155199Y1054593D03*
Y1057940D03*
X146499D03*
X155199Y1051247D03*
X146499D03*
X155199Y1054593D03*
Y1078018D03*
X146499D03*
X155199Y1071326D03*
X146499D03*
X155199Y1064633D03*
X146499D03*
X155199Y1094751D03*
X146499D03*
X155199Y1088058D03*
X146499D03*
X155199Y1108137D03*
X146499D03*
X155199Y1101444D03*
X146499D03*
X155199Y1124869D03*
X146499D03*
X155199Y1114829D03*
X146499D03*
X155199Y1144948D03*
X146499D03*
X155199Y1138255D03*
X146499D03*
X155199Y1131562D03*
X146499D03*
X155199Y1161680D03*
X146499D03*
X155199Y1151641D03*
X146499D03*
X155199Y1175066D03*
X146499D03*
X155199Y1168373D03*
X146499D03*
X155199Y1188452D03*
X146499D03*
X155199Y1181759D03*
X146499D03*
X155199Y1205184D03*
X146499D03*
X155199Y1198491D03*
X146499D03*
X155199Y1225263D03*
X146499D03*
X155199Y1218570D03*
X146499D03*
X155199Y1211877D03*
X146499D03*
X155199Y1241995D03*
X146499D03*
X155199Y1235302D03*
X146499D03*
X155135Y1257134D03*
X155199Y1248688D03*
X146499D03*
X160130Y1251847D03*
X146499Y1258727D03*
X149546Y1273364D03*
X152346D03*
X146499Y1265420D03*
Y1262074D03*
X176199Y770144D03*
X162641Y766798D03*
X171341D03*
X176099D03*
X176199Y783530D03*
Y776837D03*
X162641Y780184D03*
X171341D03*
Y773491D03*
X162641D03*
X176199Y800263D03*
X162641Y803609D03*
X171341D03*
X176199Y793570D03*
X162641Y796916D03*
X171341D03*
X162641Y790223D03*
X171341D03*
X176199Y820341D03*
X162641Y816995D03*
X171341D03*
X176199Y813648D03*
Y806955D03*
X162641Y810302D03*
X171341D03*
X162641Y833727D03*
X171341D03*
X176199Y830381D03*
X162641Y827034D03*
X171341D03*
X176199Y850459D03*
Y843766D03*
Y837074D03*
X162641Y847113D03*
X171341D03*
X162641Y840420D03*
X171341D03*
X176199Y867192D03*
X171341Y863845D03*
X162641D03*
X176199Y857152D03*
X162641Y853806D03*
X171341D03*
Y883924D03*
X162641D03*
X176199Y880577D03*
Y873885D03*
X171341Y877231D03*
X162641D03*
X171341Y870538D03*
X162641D03*
X171341Y900656D03*
X162641D03*
X176199Y893963D03*
Y887270D03*
X171341Y890617D03*
X162641D03*
X176199Y917389D03*
Y910696D03*
Y904003D03*
X171341Y914042D03*
X162641D03*
X171341Y907349D03*
X162641D03*
X176199Y930774D03*
Y924081D03*
X171341Y927428D03*
X162641D03*
X171341Y920735D03*
X162641D03*
X176199Y947507D03*
Y940814D03*
X171341Y944160D03*
X162641D03*
X171341Y937467D03*
X162641D03*
X171341Y964239D03*
X176199D03*
Y954200D03*
X171341Y960892D03*
X162641D03*
X171341Y950853D03*
X162641D03*
X171341Y964239D03*
Y957546D03*
Y954200D03*
Y980971D03*
X162641D03*
X176199Y977625D03*
Y970932D03*
X171341Y974278D03*
X162641D03*
X171341Y967585D03*
X162641D03*
X176199Y991011D03*
Y984318D03*
X171341Y987664D03*
X162641D03*
Y994357D03*
X171341Y1024475D03*
Y1021129D03*
X176199Y1031168D03*
Y1024475D03*
Y1017782D03*
X171341Y1027822D03*
X162641D03*
X171341Y1017782D03*
X162641D03*
X171341Y1021129D03*
Y1024475D03*
Y1047900D03*
X162641D03*
X176199Y1044554D03*
Y1037861D03*
X171341Y1041207D03*
X162641D03*
X171341Y1034515D03*
X162641D03*
X171341Y1051247D03*
X176199Y1057940D03*
Y1051247D03*
X171341Y1061286D03*
X162641D03*
X171341Y1054593D03*
X162641D03*
X171341Y1051247D03*
X176199Y1078018D03*
Y1071326D03*
Y1064633D03*
X171341Y1074672D03*
X162641D03*
X171341Y1067979D03*
X162641D03*
X176199Y1094751D03*
Y1088058D03*
X171341Y1091404D03*
X162641D03*
X171341Y1084711D03*
X162641D03*
X171341Y1111483D03*
X162641D03*
X176199Y1108137D03*
Y1101444D03*
X171341Y1104790D03*
X162641D03*
X171341Y1098097D03*
X162641D03*
X171341Y1128215D03*
X162641D03*
X176199Y1124869D03*
Y1114829D03*
X171341Y1121522D03*
X162641D03*
X176199Y1144948D03*
Y1138255D03*
Y1131562D03*
X171341Y1141601D03*
X162641D03*
X171341Y1134908D03*
X162641D03*
X176199Y1161680D03*
Y1151641D03*
X171341Y1158333D03*
X162641D03*
X171341Y1148294D03*
X162641D03*
X176199Y1175066D03*
Y1168373D03*
X171341Y1171719D03*
X162641D03*
X171341Y1165026D03*
X162641D03*
X176199Y1188452D03*
Y1181759D03*
X171341Y1185105D03*
X162641D03*
X171341Y1178412D03*
X162641D03*
X176199Y1205184D03*
Y1198491D03*
X171341Y1208530D03*
X162641D03*
X171341Y1201837D03*
X162641D03*
X171341Y1195144D03*
X162641D03*
X176199Y1225263D03*
Y1218570D03*
Y1211877D03*
X162641Y1221916D03*
X171341D03*
Y1215223D03*
X162641D03*
X176199Y1241995D03*
Y1235302D03*
X171341Y1238648D03*
X162641D03*
X171341Y1231955D03*
X162641D03*
X176199Y1248688D03*
X171341Y1245341D03*
X162641D03*
X176199Y1258727D03*
X162641Y1255381D03*
Y1258727D03*
Y1252034D03*
X171341Y1248688D03*
X171947Y1255837D03*
X165546Y1273364D03*
X168346D03*
X176199Y1265420D03*
X162641D03*
Y1262074D03*
X176199D03*
X184899Y773491D03*
X192341Y766798D03*
X184899Y770144D03*
Y780184D03*
Y786877D03*
X192341Y780184D03*
Y773491D03*
X184899Y783530D03*
Y776837D03*
Y780184D03*
Y773491D03*
Y786877D03*
Y790223D03*
Y796916D03*
Y803609D03*
X192341D03*
Y796916D03*
Y790223D03*
X184899Y800263D03*
Y793570D03*
Y803609D03*
Y796916D03*
Y790223D03*
Y810302D03*
Y816995D03*
X192341D03*
Y810302D03*
X184899Y820341D03*
Y813648D03*
Y806955D03*
Y816995D03*
Y810302D03*
Y833727D03*
Y827034D03*
Y823688D03*
X192341Y833727D03*
X191491Y827034D03*
X184899Y830381D03*
Y833727D03*
Y823688D03*
Y827034D03*
Y847113D03*
Y840420D03*
Y853806D03*
X192341Y847113D03*
Y840420D03*
X184899Y850459D03*
Y843766D03*
Y837074D03*
Y847113D03*
Y840420D03*
Y860499D03*
Y863845D03*
Y870538D03*
X191491Y863845D03*
X184899Y867192D03*
X192341Y853806D03*
X184899Y857152D03*
Y853806D03*
Y860499D03*
Y863845D03*
Y877231D03*
Y883924D03*
X192341D03*
Y877231D03*
Y870538D03*
X184899Y880577D03*
Y873885D03*
Y883924D03*
Y877231D03*
Y870538D03*
Y900656D03*
Y890617D03*
Y897310D03*
X192341Y900656D03*
Y890617D03*
X184899Y893963D03*
Y887270D03*
Y890617D03*
Y897310D03*
Y900656D03*
Y907349D03*
Y914042D03*
X192341D03*
Y907349D03*
X184899Y917389D03*
Y910696D03*
Y904003D03*
Y914042D03*
Y907349D03*
Y934121D03*
Y927428D03*
Y920735D03*
X191491Y927428D03*
X192341Y920735D03*
X184899Y930774D03*
Y924081D03*
Y927428D03*
Y920735D03*
Y934121D03*
Y944160D03*
Y937467D03*
Y950853D03*
X192341Y937467D03*
Y944160D03*
X184899Y947507D03*
Y940814D03*
Y944160D03*
Y937467D03*
Y960892D03*
Y957546D03*
Y967585D03*
X192341Y960892D03*
Y950853D03*
X184899Y964239D03*
Y954200D03*
Y960892D03*
Y950853D03*
Y957546D03*
Y980971D03*
Y974278D03*
X192341D03*
Y980971D03*
Y967585D03*
X184899Y977625D03*
Y970932D03*
Y980971D03*
Y974278D03*
Y967585D03*
Y994357D03*
Y987664D03*
X192341D03*
X184899Y991011D03*
Y984318D03*
Y994357D03*
Y987664D03*
Y1027822D03*
Y1021129D03*
X192341Y1027822D03*
Y1017782D03*
X184899Y1031168D03*
Y1024475D03*
Y1017782D03*
Y1027822D03*
Y1021129D03*
Y1034515D03*
Y1047900D03*
Y1041207D03*
X192341Y1047900D03*
Y1041207D03*
Y1034515D03*
X184899Y1044554D03*
Y1037861D03*
Y1047900D03*
Y1041207D03*
Y1034515D03*
Y1054593D03*
X192341D03*
Y1061286D03*
X184899Y1057940D03*
Y1051247D03*
Y1061286D03*
Y1054593D03*
Y1074672D03*
Y1067979D03*
Y1081365D03*
X192341Y1074672D03*
Y1067979D03*
X184899Y1078018D03*
Y1071326D03*
Y1064633D03*
Y1074672D03*
Y1067979D03*
Y1084711D03*
Y1091404D03*
Y1098097D03*
X192341Y1091404D03*
X191491Y1084711D03*
X184899Y1094751D03*
Y1088058D03*
Y1091404D03*
Y1081365D03*
Y1084711D03*
Y1104790D03*
Y1111483D03*
X192341D03*
Y1104790D03*
Y1098097D03*
X184899Y1108137D03*
Y1101444D03*
Y1098097D03*
Y1111483D03*
Y1104790D03*
Y1121522D03*
Y1128215D03*
Y1118176D03*
X192341Y1128215D03*
Y1121522D03*
X184899Y1124869D03*
Y1114829D03*
Y1128215D03*
Y1118176D03*
Y1121522D03*
Y1134908D03*
Y1141601D03*
X192341D03*
Y1134908D03*
X184899Y1144948D03*
Y1138255D03*
Y1131562D03*
Y1141601D03*
Y1134908D03*
Y1158333D03*
Y1148294D03*
Y1154987D03*
X191491Y1158333D03*
X192341Y1148294D03*
X184899Y1161680D03*
Y1151641D03*
Y1148294D03*
Y1154987D03*
Y1158333D03*
Y1165026D03*
Y1171719D03*
Y1178412D03*
X192341Y1171719D03*
Y1165026D03*
X184899Y1175066D03*
Y1168373D03*
Y1171719D03*
Y1165026D03*
Y1191798D03*
Y1185105D03*
Y1195144D03*
X192341Y1185105D03*
Y1178412D03*
X184899Y1188452D03*
Y1181759D03*
Y1185105D03*
Y1178412D03*
Y1191798D03*
Y1201837D03*
Y1208530D03*
X192341D03*
Y1201837D03*
Y1195144D03*
X184899Y1205184D03*
Y1198491D03*
Y1208530D03*
Y1201837D03*
Y1195144D03*
Y1221916D03*
Y1215223D03*
Y1228609D03*
X192341Y1221916D03*
Y1215223D03*
X184899Y1225263D03*
Y1218570D03*
Y1211877D03*
Y1221916D03*
Y1215223D03*
Y1238648D03*
Y1231955D03*
Y1245341D03*
X192341Y1238648D03*
X191491Y1231955D03*
X184899Y1241995D03*
Y1235302D03*
Y1238648D03*
Y1228609D03*
Y1231955D03*
X184923Y1258871D03*
X192341Y1245341D03*
X184899Y1248688D03*
Y1245341D03*
X192341Y1255381D03*
Y1258727D03*
Y1252034D03*
X192594Y1271262D03*
X192605Y1268774D03*
X182046Y1273364D03*
X179246D03*
X192341Y1265420D03*
Y1262074D03*
X186697Y1578182D03*
Y1590094D03*
X191997Y1602380D03*
Y1614292D03*
X201041Y770144D03*
X205899D03*
X201041Y766798D03*
Y770144D03*
X205799Y766798D03*
X201041Y786877D03*
Y776837D03*
Y783530D03*
X205899D03*
Y776837D03*
X201041Y780184D03*
Y773491D03*
Y776837D03*
Y786877D03*
Y783530D03*
Y800263D03*
Y793570D03*
X205899Y800263D03*
Y793570D03*
X201041Y803609D03*
Y796916D03*
Y790223D03*
Y800263D03*
Y793570D03*
Y813648D03*
Y820341D03*
Y806955D03*
X205899Y813648D03*
Y806955D03*
X205049Y820341D03*
X201041Y816995D03*
Y810302D03*
Y813648D03*
Y806955D03*
Y820341D03*
Y823688D03*
Y830381D03*
Y837074D03*
X205049Y830381D03*
X201041Y833727D03*
Y827034D03*
Y830381D03*
Y823688D03*
Y850459D03*
Y843766D03*
X205899Y850459D03*
Y837074D03*
Y843766D03*
X201041Y847113D03*
Y840420D03*
Y850459D03*
Y843766D03*
Y837074D03*
Y857152D03*
Y867192D03*
Y860499D03*
X205049Y867192D03*
X201041Y863845D03*
X205049Y857152D03*
X201041Y853806D03*
Y867192D03*
Y860499D03*
Y857152D03*
Y873885D03*
Y880577D03*
Y887270D03*
X205899Y873885D03*
Y880577D03*
X201041Y883924D03*
Y877231D03*
Y870538D03*
Y873885D03*
Y880577D03*
Y893963D03*
Y897310D03*
Y904003D03*
X205899Y893963D03*
Y887270D03*
X201041Y900656D03*
Y890617D03*
Y887270D03*
Y897310D03*
Y893963D03*
Y917389D03*
Y910696D03*
X205899Y917389D03*
Y910696D03*
Y904003D03*
X201041Y914042D03*
Y907349D03*
Y917389D03*
Y910696D03*
Y904003D03*
Y924081D03*
Y930774D03*
Y934121D03*
X205049Y930774D03*
Y924081D03*
X201041Y927428D03*
Y920735D03*
Y924081D03*
Y934121D03*
Y930774D03*
Y940814D03*
Y947507D03*
X205899Y940814D03*
Y947507D03*
X201041Y937467D03*
Y944160D03*
Y947507D03*
Y940814D03*
Y964239D03*
X205899D03*
Y954200D03*
X201041Y960892D03*
Y950853D03*
Y964239D03*
Y957546D03*
Y954200D03*
Y970932D03*
Y977625D03*
Y984318D03*
X205899Y970932D03*
Y977625D03*
X201041Y974278D03*
Y980971D03*
Y967585D03*
Y977625D03*
Y970932D03*
Y991011D03*
X205899D03*
Y984318D03*
X201041Y987664D03*
Y991011D03*
Y984318D03*
Y994357D03*
X201141Y1031168D03*
Y1024475D03*
Y1021129D03*
X205899Y1031168D03*
Y1017782D03*
Y1024475D03*
X201041Y1027822D03*
Y1017782D03*
X201141Y1021129D03*
Y1024475D03*
Y1031168D03*
Y1044554D03*
Y1037861D03*
X205899Y1044554D03*
Y1037861D03*
X201041Y1047900D03*
Y1041207D03*
Y1034515D03*
X201141Y1044554D03*
Y1037861D03*
Y1051247D03*
Y1064633D03*
X205899Y1057940D03*
Y1051247D03*
X201041Y1054593D03*
Y1061286D03*
X201141Y1051247D03*
Y1071326D03*
Y1078018D03*
Y1081366D03*
X205049Y1078018D03*
X205899Y1071326D03*
Y1064633D03*
X201041Y1074672D03*
Y1067979D03*
X201141Y1071326D03*
Y1064633D03*
Y1078018D03*
Y1088059D03*
Y1094752D03*
X205899Y1094751D03*
X205049Y1088058D03*
X201041Y1091404D03*
Y1084711D03*
X201141Y1094752D03*
Y1088059D03*
Y1081366D03*
Y1108137D03*
Y1101444D03*
Y1114830D03*
X205899Y1101444D03*
Y1108137D03*
X201041Y1111483D03*
Y1104790D03*
Y1098097D03*
X201141Y1108137D03*
Y1101444D03*
Y1118177D03*
X201041Y1124869D03*
Y1131562D03*
X205899Y1114829D03*
Y1124869D03*
X201041Y1128215D03*
Y1121522D03*
Y1124869D03*
X201141Y1118177D03*
Y1114830D03*
Y1144948D03*
Y1138255D03*
X205899Y1144948D03*
Y1138255D03*
Y1131562D03*
X201041Y1141601D03*
Y1134908D03*
X201141Y1144948D03*
Y1138255D03*
X201041Y1131562D03*
X201141Y1154988D03*
Y1161680D03*
Y1151641D03*
X205049Y1161680D03*
Y1151641D03*
X201041Y1158333D03*
Y1148294D03*
X201141Y1161680D03*
Y1154988D03*
Y1151641D03*
Y1175066D03*
Y1168373D03*
X205899D03*
Y1175066D03*
X201041Y1171719D03*
Y1165026D03*
X201141Y1175066D03*
Y1168373D03*
Y1191799D03*
Y1188452D03*
Y1181759D03*
X205899Y1188452D03*
Y1181759D03*
X201041Y1185105D03*
Y1178412D03*
X201141Y1181759D03*
Y1191799D03*
Y1188452D03*
Y1205184D03*
Y1198491D03*
Y1211877D03*
X205899Y1205184D03*
Y1198491D03*
X201041Y1208530D03*
Y1201837D03*
Y1195144D03*
X201141Y1205184D03*
Y1198491D03*
Y1218570D03*
Y1225263D03*
Y1228609D03*
X205049Y1225263D03*
X205899Y1211877D03*
Y1218570D03*
X201041Y1221916D03*
Y1215223D03*
X201141Y1218570D03*
Y1211877D03*
Y1225263D03*
Y1241995D03*
Y1235302D03*
X205899Y1241995D03*
X205049Y1235302D03*
X201041Y1238648D03*
Y1231955D03*
X201141Y1241995D03*
Y1235302D03*
Y1228609D03*
X205899Y1248688D03*
X201041Y1245341D03*
X205899Y1258727D03*
X201041Y1248688D03*
X201193Y1257900D03*
X206268Y1271348D03*
X206337Y1268720D03*
X205899Y1265420D03*
Y1262074D03*
X194497Y1578182D03*
X206557D03*
X198757D03*
X194497Y1590094D03*
X206557D03*
X198757D03*
X199797Y1614292D03*
Y1602380D03*
X204057Y1614292D03*
Y1602380D03*
X222041Y766798D03*
X214599Y770144D03*
X222041Y780184D03*
Y773491D03*
X214599Y783530D03*
Y776837D03*
X222041Y803609D03*
Y796916D03*
Y790223D03*
X214599Y800263D03*
Y793570D03*
X222041Y810302D03*
X221191Y816995D03*
X214599Y813648D03*
Y806955D03*
X215449Y820341D03*
X222041Y833727D03*
X221191Y827034D03*
X215449Y830381D03*
X222041Y847113D03*
Y840420D03*
X214599Y850459D03*
Y837074D03*
Y843766D03*
X221191Y863845D03*
X215449Y867192D03*
X222041Y853806D03*
X215449Y857152D03*
X222041Y877231D03*
X221191Y870538D03*
X222041Y883924D03*
X214599Y873885D03*
Y880577D03*
X222041Y900656D03*
Y890617D03*
X214599Y893963D03*
Y887270D03*
X222041Y914042D03*
Y907349D03*
X214599Y917389D03*
Y910696D03*
Y904003D03*
X221241Y927428D03*
X222041Y920735D03*
X215449Y930774D03*
Y924081D03*
X222041Y944160D03*
X221191Y937467D03*
X214599Y940814D03*
Y947507D03*
Y957546D03*
Y960892D03*
X222041D03*
Y950853D03*
X214599Y964239D03*
Y954200D03*
Y960892D03*
Y957546D03*
X222041D03*
Y954200D03*
Y980971D03*
Y974278D03*
Y967585D03*
X214599Y970932D03*
Y977625D03*
Y991011D03*
Y984318D03*
X222041Y987664D03*
Y994357D03*
Y1027822D03*
Y1017782D03*
X214599Y1031168D03*
Y1017782D03*
Y1024475D03*
X222041Y1047900D03*
Y1041207D03*
Y1034515D03*
X214599Y1044554D03*
Y1037861D03*
X222041Y1054593D03*
Y1061286D03*
X214599Y1057940D03*
Y1051247D03*
X222041Y1067979D03*
X221191Y1074672D03*
X215449Y1078018D03*
X214599Y1071326D03*
Y1064633D03*
X222041Y1091404D03*
X221191Y1084711D03*
X214599Y1094751D03*
X215449Y1088058D03*
X222041Y1111483D03*
Y1098097D03*
Y1104790D03*
X214599Y1101444D03*
Y1108137D03*
X222041Y1128215D03*
Y1121522D03*
X214599Y1114829D03*
Y1124869D03*
X222041Y1141601D03*
X221191Y1134908D03*
X214599Y1144948D03*
Y1138255D03*
Y1131562D03*
X222041Y1158333D03*
X221191Y1148294D03*
X215449Y1161680D03*
Y1151641D03*
X222041Y1165026D03*
Y1171719D03*
X214599Y1168373D03*
Y1175066D03*
X222041Y1185105D03*
Y1178412D03*
X214599Y1188452D03*
Y1181759D03*
X222041Y1208530D03*
Y1201837D03*
Y1195144D03*
X214599Y1205184D03*
Y1198491D03*
X222041Y1221916D03*
Y1215223D03*
X215449Y1225263D03*
X214599Y1211877D03*
Y1218570D03*
X221191Y1231955D03*
Y1238648D03*
X214599Y1241995D03*
X215449Y1235302D03*
X222041Y1245341D03*
X214824Y1258711D03*
X214599Y1248688D03*
X222041Y1255381D03*
Y1252034D03*
X224987Y1273535D03*
X222041Y1265420D03*
Y1262074D03*
X218617Y1578182D03*
X210817D03*
X222877D03*
X218617Y1590094D03*
X210817D03*
X222877D03*
X211857Y1614292D03*
Y1602380D03*
X223917Y1614292D03*
X216117D03*
X223917Y1602380D03*
X216117D03*
X235599Y770144D03*
X230741Y766798D03*
X235499D03*
X235599Y783530D03*
Y776837D03*
X230741Y780184D03*
Y773491D03*
X235599Y800263D03*
Y793570D03*
X230741Y803609D03*
Y796916D03*
Y790223D03*
X234749Y820341D03*
Y813648D03*
X235599Y806955D03*
X230741Y810302D03*
X231006Y817554D03*
X235599Y830381D03*
X230741Y833727D03*
X231591Y827034D03*
X235599Y850459D03*
Y837074D03*
Y843766D03*
X230741Y847113D03*
Y840420D03*
X234749Y867492D03*
X231591Y863845D03*
X234749Y857152D03*
X230741Y853806D03*
X235599Y874185D03*
Y880577D03*
X230741Y877231D03*
X231059Y871084D03*
X230741Y883924D03*
X235599Y893963D03*
Y887270D03*
X230741Y900656D03*
Y890617D03*
X235599Y917389D03*
Y910696D03*
Y904003D03*
X230741Y914042D03*
Y907349D03*
X235599Y930774D03*
Y924081D03*
X231541Y927428D03*
X230741Y920735D03*
X235599Y947507D03*
X234859Y940814D03*
X230741Y944660D03*
X231591Y937467D03*
X235599Y964239D03*
Y954200D03*
X230741Y960892D03*
Y950853D03*
X235599Y977625D03*
Y970932D03*
X230741Y980971D03*
Y974278D03*
Y967585D03*
X235599Y991011D03*
X230741Y987664D03*
X235599Y984318D03*
X236391Y1002557D03*
X240521Y1000395D03*
X237841Y1000437D03*
X233891Y1002557D03*
X231391D03*
X228891D03*
X235599Y1031168D03*
X230741Y1027822D03*
Y1017782D03*
X235599D03*
Y1024475D03*
Y1044554D03*
Y1037861D03*
X230741Y1047900D03*
Y1041207D03*
Y1034515D03*
X235599Y1051247D03*
Y1057940D03*
X230741Y1054593D03*
Y1061286D03*
X234749Y1078018D03*
X235599Y1071326D03*
Y1064633D03*
X230741Y1067979D03*
X231591Y1074672D03*
X235599Y1094751D03*
X234749Y1088058D03*
X230741Y1091404D03*
Y1084711D03*
X235599Y1108137D03*
Y1101444D03*
X230741Y1111483D03*
Y1098097D03*
Y1104790D03*
X234749Y1124869D03*
X235599Y1114829D03*
X230741Y1128215D03*
Y1121522D03*
X235599Y1144948D03*
Y1138255D03*
X234749Y1131562D03*
X230741Y1141601D03*
X231591Y1134908D03*
X235599Y1151641D03*
Y1161680D03*
X230741Y1158333D03*
X231591Y1148294D03*
X235599Y1175066D03*
Y1168373D03*
X230741Y1165026D03*
Y1171719D03*
X235599Y1188452D03*
Y1181759D03*
X230741Y1185105D03*
Y1178412D03*
X235599Y1205184D03*
Y1198491D03*
X230741Y1208530D03*
Y1201837D03*
Y1195144D03*
X234749Y1225263D03*
X235599Y1218570D03*
Y1211877D03*
X230741Y1221916D03*
Y1215223D03*
X235599Y1241995D03*
X235186Y1234977D03*
X231591Y1231955D03*
Y1238648D03*
X235599Y1248688D03*
X230741Y1245341D03*
X235599Y1258727D03*
X230741Y1248688D03*
X227746Y1273364D03*
X240966Y1273143D03*
X238971Y1274353D03*
X235480Y1265406D03*
X235599Y1262074D03*
X230677Y1578182D03*
X234937D03*
X230677Y1590094D03*
X234937D03*
X228177Y1614292D03*
X235977D03*
X228177Y1602380D03*
X235977D03*
X240237D03*
Y1614292D03*
X233268Y1679920D03*
Y1675383D03*
X241142Y1679320D03*
X233268Y1698627D03*
Y1694093D03*
Y1689556D03*
Y1684454D03*
X241142Y1683857D03*
Y1688391D03*
Y1693493D03*
Y1698030D03*
X233268Y1712800D03*
Y1708266D03*
Y1703729D03*
X241142Y1702564D03*
Y1707666D03*
Y1712203D03*
X233268Y1717903D03*
Y1722440D03*
Y1726974D03*
X241142Y1716737D03*
Y1730911D03*
Y1726377D03*
Y1721840D03*
X251741Y766798D03*
X244299Y770144D03*
X251741Y780184D03*
Y773491D03*
X244299Y783530D03*
Y776837D03*
X251741Y803609D03*
Y796916D03*
Y790223D03*
X244299Y800263D03*
Y793570D03*
X250891Y816995D03*
X251741Y810302D03*
X245149Y820341D03*
Y813648D03*
X244299Y806955D03*
X251741Y833727D03*
X250891Y827034D03*
X244299Y830381D03*
X251741Y847113D03*
Y840420D03*
X244299Y850459D03*
Y837074D03*
Y843766D03*
X250891Y863845D03*
Y853806D03*
X245149Y867192D03*
Y857152D03*
X244299Y883924D03*
X251741Y870538D03*
Y883924D03*
Y877231D03*
X244299Y873885D03*
Y880577D03*
Y883924D03*
Y900656D03*
Y897310D03*
Y890617D03*
X250891Y900656D03*
X251741Y890617D03*
X244299Y893963D03*
Y887270D03*
Y890617D03*
Y897310D03*
Y900656D03*
Y907349D03*
Y914042D03*
X251741D03*
Y907349D03*
X244299Y917389D03*
Y910696D03*
Y904003D03*
Y914042D03*
Y907349D03*
X250891Y927428D03*
X251741Y920735D03*
X245149Y930774D03*
X244299Y924081D03*
X251741Y944160D03*
X250891Y937467D03*
X244299Y947507D03*
X245149Y940814D03*
X244299Y957546D03*
Y960892D03*
X251741D03*
Y950853D03*
X244299Y964239D03*
Y954200D03*
Y960892D03*
Y957546D03*
X251741D03*
Y954200D03*
Y980971D03*
Y974278D03*
Y967585D03*
X244299Y977625D03*
Y970932D03*
X251741Y987664D03*
X244299Y991011D03*
Y984318D03*
X251741Y994357D03*
X254881Y999650D03*
X257561Y999608D03*
X244299Y1031168D03*
X251741Y1027822D03*
Y1017782D03*
X244299D03*
Y1024475D03*
X251741Y1047900D03*
Y1041207D03*
Y1034515D03*
X244299Y1044554D03*
Y1037861D03*
X251741Y1061286D03*
Y1054593D03*
X244299Y1051247D03*
Y1057940D03*
Y1061286D03*
X250891Y1074672D03*
Y1067979D03*
X245149Y1078018D03*
X244299Y1071326D03*
Y1064633D03*
X251741Y1091404D03*
Y1084711D03*
X244299Y1094751D03*
X245149Y1088058D03*
X251741Y1104790D03*
X250891Y1111483D03*
X251741Y1098097D03*
X244299Y1108137D03*
Y1101444D03*
X251741Y1128215D03*
X250891Y1121522D03*
X245149Y1124869D03*
X244299Y1114829D03*
X251741Y1134908D03*
Y1141601D03*
X244299Y1144948D03*
Y1138255D03*
X245149Y1131562D03*
X251741Y1158333D03*
Y1148294D03*
X244299Y1151641D03*
Y1161680D03*
Y1178412D03*
X251741Y1171719D03*
Y1165026D03*
X244299Y1175066D03*
Y1168373D03*
Y1185105D03*
Y1191798D03*
Y1195144D03*
X251741Y1185105D03*
Y1178412D03*
X244299Y1188452D03*
Y1181759D03*
Y1185105D03*
Y1178412D03*
Y1191798D03*
Y1201837D03*
Y1208530D03*
X251741D03*
Y1201837D03*
X250891Y1195144D03*
X244299Y1205184D03*
Y1198491D03*
Y1208530D03*
Y1201837D03*
Y1195144D03*
X250891Y1221916D03*
X251741Y1215223D03*
X245149Y1225263D03*
X244299Y1218570D03*
Y1211877D03*
X250891Y1231955D03*
X244299Y1241995D03*
X245149Y1235302D03*
X251741Y1238648D03*
X244299Y1248688D03*
X251741Y1245341D03*
X248047Y1259155D03*
X250467Y1259175D03*
X251707Y1252034D03*
X244789Y1260093D03*
X254897Y1274040D03*
X257197Y1273640D03*
X249603Y1266204D03*
X251699Y1265254D03*
X242737Y1578182D03*
X246997D03*
X254797D03*
X242737Y1590094D03*
X246997D03*
X254797D03*
X248037Y1602380D03*
Y1614292D03*
X252297Y1602380D03*
Y1614292D03*
X249016Y1675383D03*
Y1679920D03*
X256890Y1679320D03*
X249016Y1684454D03*
Y1689556D03*
Y1694093D03*
Y1698627D03*
X256890Y1683857D03*
Y1688391D03*
Y1693493D03*
Y1698030D03*
X249016Y1703729D03*
Y1708266D03*
Y1712800D03*
X256890Y1702564D03*
Y1707666D03*
Y1712203D03*
X249016Y1726974D03*
Y1722440D03*
Y1717903D03*
X256890Y1716737D03*
Y1730911D03*
Y1726377D03*
Y1721840D03*
X260441Y766798D03*
Y780184D03*
Y773491D03*
Y803609D03*
Y796916D03*
Y790223D03*
X261291Y816995D03*
X260441Y810302D03*
Y833727D03*
X261291Y827034D03*
X260441Y847113D03*
Y840420D03*
X261291Y863845D03*
Y853806D03*
X260441Y880577D03*
Y887270D03*
Y870538D03*
Y883924D03*
Y877231D03*
Y880577D03*
Y893963D03*
Y897310D03*
Y904003D03*
Y900656D03*
Y890617D03*
Y887270D03*
Y897310D03*
Y893963D03*
Y910696D03*
Y914042D03*
Y907349D03*
Y910696D03*
Y904003D03*
X261291Y927428D03*
X260441Y920735D03*
Y944160D03*
X261291Y937467D03*
X260441Y960892D03*
Y950853D03*
Y980971D03*
Y974278D03*
Y967585D03*
Y987664D03*
Y1027822D03*
Y1017782D03*
Y1047900D03*
Y1041207D03*
Y1034515D03*
Y1061286D03*
Y1054593D03*
Y1057940D03*
X261291Y1074672D03*
Y1067979D03*
X260441Y1091404D03*
Y1084711D03*
Y1104790D03*
X261291Y1111483D03*
X260441Y1098097D03*
Y1128215D03*
X261291Y1121522D03*
X260441Y1134908D03*
Y1141601D03*
Y1158333D03*
Y1148294D03*
Y1175066D03*
Y1171719D03*
Y1165026D03*
Y1175066D03*
Y1188452D03*
Y1181759D03*
Y1191798D03*
Y1185105D03*
Y1178412D03*
Y1181759D03*
Y1191798D03*
Y1188452D03*
Y1205184D03*
Y1198491D03*
Y1208530D03*
Y1201837D03*
Y1195144D03*
Y1205184D03*
Y1198491D03*
X261291Y1221916D03*
X260441Y1215223D03*
X261291Y1231955D03*
X260441Y1238648D03*
Y1245341D03*
Y1248688D03*
X266857Y1578182D03*
X259057D03*
X271117D03*
X266857Y1590094D03*
X259057D03*
X271117D03*
X260097Y1602380D03*
Y1614292D03*
X272157Y1602380D03*
Y1614292D03*
X264357D03*
Y1602380D03*
X264764Y1675383D03*
Y1679920D03*
X272638Y1679320D03*
X264764Y1684454D03*
Y1689556D03*
Y1694093D03*
Y1698627D03*
X272638Y1683857D03*
Y1688391D03*
Y1693493D03*
Y1698030D03*
X264764Y1703729D03*
Y1708266D03*
Y1712800D03*
X272638Y1702564D03*
Y1707666D03*
Y1712203D03*
X264764Y1726974D03*
Y1722440D03*
Y1717903D03*
X272638Y1716737D03*
Y1730911D03*
Y1726377D03*
Y1721840D03*
X278917Y1578182D03*
X283177D03*
X278917Y1590094D03*
X283177D03*
X284217Y1602380D03*
Y1614292D03*
X276417D03*
Y1602380D03*
X288477Y1614292D03*
Y1602380D03*
X280512Y1675383D03*
Y1679920D03*
Y1684454D03*
Y1689556D03*
Y1694093D03*
Y1698627D03*
Y1703729D03*
Y1708266D03*
Y1712800D03*
Y1726974D03*
Y1722440D03*
Y1717903D03*
X290977Y1578182D03*
X295237D03*
X303037D03*
X290977Y1590094D03*
X295237D03*
X303037D03*
X296277Y1614292D03*
Y1602380D03*
X300537D03*
Y1614292D03*
X300197Y1679920D03*
Y1675383D03*
Y1698627D03*
Y1694093D03*
Y1689556D03*
Y1684454D03*
Y1712800D03*
Y1708266D03*
Y1703729D03*
Y1717903D03*
Y1722440D03*
Y1726974D03*
X315097Y1578182D03*
X307297D03*
X319357D03*
X315097Y1590094D03*
X307297D03*
X319357D03*
X308337Y1602380D03*
Y1614292D03*
X320397D03*
X312597D03*
X320397Y1602380D03*
X312597D03*
X308071Y1679320D03*
X315945Y1679920D03*
Y1675383D03*
X308071Y1683857D03*
Y1698030D03*
Y1693493D03*
Y1688391D03*
X315945Y1698627D03*
Y1694093D03*
Y1689556D03*
Y1684454D03*
X308071Y1702564D03*
Y1712203D03*
Y1707666D03*
X315945Y1712800D03*
Y1708266D03*
Y1703729D03*
X308071Y1716737D03*
Y1721840D03*
Y1726377D03*
Y1730911D03*
X315945Y1717903D03*
Y1722440D03*
Y1726974D03*
X337778Y854584D03*
X335924Y857789D03*
X337779Y880219D03*
X335928Y883423D03*
X337779Y886627D03*
X334079D03*
Y880219D03*
X332228Y877014D03*
X335928D03*
X337779Y880219D03*
X335928Y883423D03*
X337779Y893036D03*
X335928Y889832D03*
X334078Y893036D03*
X335928Y896240D03*
X337779Y893036D03*
X335928Y889832D03*
X334079Y886627D03*
X337779D03*
X332229Y902649D03*
X332228Y915466D03*
X335928D03*
X332229Y921875D03*
Y941100D03*
X332228Y934692D03*
X335928D03*
X334079Y957122D03*
X335928Y953917D03*
X332228D03*
X332229Y973143D03*
X334079Y976347D03*
X331284Y978814D03*
X335349Y985939D03*
X338210Y996480D03*
X332661Y1006093D03*
X338211Y1002888D03*
X332661Y1025318D03*
Y1018910D03*
X338211Y1015705D03*
Y1022114D03*
X332661Y1044544D03*
X338211Y1041340D03*
X334511D03*
X338211Y1060565D03*
X333834Y1062790D03*
X329632Y1092168D03*
X336360Y1082995D03*
X338211Y1111834D03*
Y1105426D03*
X335344Y1097289D03*
X336361Y1121447D03*
X340061D03*
Y1127856D03*
X338211Y1124651D03*
X336361Y1115039D03*
Y1127856D03*
X338211Y1118243D03*
X336361Y1121447D03*
X338211Y1131060D03*
X327157Y1578182D03*
X331417D03*
X327157Y1590094D03*
X331417D03*
X324657Y1602380D03*
X332457D03*
X324657Y1614292D03*
X332457D03*
X336717Y1602380D03*
Y1614292D03*
X323819Y1679320D03*
X331693Y1679920D03*
Y1675383D03*
X323819Y1683857D03*
Y1698030D03*
Y1693493D03*
Y1688391D03*
X331693Y1698627D03*
Y1694093D03*
Y1689556D03*
Y1684454D03*
X323819Y1702564D03*
Y1712203D03*
Y1707666D03*
X331693Y1712800D03*
Y1708266D03*
Y1703729D03*
X323819Y1716737D03*
Y1721840D03*
Y1726377D03*
Y1730911D03*
X331693Y1717903D03*
Y1722440D03*
Y1726974D03*
X354427Y844971D03*
X356279Y841467D03*
X350727Y851380D03*
X348878Y848176D03*
X352578D03*
X356278Y854584D03*
X347028Y844971D03*
X345178Y848176D03*
X350727Y844971D03*
X347027Y851380D03*
X343327D03*
X354429D03*
X350727D03*
X354427Y844971D03*
X348878Y848176D03*
X352578D03*
X350729Y857789D03*
X352578Y860993D03*
X354429Y857789D03*
X356278Y867401D03*
X354429Y870606D03*
X350729D03*
X341478Y854584D03*
X339628Y857789D03*
X347029Y864197D03*
Y857789D03*
X348878Y854584D03*
X345179Y860993D03*
X343327Y857789D03*
X352579Y854584D03*
X354429Y864197D03*
X350729D03*
X341479Y867401D03*
X348879D03*
X352579D03*
X348879Y860993D03*
X350729Y857789D03*
X352578Y860993D03*
X354429Y857789D03*
Y883423D03*
X356278Y880219D03*
X341479D03*
X343329Y883423D03*
X352578Y873810D03*
X341479Y886627D03*
X345179D03*
X347029Y870606D03*
X354429Y877014D03*
X339629D03*
X341479Y873810D03*
X345179Y880219D03*
Y873810D03*
X343329Y877014D03*
X352579Y880219D03*
X350729Y877014D03*
X339629Y883423D03*
X347029D03*
X350729D03*
X341479Y880219D03*
X343329Y883423D03*
X350729Y870606D03*
X354429D03*
X352578Y873810D03*
X354429Y883423D03*
X348879Y873810D03*
X347029Y877014D03*
X341478Y893036D03*
X350729Y889832D03*
X348878Y899445D03*
X350729Y896240D03*
X347029D03*
X343328Y889832D03*
X348878Y893036D03*
X354429Y889832D03*
Y896240D03*
X356278Y899445D03*
Y893036D03*
X354429Y902649D03*
X350729D03*
X352578Y899445D03*
X339629Y896240D03*
Y889832D03*
X348879Y886627D03*
X347029Y889832D03*
X345179Y893036D03*
X343328Y896240D03*
X352578Y893036D03*
Y886627D03*
X345179Y899445D03*
X348878D03*
Y893036D03*
X350729Y889832D03*
X354429D03*
X341478Y893036D03*
X343328Y889832D03*
X347029Y896240D03*
X354429D03*
X341479Y886627D03*
X350729Y896240D03*
X345179Y886627D03*
X356278Y912262D03*
X354429Y909057D03*
Y915466D03*
X350729D03*
X347029D03*
X350729Y909057D03*
X348878Y912262D03*
Y918670D03*
X356278D03*
X348878Y905853D03*
X352578D03*
X341479Y912262D03*
X341478Y905853D03*
X347029Y909057D03*
Y902649D03*
X345179Y912262D03*
X352578D03*
X339629Y915466D03*
X343329D03*
X348878Y912262D03*
X350729Y909057D03*
X354429D03*
X350729Y902649D03*
X354429D03*
X347029Y915466D03*
X354429D03*
X350729D03*
X354429Y928283D03*
X350729D03*
X354429Y921875D03*
X350729D03*
X348879Y931488D03*
X356278D03*
X354429Y934691D03*
X350729D03*
X347029D03*
X348878Y925079D03*
X352578D03*
Y918670D03*
X341478Y925079D03*
X347029Y928283D03*
Y921875D03*
X345179Y918670D03*
X341479Y931488D03*
X345179D03*
X352578D03*
X348879D03*
X350729Y928283D03*
X354429D03*
Y921875D03*
X350729D03*
X348878Y918670D03*
X354429Y941100D03*
Y947509D03*
X356278Y937896D03*
X350729Y941100D03*
X348878Y937896D03*
X350729Y947509D03*
X348878Y950713D03*
X356278D03*
X341478Y944304D03*
X352578D03*
X347029Y941100D03*
X348878Y944304D03*
X347029Y947509D03*
X352578Y937896D03*
X339629Y934692D03*
X345179Y937896D03*
X343328Y934692D03*
X350729Y941100D03*
X348878Y937896D03*
X354429Y941100D03*
X347029Y934691D03*
X354429D03*
X350729D03*
Y947509D03*
X354429D03*
X350729Y960326D03*
Y966735D03*
Y953917D03*
X354429Y960326D03*
Y953917D03*
X348878Y957122D03*
X347030Y953917D03*
X354429Y966735D03*
X356278Y957122D03*
X348878Y963530D03*
X347029Y960326D03*
X343328D03*
X343329Y966735D03*
X339629D03*
Y953917D03*
X343328D03*
X345179Y957122D03*
X352578D03*
X347029Y966735D03*
X352578Y963530D03*
X341479Y950713D03*
X345179D03*
X352578D03*
X348878D03*
X350729Y960326D03*
X348878Y957122D03*
X354429Y960326D03*
X350729Y966735D03*
X354429D03*
X350729Y953917D03*
X354429D03*
X347030D03*
X354429Y979552D03*
X356278Y976347D03*
Y969939D03*
X348878Y976347D03*
X347029Y973143D03*
X348878Y969939D03*
X350729Y979552D03*
X354428Y973143D03*
X339629D03*
X345179Y976347D03*
Y969939D03*
X350729Y973143D03*
X347029Y979552D03*
X352579Y976347D03*
X352578Y969939D03*
X348878Y982756D03*
X352578D03*
X339629Y979552D03*
X343329Y973143D03*
X350729Y979552D03*
X354429D03*
X348878Y976347D03*
X347029Y973143D03*
X348878Y969939D03*
X354861Y999684D03*
X351161D03*
X354861Y1012501D03*
X356711Y1002888D03*
Y1009297D03*
X347461Y1006093D03*
X351161Y1012501D03*
X349311Y1009297D03*
Y1002888D03*
X341911Y1009297D03*
Y1002888D03*
X347461Y999684D03*
X345611Y1009297D03*
X343761Y1006093D03*
X345611Y1002888D03*
X351162Y1006093D03*
X354861D03*
X353011Y1009297D03*
Y1002888D03*
X347461Y1012501D03*
Y1006093D03*
X349311Y1002888D03*
X351161Y999684D03*
X354861D03*
X351161Y1012501D03*
X349311Y1009297D03*
X354861Y1012501D03*
X343761Y999684D03*
X351162Y1031727D03*
X351161Y1018910D03*
X354861Y1031727D03*
Y1018910D03*
X354862Y1025318D03*
X351162D03*
X347461D03*
X349311Y1028523D03*
Y1022114D03*
X356711Y1028523D03*
Y1022114D03*
X353011Y1028523D03*
Y1015705D03*
X341911Y1022114D03*
Y1015705D03*
X349311D03*
X347461Y1018910D03*
X345611Y1028523D03*
X343761Y1018910D03*
X345611Y1022114D03*
Y1015705D03*
X353011Y1022114D03*
X343761Y1031727D03*
X347461D03*
X351162D03*
X349311Y1028523D03*
X354861Y1031727D03*
X349311Y1022114D03*
X351161Y1018910D03*
X354861D03*
X347461Y1025318D03*
X354862D03*
X351162D03*
X354861Y1038136D03*
Y1044544D03*
X356711Y1047749D03*
Y1041340D03*
X347461Y1044544D03*
X349311Y1047749D03*
X351161Y1038136D03*
Y1044544D03*
X349311Y1041340D03*
X353011Y1034931D03*
Y1047749D03*
X341911Y1041340D03*
X343761Y1038136D03*
X349311Y1034931D03*
X347461Y1038136D03*
X345611Y1041340D03*
X343761Y1044544D03*
X353011Y1041340D03*
X345611Y1047749D03*
X349311D03*
Y1041340D03*
X351161Y1038136D03*
X354861D03*
X347461Y1044544D03*
X354861D03*
X351161D03*
Y1063770D03*
Y1057361D03*
X349311Y1060565D03*
X354861Y1063770D03*
Y1057361D03*
Y1050952D03*
X347461Y1063770D03*
X351161Y1050952D03*
X356711Y1060565D03*
X349311Y1054157D03*
X353011Y1060565D03*
Y1054157D03*
X343761Y1057361D03*
Y1050952D03*
X347461D03*
Y1057361D03*
X345611Y1060565D03*
X343761Y1063770D03*
X349311Y1060565D03*
X351161Y1057361D03*
X354861D03*
X347461Y1063770D03*
X351161D03*
X354861D03*
X351161Y1050952D03*
X354861D03*
Y1076587D03*
Y1070178D03*
X356711Y1079791D03*
Y1066974D03*
X351162Y1070178D03*
X351161Y1076587D03*
X349311Y1079791D03*
Y1066974D03*
X353011Y1073383D03*
X343761Y1076587D03*
Y1070178D03*
X340062Y1076587D03*
X347461D03*
Y1070178D03*
X349312Y1073383D03*
X345611Y1066974D03*
X353011D03*
X345611Y1079791D03*
X341911D03*
X353011D03*
X354861Y1070178D03*
X351162D03*
X349311Y1066974D03*
Y1079791D03*
X351161Y1076587D03*
X354861D03*
X351161Y1089404D03*
X354861D03*
Y1082995D03*
X351161D03*
X349311Y1086200D03*
X347461Y1082995D03*
X356711Y1086200D03*
X353011D03*
X349310Y1092609D03*
X347461Y1089404D03*
X345610Y1086200D03*
X343760Y1082995D03*
X343707Y1091513D03*
X340060Y1082995D03*
X353011Y1092608D03*
X340061Y1095813D03*
X351161Y1089404D03*
X349311Y1086200D03*
X354861Y1089404D03*
X347461Y1082995D03*
X354861D03*
X351161D03*
X353012Y1111834D03*
X354861Y1102221D03*
X353011Y1105426D03*
X351162Y1108630D03*
X341912Y1111834D03*
X345611D03*
X351161Y1102221D03*
X349312Y1111834D03*
X341911Y1105426D03*
X343762Y1108630D03*
X345611Y1105426D03*
X347461Y1115039D03*
Y1108630D03*
X354861D03*
X353011Y1099017D03*
X340061Y1108630D03*
Y1102221D03*
X349311Y1099017D03*
X347461Y1102221D03*
X343761D03*
X349311Y1105426D03*
X341911D03*
X343762Y1108630D03*
X345611Y1111834D03*
X351161Y1102221D03*
X349312Y1111834D03*
X353011Y1105426D03*
X345611D03*
X341912Y1111834D03*
X354861Y1102221D03*
X353012Y1111834D03*
X351162Y1108630D03*
X343761Y1121447D03*
X345611Y1124651D03*
X347461Y1127856D03*
X341912Y1118243D03*
X343761Y1127856D03*
X353011Y1124651D03*
X354861Y1127856D03*
X347461Y1121447D03*
X356712Y1124651D03*
X341911Y1131060D03*
X340061Y1115039D03*
X349311Y1124651D03*
X349312Y1118243D03*
X345611D03*
X343761Y1115039D03*
X341911Y1124651D03*
X354861Y1115039D03*
X351161Y1121447D03*
Y1115039D03*
X353011Y1124651D03*
X354861Y1127856D03*
X351162D03*
X353011Y1118243D03*
X354861Y1121447D03*
X347461Y1115039D03*
X341912Y1118243D03*
X340061Y1127856D03*
X343761D03*
X347461Y1121447D03*
X340061D03*
X343761D03*
X347461Y1127856D03*
X345611Y1124651D03*
X356712Y1137469D03*
X349312D03*
X351161Y1134264D03*
X345611Y1137469D03*
Y1131060D03*
X349311D03*
X343761Y1134264D03*
X353011Y1137469D03*
Y1131060D03*
X349312Y1137469D03*
X351161Y1134264D03*
X347461D03*
X354861D03*
X341911Y1131060D03*
X339217Y1578182D03*
X343477D03*
X351277D03*
X339217Y1590094D03*
X343477D03*
X351277D03*
X344517Y1602380D03*
Y1614292D03*
X348777Y1602380D03*
Y1614292D03*
X339567Y1679320D03*
X347441Y1679920D03*
Y1675383D03*
X355315Y1679320D03*
X339567Y1683857D03*
Y1698030D03*
Y1693493D03*
Y1688391D03*
X347441Y1698627D03*
Y1694093D03*
Y1689556D03*
Y1684454D03*
X355315Y1683857D03*
Y1698030D03*
Y1693493D03*
Y1688391D03*
X339567Y1702564D03*
Y1712203D03*
Y1707666D03*
X347441Y1712800D03*
Y1708266D03*
Y1703729D03*
X355315Y1702564D03*
Y1712203D03*
Y1707666D03*
X339567Y1716737D03*
Y1721840D03*
Y1726377D03*
Y1730911D03*
X347441Y1717903D03*
Y1722440D03*
Y1726974D03*
X355315Y1716737D03*
Y1721840D03*
Y1726377D03*
Y1730911D03*
X372927Y844971D03*
X369227D03*
X371079Y841467D03*
X358127Y844971D03*
X365527D03*
X367378Y848176D03*
X359978D03*
X361827Y844971D03*
X363679Y841467D03*
X363678Y854584D03*
X371078D03*
X359979Y841467D03*
X367379D03*
X365529Y851380D03*
X361829D03*
X358129D03*
X369229D03*
X356278Y848176D03*
X371078D03*
X363678D03*
X356279Y841467D03*
X361827Y844971D03*
X363679Y841467D03*
X369227Y844971D03*
X371079Y841467D03*
X358127Y844971D03*
X359978Y848176D03*
X365527Y844971D03*
X367378Y848176D03*
X358129Y857789D03*
X369229D03*
X365529D03*
X363678Y867401D03*
X371078D03*
X367378Y860993D03*
X359978D03*
X361829Y857789D03*
X372929D03*
Y870606D03*
X369229D03*
X361829D03*
X358129D03*
X365529D03*
Y864197D03*
X361829D03*
X359979Y854584D03*
X358129Y864197D03*
X369229D03*
X367379Y854584D03*
X359979Y867401D03*
X367379D03*
X371078D03*
X356278D03*
X363678D03*
X356278Y860993D03*
X371078D03*
X363678D03*
X356278Y854584D03*
X358129Y857789D03*
X363678Y854584D03*
X365529Y857789D03*
X371078Y854584D03*
X359978Y860993D03*
X361829Y857789D03*
X367378Y860993D03*
X369229Y857789D03*
X371078Y880219D03*
X372929Y883423D03*
X369229D03*
X363678Y880219D03*
X359978Y873810D03*
X367378D03*
X361829Y883423D03*
X365529D03*
X358129D03*
X359978Y886627D03*
X367378D03*
X365529Y877014D03*
X361829D03*
X359979Y880219D03*
X358129Y877014D03*
X369229D03*
X367379Y880219D03*
X358129Y870606D03*
X361829D03*
X365529D03*
X359978Y873810D03*
X367378D03*
X369229Y870606D03*
X356278Y880219D03*
X358129Y883423D03*
X363678Y880219D03*
X365529Y883423D03*
X371078Y880219D03*
X361829Y883423D03*
X369229D03*
X371078Y873810D03*
X356278D03*
X363678D03*
X367378Y899445D03*
X371078Y893036D03*
X358129Y896240D03*
X363678Y899445D03*
X372929Y896240D03*
X369229Y902649D03*
X361829D03*
X356278Y886627D03*
X365529Y896240D03*
Y889832D03*
X361828Y896240D03*
X361829Y889832D03*
X359979Y893036D03*
X358128Y889832D03*
X369229Y896240D03*
Y889832D03*
X359979Y899445D03*
X371078D03*
X356278D03*
Y893036D03*
X358129Y896240D03*
X363678Y899445D03*
X367378D03*
X371078Y893036D03*
X367379D03*
X359978Y886627D03*
X367378D03*
X363678D03*
X371078D03*
Y905853D03*
X372929Y915466D03*
X369229Y909057D03*
X358129Y915466D03*
X367378Y905853D03*
X363678D03*
X367378Y912262D03*
X361829Y909057D03*
X359978Y905853D03*
X363678Y912262D03*
Y918670D03*
X367378D03*
X356278Y905853D03*
X365529Y909057D03*
Y902649D03*
X359978Y912262D03*
X358128Y909057D03*
X358129Y902649D03*
X371079Y912262D03*
X365529Y915466D03*
X361828D03*
X369229D03*
X356278Y912262D03*
X358129Y915466D03*
X363678Y912262D03*
X361829Y909057D03*
X367378Y912262D03*
X369229Y909057D03*
X361829Y902649D03*
X369229D03*
X359978Y905853D03*
X367378D03*
X363678D03*
X371078D03*
X361829Y921875D03*
X369229D03*
X359978Y925079D03*
X367378D03*
X363678D03*
X371078D03*
X361829Y928283D03*
X367378Y931488D03*
X369229Y928283D03*
X363678Y931488D03*
X372929Y934691D03*
X358129D03*
X356279Y925079D03*
X365529Y928283D03*
Y921875D03*
X359979Y918670D03*
X358128Y928283D03*
X358129Y921875D03*
X371078Y918670D03*
X359978Y931488D03*
X371079D03*
X356278D03*
X363678D03*
X356278Y918670D03*
X361829Y928283D03*
X367378Y931488D03*
X369229Y928283D03*
X361829Y921875D03*
X363678Y918670D03*
X369229Y921875D03*
X367378Y918670D03*
X359978Y925079D03*
X367378D03*
X363678D03*
X371078D03*
X369229Y941100D03*
X371078Y944304D03*
X369229Y947509D03*
X363678Y937896D03*
Y944304D03*
X361829Y947509D03*
X367378Y937896D03*
Y944304D03*
X359978D03*
X361829Y941100D03*
X367378Y950713D03*
X363678D03*
X358128Y947509D03*
X358129Y941100D03*
X356279Y944304D03*
X365529Y947509D03*
Y941100D03*
Y934691D03*
X361828D03*
X359979Y937896D03*
X369229Y934691D03*
X371078Y937896D03*
X356278D03*
X358129Y934691D03*
X361829Y941100D03*
X363678Y937896D03*
X369229Y941100D03*
X367378Y937896D03*
X361829Y947509D03*
X369229D03*
X367378Y944304D03*
X359978D03*
X371078D03*
X363678D03*
X371078Y963530D03*
X361829Y960326D03*
X363678Y957122D03*
X367378D03*
X369229Y960326D03*
X359978Y963530D03*
X358129Y953917D03*
X369229Y966735D03*
X361829D03*
X372929Y953917D03*
X356279Y963530D03*
X358129Y960326D03*
X359979Y957122D03*
X358128Y966735D03*
X361829Y953917D03*
X359978Y950713D03*
X371078Y957122D03*
X371079Y950713D03*
X365529Y953917D03*
X367378Y963530D03*
X363679D03*
X365529Y960326D03*
X365528Y966735D03*
X369229Y953917D03*
X356278Y950713D03*
Y957122D03*
X358129Y953917D03*
X361829Y966735D03*
X369229D03*
X359978Y963530D03*
X363678Y950713D03*
X367378D03*
X361829Y960326D03*
X363678Y957122D03*
X369229Y960326D03*
X367378Y957122D03*
X371078Y963530D03*
X372929Y973143D03*
X369229Y979552D03*
X371078Y982756D03*
X367378Y969939D03*
Y976347D03*
X363678Y969939D03*
X358129Y973143D03*
X363678Y976347D03*
X361829Y979552D03*
X367378Y982756D03*
X363678D03*
X359978D03*
X359979Y976347D03*
X358129Y979552D03*
X359978Y969939D03*
X361828Y973143D03*
X356279Y982756D03*
X371078Y976347D03*
X371079Y969939D03*
X369229Y973143D03*
X365529Y979552D03*
Y973143D03*
X359978Y982756D03*
X367378D03*
X363678D03*
X371078D03*
X369229Y979552D03*
X367378Y976347D03*
X361829Y979552D03*
X363678Y976347D03*
X356278D03*
Y969939D03*
X358129Y973143D03*
X363678Y969939D03*
X367378D03*
X369662Y999684D03*
X362262D03*
X373362Y1006093D03*
X369662Y1012501D03*
X371511Y1002888D03*
X364111Y1009297D03*
Y1002888D03*
X362262Y1012501D03*
X358562Y1006093D03*
X367811Y1009297D03*
X371511Y1015705D03*
X360411D03*
X365962Y999684D03*
Y1006093D03*
X362261D03*
X360411Y1009297D03*
X360412Y1002888D03*
X358562Y999684D03*
X369662Y1006093D03*
X371512Y1009297D03*
X365961Y1012501D03*
X358561D03*
X367811Y1002888D03*
X358562Y1006093D03*
X356711Y1002888D03*
Y1009297D03*
X362262Y1012501D03*
X369662D03*
X364111Y1009297D03*
X367811D03*
X364111Y1002888D03*
X362262Y999684D03*
X371511Y1002888D03*
X369662Y999684D03*
X364111Y1028523D03*
Y1022114D03*
X367811D03*
Y1028523D03*
X369662Y1031727D03*
Y1018910D03*
X362262D03*
X358562Y1025318D03*
X362262Y1031727D03*
X373360Y1025318D03*
X356712Y1015705D03*
X365962Y1025318D03*
Y1018910D03*
X364112Y1015705D03*
X360411Y1028523D03*
X362261Y1025318D03*
X360412Y1022114D03*
X358562Y1018910D03*
X369662Y1025318D03*
X367811Y1015705D03*
X371511Y1028523D03*
Y1022114D03*
X365962Y1031727D03*
X358561D03*
X356711Y1028523D03*
Y1022114D03*
X362262Y1031727D03*
X364111Y1028523D03*
X369662Y1031727D03*
X367811Y1028523D03*
X358562Y1025318D03*
X360411Y1015705D03*
X371511D03*
X364111Y1022114D03*
X362262Y1018910D03*
X367811Y1022114D03*
X369662Y1018910D03*
Y1038136D03*
X371511Y1034931D03*
X373362Y1044544D03*
X367811Y1034931D03*
X364111Y1041340D03*
X362262Y1038136D03*
X367811Y1041340D03*
X360411Y1034931D03*
X364111D03*
X367811Y1047749D03*
X364111D03*
X358562Y1044544D03*
X356712Y1034931D03*
X365962Y1044544D03*
Y1038136D03*
X362261Y1044544D03*
X360412Y1041340D03*
X358562Y1038136D03*
X369662Y1044544D03*
X371511Y1041340D03*
X360411Y1047749D03*
X371511D03*
X356711D03*
Y1041340D03*
X364111D03*
X362262Y1038136D03*
X367811Y1041340D03*
X369662Y1038136D03*
X360411Y1034931D03*
X371511D03*
X364111D03*
X358562Y1044544D03*
X367811Y1034931D03*
X364111Y1047749D03*
X367811D03*
X371511Y1054157D03*
X362262Y1057361D03*
X369662D03*
Y1050952D03*
X358562Y1063770D03*
X367811Y1060565D03*
X364111Y1054157D03*
X362262Y1050952D03*
X360411Y1054157D03*
X367811D03*
X364111Y1060565D03*
X373362Y1063770D03*
X356712Y1054157D03*
X365962Y1057361D03*
Y1050952D03*
X360412Y1060565D03*
X358562Y1057361D03*
X358561Y1050952D03*
X371511Y1060565D03*
X365962Y1063770D03*
X362261D03*
X369662D03*
X356711Y1060565D03*
X358562Y1063770D03*
X364111Y1060565D03*
X362262Y1057361D03*
X367811Y1060565D03*
X369662Y1057361D03*
X362262Y1050952D03*
X369662D03*
X360411Y1054157D03*
X371511D03*
X364111D03*
X367811D03*
X371511Y1073383D03*
X369662Y1070178D03*
Y1076587D03*
X367811Y1073383D03*
X364111D03*
X367811Y1079791D03*
X360411Y1073383D03*
X362262Y1076587D03*
Y1070178D03*
X367811Y1066974D03*
X364111D03*
Y1079791D03*
X356712Y1073383D03*
X365962Y1070178D03*
Y1076587D03*
X360411Y1066974D03*
X358561Y1070178D03*
X358562Y1076587D03*
X371512Y1066974D03*
X360412Y1079791D03*
X371511D03*
X356711Y1066974D03*
X367811Y1079791D03*
X369662Y1076587D03*
X362262Y1070178D03*
X364111Y1066974D03*
X369662Y1070178D03*
X367811Y1066974D03*
X356711Y1079791D03*
X364111D03*
X362262Y1076587D03*
X360411Y1073383D03*
X371511D03*
X364111D03*
X367811D03*
X369662Y1095813D03*
X364111Y1086200D03*
Y1092608D03*
X369662Y1089404D03*
X360411Y1092608D03*
X358562Y1082995D03*
X367811Y1086200D03*
X371511Y1092608D03*
X362262Y1095813D03*
X367811Y1092608D03*
X362262Y1089404D03*
X373362Y1082995D03*
X364111Y1099017D03*
X367811D03*
X365962Y1089404D03*
Y1082995D03*
X362261D03*
X360411Y1086200D03*
X358561Y1089404D03*
X356712Y1092608D03*
X369662Y1082995D03*
X371512Y1086200D03*
X365962Y1095813D03*
X358561D03*
X356711Y1086200D03*
X358562Y1082995D03*
X362262Y1095813D03*
X369662D03*
X362262Y1089404D03*
X364111Y1086200D03*
X369662Y1089404D03*
X367811Y1086200D03*
X360411Y1092608D03*
X367811D03*
X364111D03*
X371511D03*
X369661Y1108630D03*
X365961D03*
X367812Y1111834D03*
X362261Y1108630D03*
X360412Y1111834D03*
X358561Y1108630D03*
X364112Y1105426D03*
X358561Y1115039D03*
X369661D03*
X365961D03*
X365962Y1102221D03*
X362262D03*
X360411Y1099017D03*
X356711Y1105426D03*
Y1099017D03*
X371512Y1105426D03*
Y1099017D03*
X364112Y1111834D03*
X356712D03*
X371512D03*
X364111Y1099017D03*
X367811D03*
Y1105426D03*
X369661Y1102221D03*
X358562D03*
X360412Y1105426D03*
X358561Y1108630D03*
X360412Y1111834D03*
X364112Y1105426D03*
X369661Y1108630D03*
X362261D03*
X365961D03*
X367812Y1111834D03*
X358561Y1121447D03*
X360412Y1124651D03*
X362262Y1127856D03*
X365962Y1121447D03*
X367811Y1124651D03*
X371511D03*
X369662Y1127856D03*
X364111Y1124651D03*
X373362Y1121447D03*
X364111Y1118243D03*
X362261Y1115039D03*
X360411Y1118243D03*
X356711D03*
X367811D03*
X371511D03*
X365962Y1127856D03*
X358561D03*
Y1121447D03*
X360412Y1124651D03*
X364111D03*
X367811D03*
X371511D03*
X356712D03*
X362262Y1127856D03*
X365962Y1121447D03*
X369662Y1127856D03*
Y1121447D03*
X362261D03*
X365961Y1115039D03*
X358561D03*
X369661D03*
Y1140973D03*
X371512Y1137469D03*
X373362Y1134264D03*
X358561D03*
X365962D03*
X364112Y1137469D03*
X367812D03*
X362261Y1140973D03*
X360412Y1137469D03*
X365961Y1140973D03*
X364112Y1131060D03*
X360412D03*
X358561Y1140973D03*
X356712Y1131060D03*
X367811D03*
X371511D03*
X358561Y1134264D03*
X362261Y1140973D03*
X365962Y1134264D03*
X369661Y1140973D03*
X356712Y1137469D03*
X360412D03*
X364112D03*
X367812D03*
X371512D03*
X369662Y1134264D03*
X362262D03*
X363337Y1578088D03*
X355537Y1578182D03*
X367597D03*
X363337Y1590094D03*
X355537D03*
X367597D03*
X356577Y1602380D03*
Y1614292D03*
X368637D03*
X360837D03*
X368637Y1602286D03*
X360837Y1602380D03*
X385879Y841467D03*
X389578Y848176D03*
X387727Y844971D03*
X384027D03*
X376627D03*
X382178Y848176D03*
X380327Y844971D03*
X378479Y841467D03*
X374778Y848176D03*
X385878Y854584D03*
X378478D03*
X382179Y841467D03*
X374779D03*
X380329Y851380D03*
X376629D03*
X372929D03*
X384029D03*
X387729D03*
X385878Y848176D03*
X378478D03*
X387727Y844971D03*
X376627D03*
X380327D03*
X384027D03*
X385879Y841467D03*
X372927Y844971D03*
X374778Y848176D03*
X378479Y841467D03*
X382178Y848176D03*
X387729Y857789D03*
X382178Y860993D03*
X385878Y867401D03*
X376629Y857789D03*
X374778Y860993D03*
X384029Y857789D03*
X380329D03*
X378478Y867401D03*
X389578Y860993D03*
X387729Y870606D03*
X384029D03*
X380329D03*
X376629D03*
X382179Y854584D03*
X380329Y864197D03*
X376629D03*
X374779Y854584D03*
X372929Y864197D03*
X384029D03*
X387729D03*
X382179Y867401D03*
X374779D03*
X378478D03*
X385878D03*
X378478Y860993D03*
X385878D03*
X387729Y857789D03*
X372929D03*
X378478Y854584D03*
X380329Y857789D03*
X384029D03*
X374778Y860993D03*
X376629Y857789D03*
X382178Y860993D03*
X385878Y854584D03*
X389578Y873810D03*
X385878Y880219D03*
X387729Y883423D03*
X382178Y873810D03*
X374778D03*
X376629Y883423D03*
X380329D03*
X384029D03*
X378478Y880219D03*
X382178Y886627D03*
X374778D03*
X389578D03*
X382179Y880219D03*
X380329Y877014D03*
X376629D03*
X374779Y880219D03*
X372929Y877014D03*
X384029D03*
X387729D03*
Y870606D03*
X372929D03*
X380329D03*
X374778Y873810D03*
X376629Y870606D03*
X382178Y873810D03*
X384029Y870606D03*
X372929Y883423D03*
X378478Y880219D03*
X380329Y883423D03*
X385878Y880219D03*
X387729Y883423D03*
X376629D03*
X384029D03*
X378478Y873810D03*
X385878D03*
X374778Y893036D03*
X385878D03*
X382178D03*
X380329Y896240D03*
X376629D03*
X384029D03*
X374778Y899445D03*
X382178D03*
X389578D03*
X387729Y902649D03*
X376629D03*
X380329D03*
Y889832D03*
X378479Y893036D03*
X376629Y889832D03*
X372929D03*
X384029D03*
X387729Y896240D03*
Y889832D03*
X378478Y899445D03*
X385879D03*
X374778D03*
X382178D03*
Y893036D03*
X374778D03*
X385878D03*
X372929Y896240D03*
X380329D03*
X376629D03*
X384029D03*
X374778Y886627D03*
X382178D03*
X378478D03*
X385878D03*
Y905853D03*
X387729Y909057D03*
X389578Y912262D03*
Y905853D03*
X380329Y909057D03*
X376629D03*
X380329Y915466D03*
X382178Y912262D03*
X376629Y915466D03*
X374778Y912262D03*
X384029Y915466D03*
X382178Y918670D03*
X374778D03*
X389578D03*
X382179Y905853D03*
X378478Y912262D03*
Y905853D03*
X374778D03*
X372929Y909057D03*
X372928Y902649D03*
X385878Y912262D03*
X384028Y909057D03*
X384029Y902649D03*
X387728Y915466D03*
X376629Y902649D03*
X380329D03*
X374778Y912262D03*
X376629Y909057D03*
X382178Y912262D03*
X380329Y909057D03*
X387729D03*
Y902649D03*
X372929Y915466D03*
X385878Y905853D03*
X380329Y915466D03*
X376629D03*
X384029D03*
X376629Y928283D03*
X374778Y931488D03*
X382178D03*
X387729Y928283D03*
Y921875D03*
X380329D03*
X376629D03*
X385878Y925079D03*
X380329Y928283D03*
X389578Y931488D03*
Y925079D03*
X384029Y934691D03*
X380329D03*
X376629D03*
X382179Y925079D03*
X378478D03*
Y918670D03*
X374778Y925079D03*
X372929Y928283D03*
X372928Y921875D03*
X385879Y918670D03*
X384028Y928283D03*
X384029Y921875D03*
X378478Y931488D03*
X385878D03*
X374778D03*
X376629Y928283D03*
X382178Y931488D03*
X380329Y928283D03*
X387729Y921875D03*
X376629D03*
X374778Y918670D03*
X380329Y921875D03*
X382178Y918670D03*
X387729Y928283D03*
X385878Y925079D03*
Y944304D03*
X387729Y947509D03*
Y941100D03*
X389578Y937896D03*
Y944304D03*
X374778Y937896D03*
X376629Y947509D03*
X380329D03*
X376629Y941100D03*
X382178Y937896D03*
X380329Y941100D03*
X382178Y950713D03*
X374778D03*
X389578D03*
X384029Y941100D03*
X384028Y947509D03*
X374778Y944304D03*
X372929Y947509D03*
X372928Y941100D03*
X382179Y944304D03*
X378478D03*
Y937896D03*
X385879D03*
X387728Y934691D03*
X380329Y941100D03*
X382178Y937896D03*
X376629Y947509D03*
X380329D03*
X376629Y941100D03*
X374778Y937896D03*
X372929Y934691D03*
X380329D03*
X376629D03*
X384029D03*
X387729Y947509D03*
Y941100D03*
X385878Y944304D03*
X384029Y953917D03*
X385878Y963530D03*
X387729Y960326D03*
X374778Y957122D03*
X380329Y960326D03*
X387729Y966735D03*
X380329D03*
X376629Y953917D03*
Y966735D03*
Y960326D03*
X382178Y957122D03*
X380329Y953917D03*
X389578Y957122D03*
Y963530D03*
X387729Y953917D03*
X372928Y960326D03*
X374778Y963530D03*
X372929Y966735D03*
X382179Y963530D03*
X378478D03*
Y957122D03*
X384029Y960326D03*
X385879Y957122D03*
X384028Y966735D03*
X385878Y950713D03*
X378478D03*
X376629Y960326D03*
X374778Y957122D03*
X380329Y960326D03*
X382178Y957122D03*
X374778Y950713D03*
X382178D03*
X372929Y953917D03*
X380329D03*
X376629D03*
X384029D03*
X387729Y960326D03*
Y966735D03*
X380329D03*
X376629D03*
X385878Y963530D03*
X387729Y979552D03*
X389578Y969939D03*
Y982756D03*
X389579Y976347D03*
X385878Y982756D03*
X384029Y973143D03*
X376629Y979552D03*
X374778Y976347D03*
X382178D03*
Y969939D03*
X380329Y979552D03*
X374778Y969939D03*
X387728Y973143D03*
X376629D03*
X380328D03*
X378479Y976347D03*
X378478Y969939D03*
X385879Y976347D03*
X384029Y979552D03*
X385878Y969939D03*
X374778Y982756D03*
X382179D03*
X378478D03*
X372928Y979552D03*
X385878Y982756D03*
X387729Y979552D03*
X376629D03*
X380329D03*
X374778Y976347D03*
X382178D03*
X372929Y973143D03*
X374778Y969939D03*
X382178D03*
X384029Y973143D03*
X388162Y999684D03*
X380762D03*
X377062D03*
X375210Y996480D03*
X390011Y1002888D03*
X388162Y1012501D03*
X390011Y1009297D03*
X382611D03*
X380762Y1012501D03*
X375211Y1009297D03*
X382611Y1002888D03*
X377062Y1012501D03*
Y1006093D03*
X384462D03*
X375211Y1002888D03*
X380762Y1006093D03*
X386311Y1015705D03*
X373361Y999684D03*
X378911Y1009297D03*
Y1002888D03*
X386311Y1009297D03*
X386312Y1002888D03*
X384462Y999684D03*
X373362Y1012501D03*
X384461D03*
X373362Y1006093D03*
X380762D03*
X377062D03*
X384462D03*
X375211Y1002888D03*
X377062Y999684D03*
X382611Y1002888D03*
X380762Y999684D03*
X377062Y1012501D03*
X375211Y1009297D03*
X380762Y1012501D03*
X382611Y1009297D03*
Y1028523D03*
X377062Y1025318D03*
X382611Y1022114D03*
X377062Y1018910D03*
X380762D03*
Y1031727D03*
X375211Y1022114D03*
X384462Y1025318D03*
X380760D03*
X375211Y1028523D03*
X377062Y1031727D03*
X388162Y1018910D03*
Y1031727D03*
X390011Y1028523D03*
Y1022114D03*
X382612Y1015705D03*
X378911Y1028523D03*
Y1022114D03*
Y1015705D03*
X375211D03*
X373361Y1018910D03*
X386311Y1028523D03*
X386312Y1022114D03*
X384462Y1018910D03*
X373362Y1031727D03*
X384461D03*
X377062D03*
X375211Y1028523D03*
X380762Y1031727D03*
X382611Y1028523D03*
X375211Y1022114D03*
X377062Y1018910D03*
X382611Y1022114D03*
X380762Y1018910D03*
X377062Y1025318D03*
X384462D03*
X373360D03*
X380760D03*
X386311Y1015705D03*
Y1034931D03*
X390011Y1041340D03*
Y1047749D03*
Y1034931D03*
X388162Y1038136D03*
X382611Y1047749D03*
X375211Y1041340D03*
X382611D03*
X375211Y1047749D03*
X380762Y1038136D03*
X377062Y1044544D03*
Y1038136D03*
X384462Y1044544D03*
X380762D03*
X382612Y1034931D03*
X378911Y1041340D03*
Y1034931D03*
X375211D03*
X373361Y1038136D03*
X386312Y1041340D03*
X384462Y1038136D03*
X378911Y1047749D03*
X386311D03*
X375211D03*
X382611D03*
X375211Y1041340D03*
X377062Y1038136D03*
X382611Y1041340D03*
X380762Y1038136D03*
X373362Y1044544D03*
X380762D03*
X377062D03*
X384462D03*
X386311Y1034931D03*
Y1054157D03*
X380762Y1050952D03*
X382611Y1060565D03*
X384462Y1063770D03*
X380762D03*
X377062D03*
X375211Y1060565D03*
X380762Y1057361D03*
X377062Y1050952D03*
Y1057361D03*
X388162Y1050952D03*
Y1057361D03*
X390011Y1054157D03*
Y1060565D03*
X382612Y1054157D03*
X378911Y1060565D03*
Y1054157D03*
X375211D03*
X373361Y1057361D03*
X373362Y1050952D03*
X386312Y1060565D03*
X384462Y1057361D03*
X384461Y1050952D03*
X375211Y1060565D03*
X377062Y1057361D03*
X382611Y1060565D03*
X380762Y1057361D03*
X377062Y1050952D03*
X380762D03*
X373362Y1063770D03*
X384462D03*
X377062D03*
X380762D03*
X386311Y1054157D03*
X388162Y1070178D03*
X386311Y1073383D03*
X390011D03*
X388162Y1076587D03*
X390011Y1079791D03*
Y1066974D03*
X377062Y1076587D03*
X380762D03*
X382611Y1079791D03*
Y1066974D03*
X377062Y1070178D03*
X380762D03*
X375211Y1079791D03*
Y1066974D03*
X382612Y1073383D03*
X378911D03*
Y1066974D03*
X375211Y1073383D03*
X373361Y1076587D03*
X373362Y1070178D03*
X386311Y1066974D03*
X384462Y1076587D03*
X384461Y1070178D03*
X378911Y1079791D03*
X386311D03*
X380762Y1070178D03*
X382611Y1066974D03*
X377062Y1070178D03*
X375211Y1066974D03*
Y1079791D03*
X377062Y1076587D03*
X382611Y1079791D03*
X380762Y1076587D03*
X386311Y1073383D03*
X380762Y1082995D03*
Y1089404D03*
X377062Y1082995D03*
X382611Y1086200D03*
X377062Y1089404D03*
X384462Y1082995D03*
X386311Y1092608D03*
X375211Y1086200D03*
X388162Y1089404D03*
X390011Y1092608D03*
X388162Y1095813D03*
X390011Y1086200D03*
Y1099017D03*
X382611Y1092608D03*
X378911D03*
Y1086200D03*
X375211Y1092608D03*
X373362Y1089404D03*
X386311Y1086200D03*
X384461Y1089404D03*
X373362Y1095813D03*
X384462D03*
X377062Y1089404D03*
X375211Y1086200D03*
X380762Y1089404D03*
X382611Y1086200D03*
X373362Y1082995D03*
X386311Y1092608D03*
X384462Y1082995D03*
X377062D03*
X380762D03*
Y1095813D03*
X386311Y1111834D03*
Y1105426D03*
X382611Y1111834D03*
X378912Y1105426D03*
X377062Y1108630D03*
X375211Y1111834D03*
X384462Y1108630D03*
X378911Y1111834D03*
X375211Y1105426D03*
X382611D03*
X380762Y1102221D03*
Y1115039D03*
Y1108630D03*
X378911Y1099017D03*
X377062Y1102221D03*
X373361Y1108630D03*
Y1102221D03*
X386312Y1099017D03*
X384462Y1102221D03*
X382611Y1099017D03*
X386311Y1105426D03*
X382611Y1111834D03*
X375211Y1105426D03*
X377062Y1108630D03*
X380762Y1102221D03*
X378911Y1111834D03*
X384462Y1108630D03*
X386311Y1111834D03*
X378912Y1105426D03*
X375211Y1111834D03*
X382611Y1105426D03*
X380762Y1121447D03*
X386311Y1124651D03*
X378911D03*
X375211D03*
X382611D03*
X384462Y1127856D03*
X377062D03*
X388162Y1121447D03*
X390011Y1124651D03*
X382611Y1118243D03*
X378911D03*
X377061Y1115039D03*
X375211Y1118243D03*
X373361Y1115039D03*
X386311Y1118243D03*
X384461Y1115039D03*
X380761Y1127856D03*
X373361D03*
X375211Y1124651D03*
X378911D03*
X382611D03*
X386311D03*
X373362Y1121447D03*
X377062Y1127856D03*
X380762Y1121447D03*
X384462Y1127856D03*
Y1121447D03*
X377062D03*
X380762Y1115039D03*
X390012Y1137469D03*
X386312D03*
X388162Y1134264D03*
X380762D03*
X375212Y1137469D03*
X384461Y1140973D03*
X382612Y1137469D03*
X378912D03*
X377061Y1140973D03*
X382611Y1131060D03*
X380761Y1140973D03*
X378911Y1131060D03*
X375211D03*
X373361Y1140973D03*
X386311Y1131060D03*
X373362Y1134264D03*
X377061Y1140973D03*
X380762Y1134264D03*
X384461Y1140973D03*
X375212Y1137469D03*
X378912D03*
X382612D03*
X386312D03*
X384462Y1134264D03*
X377062D03*
X375397Y1578182D03*
Y1590094D03*
X372897Y1602380D03*
X380697D03*
X372897Y1614292D03*
X380697D03*
X404378Y848176D03*
X406227Y844971D03*
X402527D03*
X400679Y841467D03*
X396978Y848176D03*
X395127Y844971D03*
X393279Y841467D03*
X391427Y844971D03*
X398827D03*
X400678Y854584D03*
X393278D03*
X396979Y841467D03*
X389579D03*
X398829Y851380D03*
X395129D03*
X391429D03*
X402529D03*
X400678Y848176D03*
X393278D03*
X391427Y844971D03*
X395127D03*
X398827D03*
X400679Y841467D03*
X389578Y848176D03*
X393279Y841467D03*
X396978Y848176D03*
X402527Y844971D03*
X395129Y857789D03*
X398829D03*
X400678Y867401D03*
X396978Y860993D03*
X391429Y857789D03*
X393278Y867401D03*
X402529Y857789D03*
X404378Y860993D03*
X406229Y857789D03*
X402529Y870606D03*
X406229D03*
X395129D03*
X398829D03*
X391429D03*
X398829Y864197D03*
X396979Y854584D03*
X395129Y864197D03*
X391429D03*
X389579Y854584D03*
X402529Y864197D03*
X396979Y867401D03*
X389579D03*
X400678D03*
X393278D03*
X400678Y860993D03*
X393278D03*
Y854584D03*
X395129Y857789D03*
X400678Y854584D03*
X402529Y857789D03*
X389578Y860993D03*
X391429Y857789D03*
X396978Y860993D03*
X398829Y857789D03*
X402529Y883423D03*
X404378Y873810D03*
X406229Y883423D03*
X391429D03*
X396978Y873810D03*
X400678Y880219D03*
X395129Y883423D03*
X393278Y880219D03*
X398829Y883423D03*
X396978Y886627D03*
X404378D03*
X398829Y877014D03*
X396979Y880219D03*
X395129Y877014D03*
X391429D03*
X389579Y880219D03*
X402529Y877014D03*
X391429Y870606D03*
X395129D03*
X402529D03*
X389578Y873810D03*
X396978D03*
X398829Y870606D03*
X393278Y880219D03*
X395129Y883423D03*
X400678Y880219D03*
X402529Y883423D03*
X391429D03*
X398829D03*
X393278Y873810D03*
X400678D03*
X393278Y899445D03*
X395129Y902649D03*
X398829Y889832D03*
X395129Y896240D03*
Y889832D03*
X391428Y896240D03*
X391429Y889832D03*
X389579Y893036D03*
X402529Y889832D03*
X396978Y899445D03*
X402529Y896240D03*
X400678Y899445D03*
X389578D03*
X393278D03*
X396979Y893036D03*
X396978Y886627D03*
X389578D03*
X398829Y896240D03*
X400678Y893036D03*
X393278Y886627D03*
X400678D03*
X395129Y909057D03*
X396978Y905853D03*
X393278Y912262D03*
Y905853D03*
Y918670D03*
X398829Y909057D03*
X398828Y902649D03*
X396979Y912262D03*
X391429Y909057D03*
Y902649D03*
X395129Y915466D03*
X391429D03*
X400678Y905853D03*
X402529Y915466D03*
Y909057D03*
X389578Y912262D03*
X393278D03*
X395129Y909057D03*
Y902649D03*
X393278Y905853D03*
X389578D03*
X396978D03*
X400678Y912262D03*
X402529Y902649D03*
X395129Y928283D03*
X393278Y925079D03*
X395129Y921875D03*
X393278Y931488D03*
X396978Y925079D03*
X400678Y931488D03*
X402529Y928283D03*
X398829D03*
X398828Y921875D03*
X396978Y918670D03*
X391429Y928283D03*
Y921875D03*
X400678Y925079D03*
X396979Y931488D03*
X393278D03*
X395129Y928283D03*
X389578Y918670D03*
X395129Y921875D03*
X393278Y918670D03*
X389578Y931488D03*
X393278Y925079D03*
X389578D03*
X396978D03*
X395129Y947509D03*
X396978Y944304D03*
X393278D03*
Y937896D03*
X395129Y941100D03*
X393278Y950713D03*
X398829Y934691D03*
X402529D03*
X398828Y941100D03*
X396978Y937896D03*
X395129Y934691D03*
X391429Y941100D03*
Y934691D03*
X400678Y937896D03*
X398829Y947509D03*
X391429D03*
X395129D03*
X389578Y937896D03*
X395129Y941100D03*
X393278Y937896D03*
Y944304D03*
X389578D03*
X396978D03*
X402529Y941100D03*
Y947509D03*
X395129Y966735D03*
X393278Y957122D03*
Y963530D03*
X396978D03*
X395129Y960326D03*
X398828D03*
X396978Y957122D03*
X396979Y950713D03*
X395129Y953917D03*
X391429Y960326D03*
Y953917D03*
X400678Y957122D03*
X398829Y966735D03*
X391429D03*
X400678Y963530D03*
X389578Y957122D03*
X395129Y960326D03*
X393278Y957122D03*
X395129Y966735D03*
X389578Y950713D03*
X393278D03*
X396978Y963530D03*
X393278D03*
X389578D03*
X398829Y953917D03*
X402529D03*
X400680Y950713D03*
X402529Y979552D03*
Y973143D03*
X393278Y969939D03*
X396978Y982756D03*
X393278D03*
X398829Y973143D03*
X400678Y976347D03*
X395129Y979552D03*
X393278Y976347D03*
X398828Y979552D03*
X396978Y976347D03*
X396979Y969939D03*
X395129Y973143D03*
X391429Y979552D03*
Y973143D03*
X400678Y982756D03*
Y969939D03*
X398829Y973143D03*
X400678Y976347D03*
X402529Y979552D03*
Y973143D03*
X393278Y982756D03*
X389578D03*
X396978D03*
X393278Y976347D03*
X395129Y979552D03*
X389579Y976347D03*
X389578Y969939D03*
X393278D03*
X395562Y999684D03*
X393711Y1009297D03*
X395562Y1012501D03*
X393711Y1002888D03*
X397411Y1015705D03*
X397412Y1009297D03*
X397411Y1002888D03*
X395562Y1006093D03*
X391862D03*
Y999684D03*
X388161Y1006093D03*
X401111Y1002888D03*
X399262Y1012501D03*
X391861D03*
X399262Y1006093D03*
X402962D03*
X390011Y1002888D03*
X388162Y999684D03*
X393711Y1002888D03*
X395562Y999684D03*
X399262D03*
X402962D03*
X388162Y1012501D03*
X395562D03*
X390011Y1009297D03*
X393711D03*
X401111D03*
X402962Y1012501D03*
X393711Y1028523D03*
X395562Y1018910D03*
X393711Y1022114D03*
X395562Y1031727D03*
X402962D03*
X399261Y1018910D03*
X397411Y1028523D03*
Y1022114D03*
X395562Y1025318D03*
X393711Y1015705D03*
X391862Y1025318D03*
Y1018910D03*
X390012Y1015705D03*
X388161Y1025318D03*
X399262Y1031727D03*
X391862D03*
X397411Y1015705D03*
X388162Y1031727D03*
X390011Y1028523D03*
X395562Y1031727D03*
X393711Y1028523D03*
X390011Y1022114D03*
X388162Y1018910D03*
X393711Y1022114D03*
X395562Y1018910D03*
X401111Y1022114D03*
X402960Y1018910D03*
X402962Y1025318D03*
X399262D03*
X401111Y1015705D03*
X397411Y1034931D03*
X395562Y1038136D03*
X393711Y1041340D03*
Y1047749D03*
Y1034931D03*
X399261Y1038136D03*
X397411Y1041340D03*
X395562Y1044544D03*
X391862D03*
Y1038136D03*
X388161Y1044544D03*
X397411Y1047749D03*
X390011Y1041340D03*
X388162Y1038136D03*
X393711Y1041340D03*
X395562Y1038136D03*
X390011Y1047749D03*
X393711D03*
Y1034931D03*
X390011D03*
X397411D03*
X401111Y1047749D03*
X399262Y1044544D03*
X402962D03*
X401111Y1041340D03*
X402962Y1038136D03*
X395562Y1057361D03*
X393711Y1054157D03*
Y1060565D03*
X397411Y1054157D03*
X395562Y1050952D03*
X399261Y1057361D03*
X399262Y1050952D03*
X397411Y1060565D03*
X391862Y1057361D03*
Y1050952D03*
X395562Y1063770D03*
X391862D03*
X388161D03*
X390011Y1060565D03*
X388162Y1057361D03*
X393711Y1060565D03*
X395562Y1057361D03*
X388162Y1050952D03*
X395562D03*
X393711Y1054157D03*
X390011D03*
X397411D03*
X402962Y1057361D03*
X401113Y1060565D03*
X399262Y1063770D03*
X402962Y1050952D03*
X395562Y1076587D03*
X397411Y1073383D03*
X395562Y1070178D03*
X393711Y1073383D03*
Y1079791D03*
Y1066974D03*
X402962Y1076587D03*
Y1070178D03*
X399261Y1076587D03*
X399262Y1070178D03*
X397412Y1066974D03*
X391862Y1076587D03*
Y1070178D03*
X401111Y1073383D03*
X397411Y1079791D03*
X401111D03*
X390011D03*
X388162Y1076587D03*
X393711Y1079791D03*
X395562Y1076587D03*
X388162Y1070178D03*
X390011Y1066974D03*
X395562Y1070178D03*
X393711Y1066974D03*
Y1073383D03*
X390011D03*
X397411D03*
X401112Y1066974D03*
X393711Y1086200D03*
X395562Y1095813D03*
X393711Y1092608D03*
X402961Y1089404D03*
X402962Y1082995D03*
X397411Y1092608D03*
X395562Y1089404D03*
X404811Y1086200D03*
Y1099017D03*
X401111D03*
X393711D03*
X399262Y1089404D03*
X397412Y1086200D03*
X395562Y1082995D03*
X391862Y1089404D03*
Y1082995D03*
X388161D03*
X401112Y1092608D03*
X401111Y1086200D03*
X399261Y1095813D03*
X391862D03*
X402962D03*
X395562D03*
X388162Y1089404D03*
X390011Y1086200D03*
X395562Y1089404D03*
X393711Y1086200D03*
X388162Y1095813D03*
X393711Y1092608D03*
X390011D03*
X397411D03*
X399262Y1082995D03*
X402962D03*
X402961Y1089404D03*
X402962Y1102221D03*
Y1108630D03*
X391862D03*
X399262D03*
X395562D03*
X393711Y1111834D03*
X401111D03*
X397411Y1105426D03*
X402962Y1115039D03*
X399262D03*
X391862D03*
X399262Y1102221D03*
X397412Y1099017D03*
X395562Y1102221D03*
X390011Y1105426D03*
X388162Y1108630D03*
Y1102221D03*
X401111Y1105426D03*
X397411Y1111834D03*
X390011D03*
X393711Y1099017D03*
X390011D03*
X391862Y1102221D03*
X393711Y1105426D03*
X401111Y1099017D03*
X391862Y1108630D03*
X393711Y1111834D03*
X397411Y1105426D03*
X402962Y1108630D03*
Y1102221D03*
X395562Y1108630D03*
X399262D03*
X401111Y1111834D03*
X399262Y1127856D03*
X401111Y1124651D03*
X402962Y1121447D03*
X391862Y1127856D03*
X395562Y1121447D03*
X393711Y1124651D03*
X397411D03*
X404811D03*
X397411Y1118243D03*
X395561Y1115039D03*
X393711Y1118243D03*
X390011D03*
X388161Y1115039D03*
X401111Y1118243D03*
X395561Y1127856D03*
X388161D03*
X402961D03*
X390011Y1124651D03*
X395562Y1121447D03*
X397411Y1124651D03*
X401111D03*
X391862Y1127856D03*
X393711Y1124651D03*
X399262Y1127856D03*
X402962Y1121447D03*
X388162D03*
X391862D03*
X399262Y1115039D03*
X391862D03*
X402962D03*
X399262Y1121447D03*
X404812Y1137469D03*
X402962Y1134264D03*
X395562D03*
X393712Y1137469D03*
X397412D03*
X399261Y1140973D03*
X391861D03*
X401112Y1137469D03*
X397411Y1131060D03*
X395561Y1140973D03*
X393711Y1131060D03*
X390011D03*
X388161Y1140973D03*
X402961D03*
X401111Y1131060D03*
X391861Y1140973D03*
X395562Y1134264D03*
X399261Y1140973D03*
X402962Y1134264D03*
X388162D03*
X390012Y1137469D03*
X393712D03*
X397412D03*
X401112D03*
X391862Y1134264D03*
X399262D03*
X419178Y848176D03*
X421027Y844971D03*
X409927D03*
X417327D03*
X413627D03*
X411778Y848176D03*
X415479Y841467D03*
X408079D03*
X408078Y854584D03*
X415478D03*
X419179Y841467D03*
X404379D03*
X411779D03*
X413629Y851380D03*
X409929D03*
X406229D03*
X417329D03*
X408078Y848176D03*
X415478D03*
X406227Y844971D03*
X409927D03*
X413627D03*
X417327D03*
X404378Y848176D03*
X408079Y841467D03*
X411778Y848176D03*
X415479Y841467D03*
X419178Y848176D03*
Y860993D03*
X415478Y867401D03*
X408078D03*
X409929Y857789D03*
X417329D03*
X411778Y860993D03*
X413629Y857789D03*
X421029D03*
Y870606D03*
X417329D03*
X413629D03*
X404379Y854584D03*
X413629Y864197D03*
X411779Y854584D03*
X409929Y864197D03*
X406229D03*
X419179Y854584D03*
X417329Y864197D03*
X404379Y867401D03*
X411779D03*
X419179D03*
X408078D03*
X415478D03*
Y860993D03*
X408078D03*
Y854584D03*
X409929Y857789D03*
X415478Y854584D03*
X417329Y857789D03*
X404378Y860993D03*
X406229Y857789D03*
X411778Y860993D03*
X413629Y857789D03*
X419178Y860993D03*
Y873810D03*
X421029Y883423D03*
X417329D03*
X413629D03*
X415478Y880219D03*
X409929Y883423D03*
X411778Y873810D03*
X408078Y880219D03*
X411778Y886627D03*
X419178D03*
X404379Y880219D03*
X413629Y877014D03*
X411779Y880219D03*
X409929Y877014D03*
Y870606D03*
X406229Y877014D03*
X419179Y880219D03*
X417329Y877014D03*
X404378Y873810D03*
X406229Y870606D03*
X408078Y880219D03*
X409929Y883423D03*
X406229D03*
X419178Y873810D03*
X417329Y870606D03*
X411778Y873810D03*
X413629Y870606D03*
X417329Y883423D03*
X415478Y880219D03*
X413629Y883423D03*
X415478Y873810D03*
X408078D03*
X413629Y889832D03*
X411779Y893036D03*
X409929Y889832D03*
X408079Y893036D03*
X406229Y889832D03*
X419179Y893036D03*
X417329Y889832D03*
X404378Y886627D03*
X411778D03*
X419178D03*
X404378Y893036D03*
X415478Y886627D03*
X408078D03*
X406229Y896240D03*
X408078Y899445D03*
X415478D03*
X417329Y896240D03*
X411778Y899445D03*
X413629Y896240D03*
Y902649D03*
X409929Y909057D03*
Y902649D03*
X404378Y912262D03*
Y905853D03*
X419178Y912262D03*
X419179Y905853D03*
X417329Y902649D03*
X409929Y915466D03*
X417329Y909057D03*
X406229D03*
X413629D03*
Y915466D03*
X411778Y905853D03*
X408078D03*
Y912262D03*
X406229Y902649D03*
X415478Y905853D03*
X411778Y912262D03*
X415478D03*
X417329Y915466D03*
X406229Y921875D03*
X409929D03*
X404378Y918670D03*
X418229Y926896D03*
X419178Y918670D03*
X405048Y930812D03*
X408078Y918670D03*
X408569Y929108D03*
X406308Y928626D03*
X417329Y921875D03*
X411872Y925264D03*
X415479Y918670D03*
X405145Y946239D03*
Y948539D03*
X414093Y942098D03*
X405048Y938046D03*
Y935746D03*
X416393Y942098D03*
X418693D03*
X407589Y942164D03*
X405289D03*
X409889D03*
X405122Y965896D03*
Y963596D03*
X415185Y956620D03*
X411685D03*
X409385D03*
X417685D03*
X414365Y971140D03*
X416755D03*
X404861Y981269D03*
Y978969D03*
X404785Y971100D03*
X407085D03*
X409385D03*
X411685D03*
X420205D03*
X404861Y986421D03*
X405101Y992971D03*
Y995271D03*
X404861Y988721D03*
X415185Y985580D03*
X417575D03*
X412365Y985610D03*
X410065D03*
X420145Y985550D03*
X415185Y1014540D03*
X417575D03*
X405227Y1007156D03*
X405231Y1004848D03*
X417575Y1000060D03*
X415185D03*
X409385Y1014540D03*
X407085D03*
X411685D03*
X412385Y1000080D03*
X410085D03*
X420215Y1000040D03*
X420405Y1014470D03*
X404986Y1022427D03*
X404998Y1026821D03*
X414461Y1028855D03*
X411961D03*
X416961D03*
X419461D03*
X408325Y1031971D03*
Y1034271D03*
X408511Y1041340D03*
X417762Y1044544D03*
X412211Y1047749D03*
X404811D03*
X419611D03*
X406662Y1044544D03*
X410362D03*
X414062D03*
X404811Y1041340D03*
X412211D03*
X415911D03*
X419611D03*
X406662Y1050952D03*
X415911Y1060565D03*
Y1054157D03*
X412211Y1060565D03*
X410361Y1050952D03*
X408511Y1054157D03*
X404811Y1060565D03*
X417761Y1050952D03*
X414060D03*
X419611Y1054157D03*
X406662Y1063770D03*
X408511Y1060565D03*
X410362Y1063770D03*
X412211Y1054157D03*
X404811D03*
X414062Y1057361D03*
X410362D03*
X414062Y1063770D03*
X419611Y1060565D03*
X408511Y1079791D03*
X419611D03*
X408511Y1073383D03*
X406662Y1070178D03*
X404811Y1073383D03*
X415911Y1066974D03*
X410362Y1076587D03*
Y1070178D03*
X406661Y1076587D03*
X404811Y1066974D03*
X419611Y1073383D03*
X412211Y1079791D03*
X404811D03*
X408511Y1066974D03*
X415911Y1079791D03*
Y1073383D03*
X414062Y1070178D03*
X419611Y1066974D03*
X408511Y1079791D03*
X419611Y1086200D03*
Y1092608D03*
X406662Y1089404D03*
X410362D03*
X408511Y1092608D03*
X414062Y1089404D03*
X412211Y1086200D03*
X414062Y1082995D03*
X410362D03*
X406662D03*
X421462Y1089404D03*
X408511Y1099017D03*
X415911Y1092608D03*
X415912Y1086200D03*
X412211Y1092608D03*
X408511Y1086200D03*
X417761Y1089404D03*
Y1082995D03*
X410362Y1095813D03*
X406662D03*
X404811Y1092608D03*
X417762Y1095813D03*
X406662Y1089404D03*
X410362D03*
X404811Y1086200D03*
X419611D03*
X414062Y1082995D03*
X410362D03*
X406662D03*
X408511Y1092608D03*
X414062Y1089404D03*
X419611Y1092608D03*
X412211Y1086200D03*
X419611Y1111834D03*
Y1105426D03*
X415911D03*
X412211D03*
X410362Y1108630D03*
X417762D03*
X415911Y1111834D03*
X412211D03*
X408511Y1105426D03*
X414062Y1102221D03*
X408511Y1111834D03*
X414062Y1115039D03*
X415912Y1099017D03*
X414062Y1108630D03*
X412211Y1099017D03*
X410362Y1102221D03*
X406661Y1108630D03*
Y1102221D03*
X404812Y1105426D03*
X417762Y1102221D03*
X404812Y1111834D03*
X404811Y1099017D03*
X408511Y1105426D03*
X412211Y1111834D03*
X415911D03*
X414062Y1102221D03*
X417762Y1108630D03*
X419611Y1105426D03*
X408511Y1099017D03*
X410362Y1108630D03*
X408511Y1111834D03*
X412211Y1105426D03*
X419611Y1111834D03*
X415911Y1105426D03*
X410362Y1121447D03*
X408511Y1124651D03*
X406662Y1127856D03*
X415911Y1118243D03*
X414061Y1121447D03*
X412211Y1124651D03*
Y1118243D03*
X410361Y1115039D03*
X408511Y1118243D03*
X406661Y1115039D03*
X404811Y1118243D03*
X417761Y1115039D03*
X410361Y1127856D03*
X404811Y1124651D03*
X408511D03*
X406662Y1127856D03*
X410362Y1121447D03*
X415912Y1124651D03*
X419612D03*
Y1118243D03*
X417761Y1121447D03*
Y1127856D03*
X414062Y1115039D03*
X406661Y1121447D03*
X414062Y1127856D03*
X410362Y1134264D03*
X406661Y1140973D03*
X408512Y1137469D03*
X414062Y1134264D03*
X412212Y1131060D03*
X410361Y1140973D03*
X408511Y1131060D03*
X404811D03*
X406661Y1140973D03*
X410362Y1134264D03*
X404812Y1137469D03*
X408512D03*
X406662Y1134264D03*
X415912Y1137469D03*
Y1131060D03*
X414061Y1140973D03*
X419612Y1137469D03*
Y1131060D03*
X417761Y1134264D03*
Y1140973D03*
X412212Y1137469D03*
X435829Y844671D03*
X437678Y848176D03*
X433978D03*
X428427Y844971D03*
X426578Y848176D03*
X430278D03*
X424727Y844971D03*
X422879Y841467D03*
X430278Y854584D03*
X422878D03*
X437679D03*
X432128Y844671D03*
X426579Y841467D03*
X432129Y851380D03*
X428429D03*
X424729D03*
X421029D03*
X435829D03*
X422878Y848176D03*
X421027Y844971D03*
X424727D03*
X428427D03*
X433978Y848176D03*
X435829Y844671D03*
X422879Y841467D03*
X426578Y848176D03*
X430278D03*
X422878Y867401D03*
X433979Y860993D03*
X432129Y857789D03*
X424729D03*
X428429D03*
X435829D03*
X430278Y867401D03*
X426578Y860993D03*
X437678Y867401D03*
X435829Y870606D03*
X428429D03*
X424729D03*
X432129D03*
Y864197D03*
X428429D03*
X426579Y854584D03*
X424729Y864197D03*
X421029D03*
X433979Y854584D03*
X435829Y864197D03*
X426579Y867401D03*
X433979D03*
X430278D03*
X422878D03*
X430278Y860993D03*
X422878D03*
Y854584D03*
X424729Y857789D03*
X430278Y854584D03*
X433979Y860993D03*
X421029Y857789D03*
X426578Y860993D03*
X428429Y857789D03*
X432129D03*
X435829D03*
X437678Y880219D03*
X435829Y883423D03*
X433979Y873810D03*
X426578D03*
X424729Y883423D03*
X428429D03*
X432129D03*
X430278Y880219D03*
X422878D03*
X426578Y886627D03*
X433978D03*
X432129Y877014D03*
X428429D03*
X426579Y880219D03*
X424729Y877014D03*
X421029D03*
X433979Y880219D03*
X435829Y877014D03*
X432129Y870606D03*
X426578Y873810D03*
X424729Y870606D03*
X433979Y873810D03*
X428429Y870606D03*
X421029D03*
X435829D03*
X432129Y883423D03*
X430278Y880219D03*
X424729Y883423D03*
X422878Y880219D03*
X428429Y883423D03*
X421029D03*
X435829D03*
X422878Y873810D03*
X430278D03*
X432129Y889832D03*
X428429D03*
X426579Y893036D03*
X424729Y889832D03*
X421029D03*
X433979Y893036D03*
X435829Y889832D03*
X433978Y886627D03*
X426578D03*
X422878D03*
X430278D03*
Y899445D03*
X422878D03*
X424729Y896240D03*
X432129D03*
X421029D03*
X428429D03*
X435829D03*
X424729Y915466D03*
X426578Y912262D03*
X424729Y902649D03*
X432129D03*
X428429Y909057D03*
Y902649D03*
X421029D03*
X435829D03*
X428429Y915466D03*
X430278Y912262D03*
X432129Y915466D03*
X421029Y909057D03*
X435829D03*
Y915466D03*
X432128Y909057D03*
X424728D03*
X422878Y905853D03*
X430278D03*
X421029Y915466D03*
X433979Y912262D03*
X430278Y918670D03*
X433980Y925079D03*
Y931487D03*
X428429Y921875D03*
X432129D03*
X433979Y918670D03*
X435829Y921875D03*
X424927Y927255D03*
X423176Y929465D03*
X422427Y927255D03*
X425676Y929465D03*
X424729Y921875D03*
X422878Y918670D03*
X421029Y921875D03*
X426578Y918670D03*
X432130Y928283D03*
X430279Y931487D03*
Y937897D03*
X433979D03*
X426875Y947199D03*
Y949499D03*
X427875Y936470D03*
X433980Y944305D03*
X427875Y941930D03*
Y944230D03*
X430280Y944305D03*
X432130Y941101D03*
X435830D03*
X432129Y947510D03*
X435830D03*
Y934692D03*
X426905Y965935D03*
Y963635D03*
X433980Y957123D03*
Y950714D03*
Y963531D03*
X427875Y956373D03*
Y954073D03*
X422685Y956620D03*
X425185D03*
X430280Y957123D03*
X432129Y960327D03*
Y953918D03*
X430280Y950714D03*
X435830Y960327D03*
Y953918D03*
X432129Y966736D03*
X430280Y963531D03*
X435830Y966736D03*
X426905Y980336D03*
Y978036D03*
X433980Y976348D03*
Y969940D03*
Y982757D03*
X430268Y976348D03*
X432129Y973144D03*
X430280Y969940D03*
X427875Y971267D03*
X422685Y971100D03*
X427875Y968967D03*
X435830Y973144D03*
X430280Y982757D03*
X432129Y979553D03*
X427875Y983111D03*
X435830Y979553D03*
X426905Y994722D03*
Y992422D03*
X422685Y985580D03*
X427875Y985411D03*
Y997521D03*
X426905Y1006875D03*
Y1009175D03*
X434411Y1009298D03*
X434412Y1002889D03*
X430712Y1009298D03*
X427875Y1012152D03*
X430712Y1002889D03*
X427875Y999821D03*
X422685Y1000060D03*
X436263Y1006094D03*
Y999685D03*
X432562Y1006094D03*
Y999685D03*
X427875Y1014452D03*
X423015Y1014470D03*
X436263Y1012502D03*
X432562D03*
X426905Y1021963D03*
Y1019663D03*
X434411Y1028524D03*
Y1022115D03*
X434412Y1015706D03*
X421961Y1028855D03*
X430712Y1022115D03*
Y1015706D03*
X427875Y1026704D03*
X430712Y1028524D03*
X436263Y1018911D03*
X432562D03*
Y1025319D03*
X436263D03*
X427875Y1029004D03*
Y1031304D03*
X436263Y1031728D03*
X432562D03*
X428862Y1044544D03*
X434412Y1034932D03*
X430712Y1047749D03*
X423311D03*
X427011D03*
X423312Y1041340D03*
X425162Y1044544D03*
X423285Y1036884D03*
X430711Y1041340D03*
X430712Y1034932D03*
X427875Y1033604D03*
X423285Y1032284D03*
Y1034584D03*
X436262Y1038137D03*
X436261Y1044544D03*
X432562Y1038137D03*
X434412Y1041340D03*
X432561Y1044544D03*
X434412Y1047749D03*
X421462Y1044544D03*
X427011Y1054157D03*
X430711D03*
X425162Y1057361D03*
X432561Y1050952D03*
X434411Y1060565D03*
Y1054157D03*
X421462Y1063770D03*
X428861Y1057361D03*
X421462D03*
X425162Y1050952D03*
X423311Y1054157D03*
X436262Y1057361D03*
Y1050952D03*
Y1063770D03*
X425162D03*
X427011Y1060565D03*
X430711D03*
Y1079791D03*
X428861Y1076587D03*
X423311Y1073383D03*
X421462Y1076587D03*
X430711Y1073383D03*
X427011D03*
Y1066974D03*
X425162Y1076587D03*
X423311Y1066974D03*
X432561Y1076587D03*
X434411Y1073383D03*
Y1066974D03*
X427012Y1079791D03*
X434411D03*
X423311D03*
X436262Y1070178D03*
Y1076587D03*
X421462Y1070178D03*
X428862D03*
X430711Y1066974D03*
X428861Y1076587D03*
X430711Y1079791D03*
X423311Y1092608D03*
X427011D03*
X430710Y1086200D03*
X425162Y1095813D03*
X430711Y1092608D03*
X423311Y1086200D03*
X428861Y1089404D03*
X427012Y1086200D03*
X425162Y1082995D03*
X428861D03*
X425162Y1089404D03*
X421462Y1082995D03*
X432561Y1089404D03*
Y1082995D03*
X434411Y1092608D03*
Y1086200D03*
X428861Y1095813D03*
X421462D03*
X432561D03*
X436262Y1082995D03*
Y1089404D03*
X436261Y1095813D03*
X421462Y1089404D03*
X423311Y1092608D03*
X427011D03*
X430710Y1086200D03*
X425162Y1082995D03*
Y1095813D03*
X430711Y1092608D03*
X423311Y1086200D03*
X428861Y1089404D03*
X427012Y1086200D03*
X427011Y1099017D03*
X425161Y1102221D03*
X423311Y1105426D03*
X421462Y1108630D03*
X434411Y1105426D03*
X423311Y1111834D03*
X434411D03*
X421462Y1102221D03*
X423311Y1099017D03*
X428861Y1108630D03*
X427012Y1105426D03*
X425162Y1108630D03*
X430711Y1105426D03*
Y1099017D03*
X428861Y1102221D03*
X436262Y1108630D03*
Y1102221D03*
X432561Y1108630D03*
Y1102221D03*
X434412Y1099017D03*
X430711Y1111834D03*
X427012D03*
X423311Y1124651D03*
Y1118243D03*
X421462Y1115039D03*
X434411Y1124651D03*
Y1118243D03*
X430711Y1124651D03*
X428861Y1121447D03*
X427012Y1124651D03*
X425162Y1121447D03*
X421461D03*
X430711Y1118243D03*
X428861Y1115039D03*
X427012Y1118243D03*
X425162Y1115039D03*
X436262Y1121447D03*
Y1115039D03*
X432561Y1121447D03*
Y1115039D03*
X428861Y1127856D03*
X425162D03*
X421461D03*
X436262D03*
X432561D03*
X423312Y1137469D03*
X423311Y1131060D03*
X434412Y1137769D03*
X434411Y1131060D03*
X430711Y1137769D03*
X427012Y1137569D03*
X430711Y1131060D03*
X428861Y1134264D03*
X427012Y1131060D03*
X425162Y1134264D03*
X421461D03*
X428861Y1140973D03*
X425161D03*
X421461D03*
X436261Y1134264D03*
X432561D03*
X452479Y841467D03*
X450628Y844971D03*
X454327D03*
X448778Y848176D03*
X443227Y844671D03*
X446927D03*
X445078Y854584D03*
X452478D03*
Y848176D03*
X445078D03*
X441378D03*
X439529Y844671D03*
X446929Y851380D03*
X443228D03*
X439529D03*
X450629D03*
X450628Y844971D03*
X446927Y844671D03*
X452479Y841467D03*
X448778Y848176D03*
X443227Y844671D03*
X437678Y848176D03*
X448779Y860993D03*
X450629Y857789D03*
X441378Y860993D03*
X446929Y857789D03*
X445078Y867401D03*
X452478D03*
X443229Y857789D03*
X454329D03*
Y870606D03*
X450629D03*
X443229D03*
X439529D03*
X446929D03*
X448779Y854584D03*
X446929Y864197D03*
X443229D03*
X441379Y854584D03*
X439529Y864197D03*
X439528Y857789D03*
X437680Y860992D03*
X450629Y864197D03*
X448779Y867401D03*
X441379D03*
X452478D03*
X445078D03*
X437678D03*
X445078Y860993D03*
X452479D03*
X437679Y854584D03*
X452478D03*
X450629Y857789D03*
X445078Y854584D03*
X443229Y857789D03*
X448779Y860993D03*
X446929Y857789D03*
X441378Y860993D03*
X454329Y883423D03*
X452479Y880219D03*
X450629Y883423D03*
X439529D03*
X446929D03*
X445078Y880219D03*
X443229Y883423D03*
X448779Y873810D03*
X441378D03*
Y886627D03*
X448778D03*
X448779Y880219D03*
X446929Y877014D03*
X443229D03*
X441379Y880219D03*
X439529Y877014D03*
X450629D03*
X448779Y873810D03*
X446929Y870606D03*
X441378Y873810D03*
X439529Y870606D03*
X450629D03*
X443229D03*
X452479Y880219D03*
X446929Y883423D03*
X445078Y880219D03*
X439529Y883423D03*
X437678Y880219D03*
X450629Y883423D03*
X443229D03*
X437679Y873810D03*
X452479D03*
X445078D03*
X448779Y893036D03*
X446929Y889832D03*
X443229D03*
X441379Y893036D03*
X439529Y896240D03*
Y889832D03*
X437678Y886627D03*
X450629Y889832D03*
X437679Y899445D03*
X448778Y886627D03*
X441378D03*
X452478D03*
X445078D03*
X452478Y899445D03*
X446929Y896240D03*
X445078Y899445D03*
X443229Y896240D03*
X450630D03*
X446929Y909057D03*
Y902649D03*
X443229D03*
X439528D03*
X437678Y912262D03*
X437679Y905853D03*
X450629Y902649D03*
X446929Y915466D03*
X443229Y909057D03*
X439529Y915466D03*
X441379Y905853D03*
X450630Y909057D03*
X448779Y905853D03*
X439529Y909057D03*
X445080Y912262D03*
X443229Y915466D03*
X450629D03*
X452478Y912262D03*
X439529Y921875D03*
X446930Y928283D03*
X441379Y925079D03*
Y931487D03*
X446929Y921875D03*
X437678Y918670D03*
X441378D03*
X450629Y921875D03*
X445078Y918670D03*
X443229Y921875D03*
X452478Y918670D03*
X448780Y931487D03*
X437679D03*
X448780Y925079D03*
X445079Y931487D03*
Y925079D03*
X439530Y928283D03*
X437679Y925079D03*
X441379Y937897D03*
X445079D03*
X437679D03*
X448779D03*
X446929Y941101D03*
X446930Y947510D03*
X437680Y944305D03*
X441380D03*
X443230Y941101D03*
X445079Y944305D03*
X439530Y941101D03*
X450630D03*
X448780Y944305D03*
X443229Y947510D03*
X439529D03*
X450630D03*
X443230Y934692D03*
X446930Y960327D03*
Y953918D03*
Y966736D03*
X445079Y957123D03*
X437680D03*
X441380D03*
X439529Y960327D03*
X443229D03*
Y953918D03*
X439529D03*
X437680Y950714D03*
X441380D03*
X445079D03*
X448780Y957123D03*
X450630Y953918D03*
Y960327D03*
X448780Y950714D03*
X445079Y963531D03*
X437680D03*
X441380D03*
X439529Y966736D03*
X443229D03*
X448780Y963531D03*
X450630Y966736D03*
X446930Y979553D03*
Y973144D03*
X445079Y976348D03*
Y969940D03*
X439529Y973144D03*
X443229D03*
X437680Y976348D03*
X441380D03*
X437680Y969940D03*
X441380D03*
X450630Y973144D03*
X448780Y976348D03*
Y969940D03*
X445079Y982757D03*
X437680D03*
X441380D03*
X439529Y979553D03*
X443229D03*
X448780Y982757D03*
X450630Y979553D03*
X447362Y1006094D03*
Y999685D03*
Y1012502D03*
X439962Y1006094D03*
X443662D03*
X445511Y1009298D03*
X438113D03*
X441813D03*
X445512Y1002889D03*
X438113D03*
X441813D03*
X439962Y999685D03*
X443662D03*
X451062Y1006094D03*
X449213Y1009298D03*
Y1002889D03*
X451062Y999685D03*
X439962Y1012502D03*
X443662D03*
X451062D03*
X447362Y1025319D03*
Y1018911D03*
Y1031728D03*
X445511Y1022115D03*
X438113D03*
X441813D03*
X445512Y1015706D03*
X438113D03*
X439962Y1018911D03*
X441813Y1015706D03*
X443662Y1018911D03*
Y1025319D03*
X439962D03*
X445511Y1028524D03*
X441813D03*
X438113D03*
X449213Y1022115D03*
X451062Y1018911D03*
X449213Y1015706D03*
X451062Y1025319D03*
X449213Y1028524D03*
X439962Y1031728D03*
X443662D03*
X451062D03*
X447360Y1038136D03*
X452911Y1041340D03*
X451061Y1044544D03*
X449211Y1047749D03*
X452911D03*
X439962Y1038137D03*
X443662D03*
X438112Y1041340D03*
X439961Y1044544D03*
X441812Y1041340D03*
X443661Y1044544D03*
X447361D03*
X445511Y1041340D03*
X445512Y1034932D03*
X438113D03*
X441813D03*
X451062Y1038137D03*
X449211Y1041340D03*
X449213Y1034932D03*
X445510Y1047749D03*
X441812D03*
X438112D03*
X447361Y1057361D03*
Y1050952D03*
X452911Y1060565D03*
X447361Y1063770D03*
X438112Y1060565D03*
Y1054157D03*
X439961Y1057361D03*
X441812Y1054157D03*
Y1060565D03*
X443661Y1057361D03*
X445511Y1060565D03*
Y1054157D03*
X439961Y1050952D03*
X443661D03*
X439961Y1063770D03*
X443661D03*
X451061D03*
X452911Y1054157D03*
X451062Y1050952D03*
Y1057361D03*
X452911Y1073383D03*
X447361Y1076587D03*
Y1070178D03*
X449211Y1073383D03*
X452911Y1079791D03*
X449211D03*
X439961Y1076587D03*
Y1070178D03*
X441812Y1073383D03*
X438112D03*
X443661Y1070178D03*
Y1076587D03*
X445511Y1073383D03*
X441812Y1066974D03*
X438112D03*
X445511D03*
X441812Y1079791D03*
X438112D03*
X445511D03*
X452911Y1066974D03*
X449211D03*
X447361Y1082995D03*
X452911Y1092608D03*
X451062Y1089404D03*
X449212Y1086200D03*
X451062Y1095813D03*
X452911Y1086200D03*
X443661Y1082995D03*
X439961D03*
X441812Y1086200D03*
X445511D03*
X439961Y1089404D03*
X441812Y1092608D03*
X438112D03*
X443661Y1089404D03*
X445511Y1092608D03*
X447361Y1089404D03*
X438112Y1086200D03*
X449211Y1092608D03*
X439961Y1095813D03*
X443661D03*
X447361D03*
X451060Y1082995D03*
X447361Y1108630D03*
Y1102221D03*
X452911Y1099017D03*
X441812Y1105426D03*
X438112D03*
X439961Y1108630D03*
X443661D03*
X445511Y1105426D03*
X439961Y1102221D03*
X441812Y1099017D03*
X438112D03*
X443661Y1102221D03*
X445511Y1099017D03*
X452912Y1105426D03*
X451061Y1108630D03*
X449212Y1105426D03*
X451061Y1102221D03*
X449212Y1099017D03*
X441812Y1111834D03*
X438112D03*
X445511D03*
X452912D03*
X449212D03*
X447361Y1121447D03*
Y1115039D03*
Y1127856D03*
X438112Y1124651D03*
X439961Y1121447D03*
X441812Y1124651D03*
X445511D03*
X443661Y1121447D03*
X438112Y1118243D03*
X441812D03*
X439961Y1115039D03*
X445511Y1118243D03*
X443661Y1115039D03*
X452912Y1124651D03*
Y1118243D03*
X451061Y1121447D03*
X449212Y1124651D03*
Y1118243D03*
X451061Y1115039D03*
X439961Y1127856D03*
X443661D03*
X451061D03*
X447361Y1134264D03*
X441812Y1137769D03*
X438112D03*
X445511D03*
X443661Y1134264D03*
X441812Y1131060D03*
X439961Y1134264D03*
X438112Y1131060D03*
X445511D03*
X452912Y1137769D03*
Y1131060D03*
X449212Y1137769D03*
Y1131060D03*
X451061Y1134264D03*
X467279Y841467D03*
X469127Y844971D03*
X470978Y848176D03*
X456178D03*
X461727Y844971D03*
X459879Y841467D03*
X463578Y848176D03*
X465427Y844971D03*
X458027D03*
X467278Y854584D03*
X459878D03*
X461729Y851380D03*
X458029D03*
X454328D03*
X456179Y841467D03*
X463579D03*
X469129Y851380D03*
X465429D03*
X459878Y848176D03*
X467278D03*
X467279Y841467D03*
X463578Y848176D03*
X459879Y841467D03*
X458027Y844971D03*
X454327D03*
X469127D03*
X465427D03*
X461727D03*
X456178Y848176D03*
X461729Y857789D03*
X456178Y860993D03*
X465429Y857789D03*
X459878Y867401D03*
X467278D03*
X463578Y860993D03*
X458029Y857789D03*
X469129D03*
X470978Y860993D03*
X469129Y870606D03*
X461729D03*
X465429D03*
X458029D03*
X456179Y854584D03*
X463579D03*
X461729Y864197D03*
X458029D03*
X454329D03*
X469129D03*
X465429D03*
X456179Y867401D03*
X463579D03*
X467278D03*
X459878D03*
Y860993D03*
X467278D03*
Y854584D03*
X465429Y857789D03*
X459878Y854584D03*
X458029Y857789D03*
X469129D03*
X463578Y860993D03*
X461729Y857789D03*
X456178Y860993D03*
X454329Y857789D03*
X467278Y880219D03*
X469129Y883423D03*
X459878Y880219D03*
X463578Y873810D03*
X458029Y883423D03*
X461729D03*
X465429D03*
X456178Y873810D03*
Y886627D03*
X463578D03*
X470978D03*
X461729Y877014D03*
X458029D03*
X456179Y880219D03*
X454329Y877014D03*
X463579Y880219D03*
X469129Y877014D03*
X465429D03*
X469129Y870606D03*
X463578Y873810D03*
X461729Y870606D03*
X456178Y873810D03*
X454329Y870606D03*
X465429D03*
X458029D03*
X469129Y883423D03*
X467278Y880219D03*
X461729Y883423D03*
X459878Y880219D03*
X454329Y883423D03*
X465429D03*
X458029D03*
X467278Y873810D03*
X459878D03*
X461729Y889832D03*
X458029D03*
X456179Y893036D03*
X454329Y889832D03*
X463579Y893036D03*
X469129Y896240D03*
Y889832D03*
X465429D03*
X463578Y886627D03*
X456178D03*
X459878D03*
X467278D03*
X459878Y899445D03*
X467278D03*
X454329Y896240D03*
X461729D03*
X458029D03*
X465429D03*
X463578Y905853D03*
X461729Y902649D03*
X458029D03*
X456178Y912262D03*
Y905853D03*
X454329Y902649D03*
X465429D03*
Y909057D03*
Y915466D03*
X469129Y902649D03*
X454329Y909057D03*
X467278Y912262D03*
X469129Y915466D03*
X458029Y909057D03*
X459878Y905853D03*
X461729Y915466D03*
X458029D03*
X463578Y912262D03*
X459878D03*
X469129Y909057D03*
X454103Y931359D03*
Y933659D03*
X461729Y921875D03*
X456178Y918670D03*
X467278D03*
X454329Y921875D03*
X468236Y928349D03*
X465936D03*
X463636D03*
X461336D03*
X459036D03*
X469129Y921875D03*
X463578Y918670D03*
X458029Y921875D03*
X462261Y942152D03*
X464561D03*
X466861D03*
X454423Y949139D03*
X469251Y942246D03*
X453585Y942238D03*
Y939938D03*
Y944538D03*
X454393Y963829D03*
Y966129D03*
X463874Y956540D03*
X466272D03*
X454423Y951439D03*
X453403Y956999D03*
X461424Y956620D03*
X458404D03*
X453403Y959299D03*
X468904Y956620D03*
X466272Y971100D03*
X463874Y971140D03*
X454263Y981209D03*
Y978909D03*
X468904Y971100D03*
X458404D03*
X461424Y971140D03*
X453403Y973099D03*
Y970799D03*
X454463Y995299D03*
Y992999D03*
X466272Y985580D03*
X463874D03*
X453403Y986899D03*
X461424Y985580D03*
X458404D03*
X453403Y984599D03*
X468904Y985580D03*
X453403Y998399D03*
X466272Y1014540D03*
X463874D03*
X454443Y1009409D03*
Y1007109D03*
X466272Y1000060D03*
X463874D03*
X468895Y1014550D03*
X453403Y1012199D03*
X458404Y1000080D03*
X461424D03*
X453403Y1000699D03*
X468904Y1000080D03*
X458404Y1014540D03*
X461295Y1014510D03*
X453403Y1014499D03*
X454434Y1022186D03*
Y1019886D03*
X465680Y1028855D03*
X463180D03*
X460680D03*
X458180D03*
X457942Y1031909D03*
X460311Y1041340D03*
X467372Y1036874D03*
X465861Y1044544D03*
X456611Y1047749D03*
X464011D03*
X467711Y1041340D03*
X454762Y1044544D03*
Y1038136D03*
X460971Y1037069D03*
X463271D03*
X458671D03*
X457942Y1034409D03*
X462162Y1044544D03*
X458462D03*
X465860Y1050952D03*
X456611Y1060565D03*
X462161Y1057361D03*
X456611Y1054157D03*
X462162Y1050952D03*
X465862Y1057361D03*
X458462Y1063770D03*
X465862D03*
X462161D03*
X460312Y1054157D03*
X458462Y1057361D03*
X467712Y1054157D03*
Y1060565D03*
X454761Y1063770D03*
X464012Y1060565D03*
X458460Y1050952D03*
X454761Y1076587D03*
X456611Y1073383D03*
X454762Y1070178D03*
X462162D03*
X467711Y1073383D03*
Y1066974D03*
X456612Y1079791D03*
X467711D03*
X460311Y1073383D03*
Y1066974D03*
X465860Y1070178D03*
X464012Y1079791D03*
X460312D03*
X462162Y1076587D03*
X456611Y1066974D03*
X465862Y1076587D03*
X458462D03*
X458461Y1082995D03*
X456611Y1086200D03*
X460311Y1092608D03*
X464011Y1086200D03*
X467712D03*
Y1092608D03*
X465862Y1082995D03*
X462162D03*
X462161Y1095812D03*
X458461D03*
X465861Y1089403D03*
X456612Y1092607D03*
X454761Y1089403D03*
X460311Y1086200D03*
X454760Y1082995D03*
X465861Y1095812D03*
X464012Y1092607D03*
X454761Y1095812D03*
X458461Y1089403D03*
X462161D03*
X460312Y1105426D03*
X458462Y1102221D03*
X456611Y1099017D03*
X464012Y1105426D03*
Y1099017D03*
X462162Y1108630D03*
X465861D03*
Y1102221D03*
X464012Y1111834D03*
X467711Y1105426D03*
Y1111834D03*
Y1099017D03*
X462162Y1102221D03*
X458461Y1108630D03*
X456612Y1105426D03*
X454761Y1108630D03*
Y1102221D03*
X460312Y1111834D03*
X456611D03*
X460312Y1099016D03*
X471411Y1124651D03*
X469562Y1121447D03*
X458462D03*
Y1115039D03*
X467712Y1124651D03*
X467711Y1118243D03*
X465862Y1121447D03*
Y1115039D03*
X458462Y1127856D03*
X464012Y1124651D03*
X462161Y1121447D03*
X460312Y1124651D03*
X456611D03*
X454761Y1121447D03*
X464011Y1118243D03*
X462161Y1115039D03*
X460312Y1118243D03*
X456611D03*
X454761Y1115039D03*
X462161Y1127856D03*
X454761D03*
X465861D03*
X458462Y1134264D03*
X464012Y1137469D03*
X460312D03*
X456612D03*
X464012Y1131060D03*
X462161Y1134264D03*
X460312Y1131060D03*
X456611D03*
X454761Y1134264D03*
X462161Y1140973D03*
X458461D03*
X454761D03*
X467712Y1137469D03*
X465861Y1134264D03*
X467712Y1131060D03*
X465861Y1140973D03*
X483927Y844971D03*
X485778Y848176D03*
X487627Y844971D03*
X480227D03*
X476527D03*
X482079Y841467D03*
X478378Y848176D03*
X474679Y841467D03*
X472827Y844971D03*
X474678Y854584D03*
X482078D03*
X478379Y841467D03*
X470979D03*
X476529Y851380D03*
X480229D03*
X472829D03*
X483929D03*
X474678Y848176D03*
X482078D03*
X483927Y844971D03*
X480227D03*
X476527D03*
X470978Y848176D03*
X482079Y841467D03*
X478378Y848176D03*
X474679Y841467D03*
X472827Y844971D03*
X476529Y857789D03*
X480229D03*
X474678Y867401D03*
X482078D03*
X478378Y860993D03*
X472829Y857789D03*
X483929D03*
X485778Y860993D03*
X487629Y857789D03*
Y870606D03*
X483929D03*
X480229D03*
X476529D03*
X480229Y864197D03*
X478379Y854584D03*
X476529Y864197D03*
X470979Y854584D03*
X472829Y864197D03*
X483929D03*
X478379Y867401D03*
X470979D03*
X474678D03*
X482078D03*
X474678Y860993D03*
X482078D03*
Y854584D03*
X480229Y857789D03*
X474678Y854584D03*
X472829Y857789D03*
X483929D03*
X478378Y860993D03*
X476529Y857789D03*
X470978Y860993D03*
X485778Y873810D03*
X487629Y883423D03*
X483929D03*
X478378Y873810D03*
X476529Y883423D03*
X482078Y880219D03*
X474678D03*
X480229Y883423D03*
X472829D03*
X478378Y886627D03*
X485778D03*
X480229Y877014D03*
X478379Y880219D03*
X476529Y877014D03*
X472829D03*
X472828Y870606D03*
X470979Y880219D03*
Y873810D03*
X483929Y877014D03*
X480229Y870606D03*
X476529D03*
X478378Y873810D03*
X483929Y870606D03*
X474678Y880219D03*
X476529Y883423D03*
X482078Y880219D03*
X483929Y883423D03*
X472829D03*
X480229D03*
X474678Y873810D03*
X482078D03*
X483929Y896240D03*
X482078Y893036D03*
X487629Y896240D03*
X485778Y899445D03*
Y893036D03*
X487629Y902649D03*
X480228Y896240D03*
X480229Y889832D03*
X478379Y893036D03*
X470979D03*
X476529Y889832D03*
X472829D03*
X483929D03*
X474678Y899445D03*
X482078D03*
X474678Y893036D03*
X472829Y896240D03*
X482078Y893036D03*
X483929Y896240D03*
X470978Y886627D03*
X478378D03*
Y899445D03*
X474678Y886627D03*
X482078D03*
X483929Y915466D03*
X487629Y909057D03*
X485778Y912262D03*
X487629Y915466D03*
X485778Y918670D03*
X476529Y915466D03*
X480229Y902649D03*
X474678Y912262D03*
Y905853D03*
X483929Y909057D03*
X482079Y912262D03*
X483928Y902649D03*
X483929Y915466D03*
X480229D03*
X472828D03*
X472829Y902649D03*
X480228Y909057D03*
X482078Y905853D03*
X476529Y902649D03*
X470978Y905853D03*
X472829Y909057D03*
X476529D03*
X487629Y928283D03*
Y921875D03*
X485778Y931488D03*
X487629Y934691D03*
X483929D03*
X480229Y928283D03*
X478378Y931488D03*
Y925079D03*
X482078D03*
X476285Y930126D03*
X480229Y921875D03*
X476528D03*
X474678Y918670D03*
X483929Y928283D03*
X482078Y918670D03*
X483928Y921875D03*
X482079Y931488D03*
X472829Y921875D03*
X470536Y928349D03*
X485778Y937896D03*
X487629Y947509D03*
Y941100D03*
X485778Y950713D03*
X478378Y937896D03*
X480229Y941100D03*
X476285Y934726D03*
X476180Y945355D03*
Y947655D03*
X478378Y944304D03*
X480229Y934691D03*
X483928Y941100D03*
X482079Y944304D03*
X482078Y937896D03*
X483928Y947509D03*
X483929Y934691D03*
X480229Y947509D03*
X471550Y942152D03*
X473851Y942246D03*
X483929Y953917D03*
X487629Y960326D03*
Y953917D03*
Y966735D03*
X485778Y957122D03*
X476285Y962326D03*
Y960026D03*
Y964626D03*
X483928Y960326D03*
X482078Y957122D03*
X482079Y950713D03*
X483929Y966735D03*
X478378Y963530D03*
X483929Y953917D03*
X478378Y950713D03*
X480229Y953917D03*
X478378Y957122D03*
X471404Y956620D03*
X480229Y966735D03*
X482078Y963529D03*
X485778Y976347D03*
X487629Y979552D03*
Y973143D03*
X485778Y969939D03*
X483929Y973143D03*
X476285Y966926D03*
X476192Y977670D03*
X476335Y980737D03*
X482079Y969939D03*
X483928Y979552D03*
X482078Y976347D03*
X483929Y973143D03*
X476285Y973826D03*
Y971526D03*
X471404Y971100D03*
X473904D03*
X480229Y979552D03*
X478378Y982756D03*
X480229Y973143D03*
X478378Y976347D03*
X476285Y996826D03*
Y994526D03*
Y989926D03*
Y987626D03*
X471404Y985580D03*
X486211Y1009297D03*
Y1002888D03*
X484362Y1006093D03*
X476295Y1010500D03*
X476285Y1012926D03*
Y1006026D03*
Y1003726D03*
X471204Y1014540D03*
X484361Y999684D03*
X482512Y1009297D03*
X482511Y1002888D03*
X484362Y1012501D03*
X480662Y999684D03*
X478811Y1002888D03*
Y1009297D03*
X480662Y1012501D03*
X484362Y1006093D03*
X471404Y1000080D03*
X484362Y1025318D03*
X486211Y1022114D03*
Y1028523D03*
X476275Y1022636D03*
X476285Y1017526D03*
X482511Y1028523D03*
Y1022114D03*
X484361Y1018910D03*
Y1031727D03*
X484362Y1025318D03*
X480662Y1031727D03*
X482511Y1015705D03*
X480661Y1018910D03*
X478811Y1022114D03*
Y1028523D03*
Y1015705D03*
X476325Y1031795D03*
Y1027195D03*
Y1029495D03*
X470724Y1028827D03*
X480662Y1025318D03*
X486211Y1047749D03*
Y1041340D03*
X484362Y1044544D03*
X471282Y1036526D03*
X473507Y1035928D03*
X475111Y1041340D03*
X482511D03*
X482512Y1034931D03*
X484361Y1038136D03*
X471411Y1047749D03*
X482511D03*
X484362Y1044544D03*
X469562D03*
X480662Y1038136D03*
X478811Y1041340D03*
X480662Y1044544D03*
X473262D03*
X476962D03*
X478811Y1047749D03*
X484362Y1063770D03*
X486211Y1060565D03*
X480662Y1050952D03*
X475111Y1060565D03*
X471411Y1054157D03*
X484361Y1057361D03*
X482511Y1060565D03*
X484362Y1050952D03*
Y1063770D03*
X473261Y1057361D03*
X471412Y1060565D03*
X475112Y1054157D03*
X469562Y1063770D03*
X469561Y1057361D03*
X473262Y1063770D03*
X469561Y1050952D03*
X473262D03*
X482511Y1054157D03*
X480662Y1063770D03*
X480661Y1057361D03*
X478812Y1060565D03*
X476962Y1063770D03*
Y1057361D03*
X478812Y1054157D03*
X476961Y1050952D03*
X486211Y1079791D03*
Y1066974D03*
X475111D03*
X473262Y1070178D03*
X478811Y1073383D03*
X484361Y1076587D03*
X484362Y1070178D03*
X482512Y1066974D03*
X478812Y1079791D03*
X475111D03*
X482511D03*
X471411Y1066974D03*
X476962Y1076587D03*
X480662D03*
Y1070178D03*
X476962D03*
X473262Y1076587D03*
X469562D03*
X471411Y1073383D03*
Y1079791D03*
X484362Y1082995D03*
X486211Y1086200D03*
X480662Y1082995D03*
X476962Y1089404D03*
X473262Y1082995D03*
X469561Y1089404D03*
X482512Y1086200D03*
X484362Y1089404D03*
X480661Y1095813D03*
X469562D03*
X484362D03*
Y1082995D03*
X473262Y1095813D03*
X469562Y1082995D03*
X480662Y1089404D03*
X478812Y1092607D03*
X475112D03*
X473261Y1089403D03*
X471412Y1086199D03*
X476961Y1082994D03*
X482512Y1092607D03*
X476961Y1095812D03*
X471412Y1092607D03*
X475112Y1086199D03*
X478812D03*
X480662Y1108630D03*
X478811Y1099017D03*
X473262Y1108630D03*
X476962Y1102221D03*
X475112Y1099017D03*
X471411D03*
X469562Y1102221D03*
X482511Y1105426D03*
Y1111834D03*
X484362Y1108630D03*
X475111Y1111834D03*
X471411D03*
X478811Y1105426D03*
X469562Y1108630D03*
X473262Y1102221D03*
X482511Y1099017D03*
X478811Y1111834D03*
X476962Y1108630D03*
X471411Y1105426D03*
X475111D03*
X484362Y1102221D03*
X480662D03*
X476962Y1121447D03*
X484362D03*
X480662Y1127856D03*
X473262D03*
X482511Y1124651D03*
X478811D03*
X475111D03*
X486211D03*
X480661Y1115039D03*
X478811Y1118243D03*
X476961Y1115039D03*
X475111Y1118243D03*
X471411D03*
X469561Y1115039D03*
X482511Y1118243D03*
X476961Y1127856D03*
X469562D03*
X484361D03*
X484362Y1115039D03*
X473262D03*
X484362Y1121447D03*
X480662Y1127856D03*
X476962Y1121447D03*
X473262Y1127856D03*
X469562Y1121447D03*
X482511Y1124651D03*
X478811D03*
X475111D03*
X471411D03*
X473262Y1121447D03*
X480662D03*
X486212Y1137469D03*
X484362Y1134264D03*
X475112Y1137469D03*
X482512D03*
X478812D03*
X473261Y1140973D03*
X476962Y1134264D03*
X480661Y1140973D03*
X478811Y1131060D03*
X476961Y1140973D03*
X475111Y1131060D03*
X471412Y1137469D03*
Y1131060D03*
X469561Y1140973D03*
X473261Y1134264D03*
X482511Y1131060D03*
X484361Y1140973D03*
X484362Y1134264D03*
X482512Y1137469D03*
X476962Y1134264D03*
X475112Y1137469D03*
X480661Y1140973D03*
X478812Y1137469D03*
X473261Y1140973D03*
X480662Y1134264D03*
X469561D03*
X482911Y1578182D03*
X478651D03*
X470851D03*
X482911Y1590094D03*
X478651D03*
X470851D03*
X483951Y1614292D03*
Y1602380D03*
X476151D03*
Y1614292D03*
X502427Y844971D03*
X500578Y848176D03*
X498727Y844971D03*
X491327D03*
X495027D03*
X496878Y841467D03*
X493178Y848176D03*
X489478Y841467D03*
X496878Y854584D03*
X489478D03*
X493179Y841467D03*
X485779D03*
X500579D03*
X495029Y851380D03*
X491329D03*
X487629D03*
X498729D03*
X489478Y848176D03*
X496878D03*
X493178D03*
X489478Y841467D03*
X487627Y844971D03*
X500578Y848176D03*
X496878Y841467D03*
X495027Y844971D03*
X491327D03*
X485778Y848176D03*
X498727Y844971D03*
X496878Y867401D03*
X493178Y860993D03*
X491329Y857789D03*
X495029D03*
X500578Y860993D03*
X498729Y857789D03*
X489478Y867401D03*
X502429Y857789D03*
Y870606D03*
X491329D03*
X498729D03*
X495029D03*
Y864197D03*
X493179Y854584D03*
X491329Y864197D03*
X487629D03*
X485779Y854584D03*
X498729Y864197D03*
X500579Y854584D03*
X493179Y867401D03*
X485779D03*
X500579D03*
X489478D03*
X496878D03*
X489478Y860993D03*
X496878D03*
X489478Y854584D03*
X487629Y857789D03*
X500578Y860993D03*
X498729Y857789D03*
X495029D03*
X491329D03*
X485778Y860993D03*
X496878Y854584D03*
X493178Y860993D03*
X502429Y883423D03*
X500578Y873810D03*
X493178D03*
X489478Y880219D03*
X496878D03*
X498729Y883423D03*
X491329D03*
X495029D03*
X493178Y886627D03*
X500578D03*
X495029Y877014D03*
X493179Y880219D03*
X491329Y877014D03*
X487629D03*
X485779Y880219D03*
X500579D03*
X498729Y877014D03*
X487629Y870606D03*
X495029D03*
X485778Y873810D03*
X491329Y870606D03*
X493178Y873810D03*
X498729Y870606D03*
X500578Y873810D03*
X489478Y880219D03*
X491329Y883423D03*
X496878Y880219D03*
X498729Y883423D03*
X487629D03*
X495029D03*
X496878Y873810D03*
X489478D03*
X493178Y893036D03*
X495029Y896240D03*
X496878Y893036D03*
X500578Y899445D03*
X493178D03*
X491329Y896240D03*
X498729Y902649D03*
X491329D03*
X489479Y893036D03*
X495029Y889832D03*
X491329D03*
X487629D03*
X498729D03*
X500579Y893036D03*
X498729Y896240D03*
X496879Y899445D03*
X489478D03*
X500578D03*
X485778D03*
X493178D03*
Y893036D03*
X496878D03*
X485778D03*
X491329Y896240D03*
X487629D03*
X495029D03*
X485778Y886627D03*
X493178D03*
X500578D03*
X489478D03*
X496878D03*
X500578Y905853D03*
Y912262D03*
X491329Y915466D03*
X498729Y909057D03*
X496878Y905853D03*
X491329Y909057D03*
X493178Y912262D03*
X495029Y915466D03*
X500578Y918670D03*
X493178D03*
X496878Y912262D03*
X495029Y909057D03*
X489478Y912262D03*
Y905853D03*
X495029Y902649D03*
X493179Y905853D03*
X485778D03*
X498728Y915466D03*
X485778Y912262D03*
X487629Y909057D03*
X493178Y912262D03*
X491329Y909057D03*
X500578Y912262D03*
X498729Y909057D03*
Y902649D03*
X487629D03*
X491329D03*
X487629Y915466D03*
X500578Y905853D03*
X495029Y915466D03*
X496878Y905853D03*
X491329Y915466D03*
X493178Y931488D03*
X500578Y925079D03*
X496878D03*
X498729Y928283D03*
Y921875D03*
X500578Y931488D03*
X491329Y921875D03*
Y928283D03*
X495029Y934691D03*
X491329D03*
X495028Y928283D03*
X493179Y925079D03*
X489478D03*
Y918670D03*
X485778Y925079D03*
X496879Y918670D03*
X495029Y921875D03*
X496878Y931488D03*
X489478D03*
X500578D03*
X498729Y921875D03*
X500578Y918670D03*
X498729Y928283D03*
X496878Y925079D03*
X500578D03*
X491329Y921875D03*
X493178Y918670D03*
X485778Y931488D03*
X491329Y928283D03*
X493178Y931488D03*
X487629Y928283D03*
Y921875D03*
X485778Y918670D03*
X500578Y944304D03*
Y937896D03*
X496878Y944304D03*
X498729Y947509D03*
Y941100D03*
X491329Y947509D03*
Y941100D03*
X493178Y937896D03*
X500578Y950713D03*
X493178D03*
X496879Y937896D03*
X495029Y941100D03*
X493179Y944304D03*
X489478D03*
Y937896D03*
X485778Y944304D03*
X498729Y934691D03*
X495028Y947509D03*
X498729D03*
Y941100D03*
X500578Y937896D03*
X496878Y944304D03*
X500578D03*
X487629Y947509D03*
X491329D03*
X487629Y941100D03*
X485778Y937896D03*
X491329Y941100D03*
X493178Y937896D03*
X487629Y934691D03*
X495029D03*
X491329D03*
X496878Y963530D03*
X491329Y960326D03*
Y953917D03*
X498729Y960326D03*
X500578Y957122D03*
X495029Y953917D03*
X491329Y966735D03*
X493178Y957122D03*
X498729Y966735D03*
X496879Y957122D03*
X495029Y960326D03*
X489478Y957122D03*
Y950713D03*
X496878D03*
X498729Y953917D03*
X495028Y966735D03*
X493179Y963530D03*
X485778D03*
X489478D03*
X500579D03*
X500578Y950713D03*
X487629Y966735D03*
X491329D03*
X498729D03*
X496878Y963530D03*
X485778Y950713D03*
X493178D03*
X491329Y960326D03*
X493178Y957122D03*
X487629Y960326D03*
X485778Y957122D03*
X500578D03*
X498729Y960326D03*
X495029Y953917D03*
X487629D03*
X491329D03*
X500578Y969939D03*
Y982756D03*
Y976347D03*
X496878Y982756D03*
X491329Y979552D03*
X493178Y969939D03*
X491329Y973143D03*
X498729Y979552D03*
X493178Y976347D03*
X495029Y973143D03*
X496879Y976347D03*
X496878Y969939D03*
X489478Y976347D03*
Y969939D03*
X495029Y979552D03*
X498728Y973143D03*
X493179Y982756D03*
X489478D03*
X485778D03*
X487629Y979552D03*
X485778Y976347D03*
X491329Y979552D03*
X493178Y976347D03*
X500578Y982756D03*
X496878D03*
X498729Y979552D03*
X500578Y976347D03*
X495029Y973143D03*
X487629D03*
X491329D03*
X485778Y969939D03*
X493178D03*
X500578D03*
X499162Y999684D03*
X488062D03*
X491762D03*
X501011Y1009297D03*
Y1002888D03*
X493611D03*
Y1009297D03*
X491761Y1012501D03*
X488062D03*
X499162D03*
X495462Y1006093D03*
X497311Y1015705D03*
Y1009297D03*
X497312Y1002888D03*
X495462Y999684D03*
X489911Y1009297D03*
X489912Y1002888D03*
X491761Y1006093D03*
X488062D03*
X499161D03*
X495461Y1012501D03*
X501011Y1002888D03*
X499162Y999684D03*
Y1012501D03*
X501011Y1009297D03*
X495462Y1006093D03*
X486211Y1002888D03*
X493611D03*
X488062Y999684D03*
X491762D03*
X491761Y1012501D03*
X493611Y1009297D03*
X488062Y1012501D03*
X486211Y1009297D03*
X499162Y1018910D03*
X501011Y1028523D03*
Y1022114D03*
X491762Y1018910D03*
X499162Y1031727D03*
X493611Y1028523D03*
Y1022114D03*
X488062Y1031727D03*
Y1018910D03*
X491762Y1031727D03*
X495462Y1025318D03*
X491762D03*
X488062D03*
X497311Y1028523D03*
X489911D03*
Y1022114D03*
Y1015705D03*
X497311Y1022114D03*
X495462Y1018910D03*
X493612Y1015705D03*
X486211D03*
X501012D03*
X499161Y1025318D03*
X495461Y1031727D03*
X497311Y1015705D03*
X499162Y1031727D03*
X501011Y1028523D03*
Y1022114D03*
X499162Y1018910D03*
X488062Y1031727D03*
X486211Y1028523D03*
X491762Y1031727D03*
X493611Y1028523D03*
X486211Y1022114D03*
X488062Y1018910D03*
X493611Y1022114D03*
X491762Y1018910D03*
X488062Y1025318D03*
X495462D03*
X491762D03*
X501011Y1041340D03*
Y1047749D03*
Y1034931D03*
X491762Y1038136D03*
X497311Y1034931D03*
X499162Y1038136D03*
X495462Y1044544D03*
X488062D03*
X491762D03*
X493611Y1041340D03*
X488062Y1038136D03*
X493611Y1047749D03*
X497312Y1041340D03*
X489911D03*
Y1034931D03*
X495462Y1038136D03*
X493612Y1034931D03*
X486211D03*
X499161Y1044544D03*
X489911Y1047749D03*
X497311D03*
X501011Y1041340D03*
X499162Y1038136D03*
X501011Y1047749D03*
Y1034931D03*
X497311D03*
X486211Y1047749D03*
X493611D03*
X486211Y1041340D03*
X488062Y1038136D03*
X493611Y1041340D03*
X491762Y1038136D03*
X488062Y1044544D03*
X495462D03*
X491762D03*
Y1057361D03*
X493611Y1060565D03*
X488062Y1057361D03*
X501011Y1060565D03*
X499162Y1057361D03*
X501011Y1054157D03*
X497311D03*
X491762Y1050952D03*
X488062D03*
X499162D03*
X495462Y1063770D03*
X488062D03*
X491762D03*
X497311Y1060565D03*
X495462Y1057361D03*
X489911Y1060565D03*
Y1054157D03*
X495461Y1050952D03*
X493611Y1054157D03*
X486211D03*
X499162Y1063770D03*
X501011Y1060565D03*
X499162Y1057361D03*
Y1050952D03*
X501011Y1054157D03*
X497311D03*
X486211Y1060565D03*
X488062Y1057361D03*
X493611Y1060565D03*
X491762Y1057361D03*
X488062Y1050952D03*
X491762D03*
X488062Y1063770D03*
X495462D03*
X491762D03*
X501011Y1079791D03*
Y1073383D03*
Y1066974D03*
X491762Y1070178D03*
X488062D03*
X491762Y1076587D03*
X493611Y1079791D03*
X488062Y1076587D03*
X499162Y1070178D03*
Y1076587D03*
X497311Y1073383D03*
X493611Y1066974D03*
X495462Y1076587D03*
X493612Y1073383D03*
X489911Y1066974D03*
X486211Y1073383D03*
X497311Y1066974D03*
X495461Y1070178D03*
X489911Y1073383D03*
X497312Y1079791D03*
X489911D03*
X499162Y1070178D03*
X501011Y1066974D03*
Y1079791D03*
X499162Y1076587D03*
X497311Y1073383D03*
X501011D03*
X486211Y1079791D03*
X488062Y1076587D03*
X493611Y1079791D03*
X491762Y1076587D03*
X488062Y1070178D03*
X486211Y1066974D03*
X491762Y1070178D03*
X493611Y1066974D03*
X501011Y1086200D03*
X493611D03*
X488062Y1089404D03*
X497311Y1092608D03*
X491762Y1089404D03*
X501011Y1092608D03*
X488062Y1082995D03*
X491762D03*
X495462D03*
X499162Y1089404D03*
X497311Y1086200D03*
X493612Y1092608D03*
X489911D03*
Y1086200D03*
X486211Y1092608D03*
X495461Y1089404D03*
X499161Y1082995D03*
X495462Y1095813D03*
X499162D03*
X491762D03*
Y1089404D03*
X493611Y1086200D03*
X499162Y1089404D03*
X501011Y1086200D03*
X488062Y1089404D03*
X486211Y1086200D03*
X497311Y1092608D03*
X495462Y1082995D03*
X501011Y1092608D03*
X488062Y1082995D03*
X491762D03*
X488062Y1095813D03*
X497312Y1105426D03*
X493611D03*
X491762Y1102221D03*
X488061D03*
X486211Y1105426D03*
X486212Y1099017D03*
X499161Y1108630D03*
Y1102221D03*
X497312Y1111834D03*
X489911D03*
Y1099017D03*
X495462Y1102221D03*
X501011Y1099017D03*
X493611D03*
X497311D03*
X495462Y1108630D03*
X489911Y1105426D03*
X486211Y1111834D03*
X493611D03*
X491762Y1108630D03*
X488062D03*
X501012Y1105426D03*
Y1111833D03*
X488062Y1127856D03*
X495462D03*
X489911Y1124651D03*
X493611D03*
X501011D03*
X499162Y1121447D03*
X491762D03*
X497311Y1124651D03*
X502862Y1127856D03*
X497311Y1118243D03*
X495462Y1121447D03*
X493612Y1118243D03*
X489911D03*
X486211D03*
X501011D03*
X499161Y1115039D03*
X491761Y1127856D03*
X499161D03*
X491762Y1115039D03*
X495462D03*
X488062Y1127856D03*
X499162Y1121447D03*
X495462Y1127856D03*
X491762Y1121447D03*
X489911Y1124651D03*
X486211D03*
X501011D03*
X497311D03*
X493611D03*
X488062Y1115039D03*
Y1121447D03*
X502861Y1140973D03*
X501012Y1137469D03*
X488061Y1140973D03*
X493612Y1137469D03*
X489912D03*
X499162Y1134264D03*
X497312Y1137469D03*
X491762Y1134264D03*
X495461Y1140973D03*
X497311Y1131060D03*
X493611D03*
X489911D03*
X486211D03*
X491761Y1140973D03*
X501011Y1131060D03*
X499161Y1140973D03*
X493612Y1137469D03*
X488061Y1140973D03*
X501012Y1137469D03*
X495461Y1140973D03*
X491762Y1134264D03*
X489912Y1137469D03*
X486212D03*
X499162Y1134264D03*
X497312Y1137469D03*
X495462Y1134264D03*
X488062D03*
X494971Y1578182D03*
X490711D03*
X494971Y1590094D03*
X490711D03*
X500271Y1614292D03*
Y1602380D03*
X488211Y1614292D03*
Y1602380D03*
X496011D03*
Y1614292D03*
X497441Y1675383D03*
Y1679920D03*
Y1684454D03*
Y1689556D03*
Y1694093D03*
Y1698627D03*
Y1703729D03*
Y1708266D03*
Y1712800D03*
Y1726974D03*
Y1722440D03*
Y1717903D03*
X517227Y844971D03*
X519079Y841467D03*
X511679D03*
X509827Y844971D03*
X506127D03*
X513527D03*
X504279Y841467D03*
X515378Y848176D03*
X507978D03*
X511678Y854584D03*
X504278D03*
X519078D03*
X507979Y841467D03*
X515379D03*
X506129Y851380D03*
X502429D03*
X513529D03*
X509829D03*
X517229D03*
X511678Y848176D03*
X504278D03*
X517227Y844971D03*
X511679Y841467D03*
X509827Y844971D03*
X504279Y841467D03*
X515378Y848176D03*
X513527Y844971D03*
X507978Y848176D03*
X506127Y844971D03*
X502427D03*
X517229Y857789D03*
X513529D03*
X504278Y867401D03*
X506129Y857789D03*
X509829D03*
X511678Y867401D03*
X515378Y860993D03*
X507978D03*
X519078Y867401D03*
X517229Y870606D03*
X509829D03*
X506129D03*
X513529D03*
Y864197D03*
X509829D03*
X506129D03*
X502429D03*
X507979Y854584D03*
X515379D03*
X517229Y864197D03*
X507979Y867401D03*
X515379D03*
X511678D03*
X504278D03*
X511678Y860993D03*
X504278D03*
X517229Y857789D03*
X513529D03*
X509829D03*
X506129D03*
X515378Y860993D03*
X511678Y854584D03*
X507978Y860993D03*
X504278Y854584D03*
X502429Y857789D03*
X517229Y883423D03*
X519078Y880219D03*
X515378Y873810D03*
X513529Y883423D03*
X504278Y880219D03*
X507978Y873810D03*
X506129Y883423D03*
X511678Y880219D03*
X509829Y883423D03*
X515378Y886627D03*
X507978D03*
X509829Y877014D03*
X507979Y880219D03*
X502429Y877014D03*
X513529D03*
X506129D03*
X515379Y880219D03*
X517229Y877014D03*
Y870606D03*
X502429D03*
X509829D03*
X513529D03*
X515378Y873810D03*
X506129Y870606D03*
X507978Y873810D03*
X511678Y880219D03*
X513529Y883423D03*
X504278Y880219D03*
X506129Y883423D03*
X509829D03*
X517229D03*
X502429D03*
X511678Y873810D03*
X504278D03*
X517229Y896240D03*
X511678Y899445D03*
X507978Y893036D03*
X513529Y896240D03*
X511678Y893036D03*
X509829Y896240D03*
X504278Y899445D03*
X519078Y893036D03*
Y899445D03*
X517229Y902649D03*
X513529D03*
X506129D03*
Y889832D03*
X502428Y896240D03*
X502429Y889832D03*
X513529D03*
X509829D03*
X506128Y896240D03*
X504279Y893036D03*
X515379D03*
X517229Y889832D03*
X507978Y899445D03*
X515378D03*
X511678D03*
Y893036D03*
X507978D03*
X509829Y896240D03*
X517229D03*
X513529D03*
X504278Y899445D03*
X515378Y886627D03*
X507978D03*
X511678D03*
X504278D03*
X519078Y912262D03*
X517229Y909057D03*
Y915466D03*
X513529D03*
X509829D03*
X504278Y905853D03*
X507978D03*
X511678Y912262D03*
X513529Y909057D03*
X504278Y912262D03*
X506129Y909057D03*
X511678Y918670D03*
X504278D03*
X519078D03*
X511678Y905853D03*
X509829Y909057D03*
X507979Y912262D03*
X502429Y909057D03*
Y902649D03*
X509828D03*
X515378Y912262D03*
Y905853D03*
X502429Y915466D03*
X506129D03*
X513529Y902649D03*
X517229D03*
X511678Y912262D03*
X513529Y909057D03*
X517229D03*
X513529Y915466D03*
X509829D03*
X517229D03*
X504278Y912262D03*
X506129Y909057D03*
Y902649D03*
X507978Y905853D03*
X504278D03*
Y925079D03*
X506129Y928283D03*
Y921875D03*
X513529D03*
Y928283D03*
X511678Y931488D03*
X517229Y928283D03*
X504278Y931488D03*
X507978Y925079D03*
X517229Y921875D03*
X519078Y931488D03*
X517229Y934691D03*
X513529D03*
X509829D03*
X511678Y925079D03*
X509829Y928283D03*
X502429D03*
Y921875D03*
X509828D03*
X507978Y918670D03*
X515378Y925079D03*
Y918670D03*
X507979Y931488D03*
X515378D03*
X511678D03*
X513529Y928283D03*
X517229D03*
X506129D03*
Y921875D03*
X504278Y918670D03*
X513529Y921875D03*
X511678Y918670D03*
X517229Y921875D03*
X504278Y931488D03*
Y925079D03*
X507978D03*
X517229Y941100D03*
X519078Y937896D03*
X517229Y947509D03*
X506129Y941100D03*
Y947509D03*
X507978Y944304D03*
X511678Y937896D03*
X513529Y941100D03*
X504278Y944304D03*
X513529Y947509D03*
X504278Y937896D03*
X511678Y950713D03*
X504278D03*
X519078D03*
X511678Y944304D03*
X509828Y941100D03*
X507978Y937896D03*
X506129Y934691D03*
X502429Y941100D03*
Y934691D03*
X515378Y944304D03*
Y937896D03*
X509829Y947509D03*
X502429D03*
X513529Y941100D03*
X511678Y937896D03*
X517229Y941100D03*
X513529Y934691D03*
X509829D03*
X517229D03*
X513529Y947509D03*
X517229D03*
X506129D03*
Y941100D03*
X504278Y937896D03*
X507978Y944304D03*
X504278D03*
X517229Y960326D03*
X506129Y966735D03*
X517229D03*
X506129Y960326D03*
X511678Y957122D03*
X517229Y953917D03*
X509829D03*
X513529D03*
Y966735D03*
X504278Y957122D03*
X507978Y963530D03*
X513529Y960326D03*
X519078Y957122D03*
X509828Y960326D03*
X507978Y957122D03*
X506129Y953917D03*
X502429Y960326D03*
Y953917D03*
X507979Y950713D03*
X515378Y957122D03*
Y950713D03*
X509829Y966735D03*
X502428D03*
X511678Y963530D03*
X504278D03*
X515378D03*
X511678Y950713D03*
X513529Y960326D03*
X511678Y957122D03*
X517229Y960326D03*
Y966735D03*
X513529D03*
X504278Y950713D03*
X513529Y953917D03*
X517229D03*
X509829D03*
X506129Y966735D03*
X504278Y957122D03*
X506129Y960326D03*
X507978Y963530D03*
X517229Y979552D03*
X519078Y969939D03*
Y976347D03*
X506129Y979552D03*
X513529D03*
X509829Y973143D03*
X511678Y969939D03*
X504278D03*
X507978Y982756D03*
X504278D03*
Y976347D03*
X511678D03*
X507978D03*
X507979Y969939D03*
X502429Y979552D03*
Y973143D03*
X513529D03*
X509828Y979552D03*
X506129Y973143D03*
X515379Y976347D03*
X515378Y969939D03*
X517228Y973143D03*
X511678Y982756D03*
X515378D03*
X507978D03*
X504278D03*
Y976347D03*
X506129Y979552D03*
X513529D03*
X517229D03*
X511678Y976347D03*
X509829Y973143D03*
X511678Y969939D03*
X504278D03*
X517661Y999684D03*
X513962D03*
X506561D03*
X517662Y1006093D03*
X519511Y1009297D03*
X519513Y1002888D03*
X517662Y1012501D03*
X504711Y1009297D03*
X506562Y1012501D03*
X513962Y1006093D03*
X512111Y1002888D03*
X510262Y1006093D03*
X512111Y1009297D03*
X504711Y1002888D03*
X513962Y1012501D03*
X508411Y1015705D03*
X510261Y999684D03*
X508411Y1002888D03*
X506562Y1006093D03*
X502862Y999684D03*
X502861Y1012501D03*
X508412Y1009297D03*
X510262Y1012501D03*
X515811Y1009297D03*
Y1002888D03*
X502862Y1006093D03*
X517662D03*
X513962D03*
X510262D03*
X517662Y1012501D03*
X504711Y1002888D03*
X506561Y999684D03*
X513962Y1012501D03*
X512111Y1009297D03*
X506562Y1012501D03*
X504711Y1009297D03*
X517661Y999684D03*
X512111Y1002888D03*
X513962Y999684D03*
X510262Y1025318D03*
X513962Y1018910D03*
X517662Y1025318D03*
X506562Y1018910D03*
X517662Y1031727D03*
X512111Y1028523D03*
Y1022114D03*
X513962Y1025318D03*
Y1031727D03*
X504711Y1028523D03*
X506562Y1031727D03*
X517662Y1018910D03*
X504711Y1022114D03*
X519511D03*
Y1028523D03*
X508411D03*
X502862Y1025318D03*
Y1018910D03*
X510261D03*
X508411Y1022114D03*
X506562Y1025318D03*
X504711Y1015705D03*
X515811Y1028523D03*
Y1022114D03*
X510262Y1031727D03*
X502862D03*
X515811Y1015705D03*
X512111D03*
X513962Y1031727D03*
X512111Y1028523D03*
X517662Y1031727D03*
X512111Y1022114D03*
X513962Y1018910D03*
X517662D03*
X513962Y1025318D03*
X510262D03*
X517662D03*
X508411Y1015705D03*
X506562Y1031727D03*
X504711Y1028523D03*
Y1022114D03*
X506562Y1018910D03*
X517662Y1044544D03*
Y1038136D03*
X519511Y1041340D03*
Y1047749D03*
X513962Y1038136D03*
X508411Y1034931D03*
X510262Y1044544D03*
X512111Y1047749D03*
Y1041340D03*
X504711Y1034931D03*
X513962Y1044544D03*
X506562Y1038136D03*
X504711Y1041340D03*
Y1047749D03*
X502862Y1044544D03*
Y1038136D03*
X512111Y1034931D03*
X510261Y1038136D03*
X508411Y1041340D03*
X506562Y1044544D03*
X515811Y1034931D03*
Y1041340D03*
X508411Y1047749D03*
X515811D03*
X504711Y1041340D03*
X506562Y1038136D03*
X512111Y1047749D03*
Y1041340D03*
X513962Y1038136D03*
X517662D03*
X504711Y1047749D03*
X510262Y1044544D03*
X508411Y1034931D03*
X513962Y1044544D03*
X517662D03*
X504711Y1034931D03*
X506562Y1057361D03*
X508411Y1054157D03*
X506562Y1050952D03*
X512111Y1060565D03*
X517662Y1063770D03*
X510262D03*
X513962D03*
Y1050952D03*
X517662D03*
Y1057361D03*
X504711Y1060565D03*
X513962Y1057361D03*
X504711Y1054157D03*
X519511Y1060565D03*
X510262Y1057361D03*
X508411Y1060565D03*
X502862Y1057361D03*
Y1050952D03*
X512111Y1054157D03*
X510262Y1050952D03*
X515811Y1054157D03*
Y1060565D03*
X502862Y1063770D03*
X506562D03*
X512111Y1060565D03*
X513962Y1057361D03*
X517662D03*
X510262Y1063770D03*
X513962D03*
X517662D03*
X513962Y1050952D03*
X517662D03*
X504711Y1060565D03*
X506562Y1057361D03*
Y1050952D03*
X508411Y1054157D03*
X504711D03*
X519511Y1066974D03*
Y1079791D03*
X517662Y1076587D03*
Y1070178D03*
X513962Y1076587D03*
X504711Y1073383D03*
X512111Y1066974D03*
X504711D03*
X512111Y1079791D03*
X513962Y1070178D03*
X504711Y1079791D03*
X506562Y1076587D03*
X508411Y1073383D03*
X506562Y1070178D03*
X510262Y1076587D03*
Y1070178D03*
X502862Y1076587D03*
Y1070178D03*
X512111Y1073383D03*
X508411Y1066974D03*
X515811Y1073383D03*
Y1066974D03*
X508411Y1079791D03*
X515811D03*
X517662Y1070178D03*
X513962D03*
X512111Y1066974D03*
X504711Y1079791D03*
X506562Y1076587D03*
Y1070178D03*
X504711Y1066974D03*
X512111Y1079791D03*
X513962Y1076587D03*
X517662D03*
X508411Y1073383D03*
X504711D03*
X517662Y1089404D03*
X504711Y1092608D03*
X513962Y1082995D03*
X510262D03*
X512111Y1086200D03*
X513962Y1089404D03*
X506562D03*
X506561Y1095813D03*
X517662Y1082995D03*
X510262Y1095813D03*
X508411Y1092608D03*
X504711Y1086200D03*
X519511D03*
X515811Y1099017D03*
X512112Y1092608D03*
X510262Y1089404D03*
X508412Y1086200D03*
X506562Y1082995D03*
X502862Y1089404D03*
Y1082995D03*
X515812Y1092608D03*
X515811Y1086200D03*
X513961Y1095813D03*
X502862D03*
X517662D03*
X513962Y1089404D03*
X512111Y1086200D03*
X517662Y1089404D03*
X513962Y1082995D03*
X510262D03*
X517662D03*
X510262Y1095813D03*
X506561D03*
X506562Y1089404D03*
X504711Y1086200D03*
X508411Y1092608D03*
X504711D03*
X517662Y1102221D03*
X513962Y1108630D03*
Y1102221D03*
X512112Y1099017D03*
X508411D03*
X506562Y1108630D03*
X504711Y1099017D03*
X502862Y1102221D03*
X515811Y1105426D03*
Y1111834D03*
X517662Y1108630D03*
Y1102221D03*
X515811Y1099017D03*
X510262Y1102221D03*
X502861Y1108629D03*
X512112Y1105426D03*
X508412Y1111833D03*
X506561Y1102220D03*
X504712Y1111833D03*
Y1105426D03*
X510261Y1108630D03*
X512112Y1111833D03*
X508412Y1105426D03*
X513962Y1121447D03*
X508411Y1124651D03*
X517662Y1127856D03*
X504711Y1124651D03*
X510262Y1127856D03*
X515811Y1124651D03*
X512111D03*
X506562Y1121447D03*
X519511Y1124651D03*
X513961Y1115039D03*
X512111Y1118243D03*
X508411D03*
X504711D03*
X510261Y1115039D03*
X515811Y1118243D03*
X513961Y1127856D03*
X506561D03*
X517662Y1115039D03*
Y1127856D03*
X513962Y1121447D03*
X510262Y1127856D03*
X506562Y1121447D03*
X502862Y1127856D03*
X515811Y1124651D03*
X512111D03*
X508411D03*
X504711D03*
X502862Y1115039D03*
X510262Y1121447D03*
X502862D03*
X517662D03*
X506561Y1115038D03*
X519512Y1137469D03*
X517661Y1140973D03*
X515812Y1137469D03*
X513962Y1134264D03*
X508412Y1137469D03*
X504712D03*
X506562Y1134264D03*
X510261Y1140973D03*
X512112Y1137469D03*
X513961Y1140973D03*
X512111Y1131060D03*
X508411D03*
X504711D03*
X506561Y1140973D03*
X515811Y1131060D03*
X517661Y1140973D03*
X513962Y1134264D03*
X512112Y1137469D03*
X506562Y1134264D03*
X504712Y1137469D03*
X515812D03*
X510261Y1140973D03*
X508412Y1137469D03*
X502861Y1140973D03*
X510262Y1134264D03*
X502862D03*
X517662D03*
X507031Y1578182D03*
X514831D03*
X502771D03*
X507031Y1590094D03*
X514831D03*
X502771D03*
X512331Y1614292D03*
Y1602380D03*
X508071Y1614292D03*
Y1602380D03*
X513189Y1675383D03*
Y1679920D03*
X505315Y1679320D03*
X513189Y1684454D03*
Y1689556D03*
Y1694093D03*
Y1698627D03*
X505315Y1688391D03*
Y1693493D03*
Y1698030D03*
Y1683857D03*
X513189Y1703729D03*
Y1708266D03*
Y1712800D03*
X505315Y1707666D03*
Y1712203D03*
Y1702564D03*
X513189Y1726974D03*
Y1722440D03*
Y1717903D03*
X505315Y1730911D03*
Y1726377D03*
Y1721840D03*
Y1716737D03*
X533878Y848176D03*
X532028Y844671D03*
X526478Y848176D03*
X522778D03*
X520927Y844971D03*
X530178Y848176D03*
X524627Y844971D03*
X526478Y854584D03*
X533879D03*
X528329Y844671D03*
X522779Y841467D03*
X528329Y851380D03*
X524629D03*
X520929D03*
X532029D03*
X519078Y848176D03*
X532028Y844671D03*
X526478Y848176D03*
X524627Y844971D03*
X519079Y841467D03*
X533878Y848176D03*
X530178D03*
X522778D03*
X520927Y844971D03*
X522778Y860993D03*
X520929Y857789D03*
X524629D03*
X526479Y867401D03*
X532029Y864197D03*
X528329Y857789D03*
X535729D03*
Y864197D03*
X532029Y870606D03*
X524629D03*
X528329D03*
X520929D03*
X528329Y864197D03*
X524629D03*
X520929D03*
X530179Y860993D03*
Y854584D03*
X522779D03*
X532028Y857789D03*
X533879Y860993D03*
X530178Y867401D03*
X522779D03*
X533879D03*
X532029Y864197D03*
X533879Y854584D03*
X519078Y867401D03*
X526479D03*
Y860993D03*
X519078D03*
X528329Y857789D03*
X522778Y860993D03*
X520929Y857789D03*
X526478Y854584D03*
X524629Y857789D03*
X519078Y854584D03*
X535729Y877014D03*
X528329Y883423D03*
X520929D03*
X522778Y873810D03*
X524629Y883423D03*
X530178Y873810D03*
X526479Y880219D03*
X522778Y886627D03*
X530179D03*
X528329Y877014D03*
X522779Y880219D03*
X520929Y877014D03*
X530179Y880219D03*
X524629Y877014D03*
X532029D03*
X533879Y880219D03*
Y873810D03*
X532028Y883423D03*
X524629Y870606D03*
X532029D03*
X520929D03*
X522778Y873810D03*
X528329Y870606D03*
X530178Y873810D03*
X519078Y880219D03*
X520929Y883423D03*
X526479Y880219D03*
X528329Y883423D03*
X524629D03*
X526479Y873810D03*
X519078D03*
X522778Y893036D03*
X520929Y896240D03*
X526479Y899445D03*
X530178D03*
X532029Y902649D03*
X524629D03*
X528329Y896240D03*
Y889832D03*
X524629D03*
X526479Y893036D03*
X524629Y896240D03*
X520929Y889832D03*
X532029D03*
Y896240D03*
X533879Y893036D03*
X522779Y899445D03*
X533879D03*
X526479D03*
X530178D03*
X519078D03*
Y893036D03*
X522778D03*
X520929Y896240D03*
X522778Y886627D03*
X530179D03*
X526479D03*
X519078D03*
X533879D03*
X532029Y909057D03*
X533879Y905853D03*
X530179Y912262D03*
X524629Y909057D03*
X526479Y912262D03*
X520929Y915466D03*
X526479Y905853D03*
X522778D03*
X530179D03*
X526479Y918670D03*
X530179D03*
X528329Y902649D03*
X522778Y912262D03*
X520928Y909057D03*
X519079Y905853D03*
X520929Y902649D03*
X528329Y915466D03*
X524628D03*
X532029D03*
X528329Y909057D03*
X533879Y912262D03*
X530179D03*
X532029Y909057D03*
X524629Y902649D03*
X532029D03*
X526479Y912262D03*
X524629Y909057D03*
X526479Y905853D03*
X533879D03*
X522778D03*
X530179D03*
X519078Y912262D03*
X520929Y915466D03*
X526479Y931488D03*
X524629Y928283D03*
X530179Y931488D03*
X532029Y928283D03*
X524629Y921875D03*
X532029D03*
X526479Y925079D03*
X533879D03*
X522778D03*
X530179D03*
X520929Y934691D03*
X528329Y921875D03*
X520928Y928283D03*
X519079Y925079D03*
X522779Y918670D03*
X520929Y921875D03*
X522778Y931488D03*
X528329Y928283D03*
X533879Y918670D03*
X533878Y931488D03*
X526479D03*
X524629Y928283D03*
X530179Y931488D03*
X532029Y928283D03*
X524629Y921875D03*
X526479Y918670D03*
X532029Y921875D03*
X530179Y918670D03*
X526479Y925079D03*
X533879D03*
X522778D03*
X530179D03*
X519078Y931488D03*
Y918670D03*
X533879Y944304D03*
X532029Y941100D03*
Y947509D03*
X526479Y944304D03*
X530178D03*
X522778D03*
X524629Y941100D03*
X526479Y937896D03*
X530179D03*
X524629Y947509D03*
X526479Y950713D03*
X530178D03*
X528329Y941100D03*
Y934691D03*
X524628D03*
X522779Y937896D03*
X520929Y941100D03*
X519079Y944304D03*
X520928Y947509D03*
X532029Y934691D03*
X533879Y937896D03*
X528329Y947509D03*
X524629Y941100D03*
X526479Y937896D03*
X532029Y941100D03*
X530179Y937896D03*
X524629Y947509D03*
X532029D03*
X519078Y937896D03*
X533879Y944304D03*
X520929Y934691D03*
X526479Y944304D03*
X530178D03*
X522778D03*
X524629Y960326D03*
X526479Y957122D03*
X533879Y963530D03*
X520929Y953917D03*
X524629Y966735D03*
X532029D03*
X522778Y963530D03*
X532029Y960326D03*
X530178Y957122D03*
X528329Y960326D03*
Y953917D03*
X524629D03*
X522779Y957122D03*
X520929Y960326D03*
X522778Y950713D03*
X520928Y966735D03*
X526479Y963530D03*
X519079D03*
X533879Y957122D03*
X532029Y953917D03*
X533879Y950713D03*
X530178Y963530D03*
X528329Y966735D03*
X524629D03*
X532029D03*
X522778Y963530D03*
X526479Y950713D03*
X530178D03*
X532029Y960326D03*
X530178Y957122D03*
X524629Y960326D03*
X526479Y957122D03*
X533879Y963530D03*
X519078Y950713D03*
Y957122D03*
X520929Y953917D03*
X526479Y969939D03*
X520929Y973143D03*
X530179Y969939D03*
X528329Y979552D03*
Y973143D03*
X522779Y976347D03*
X522778Y969939D03*
X524628Y973143D03*
X520929Y979552D03*
X533879Y976347D03*
X519079Y982756D03*
X533901Y980606D03*
X533879Y969939D03*
X532029Y973143D03*
X526479Y969939D03*
X530179D03*
X519078Y976347D03*
Y969939D03*
X520929Y973143D03*
X532461Y999684D03*
X525062D03*
X532461Y1012501D03*
X525062D03*
X530611Y1009297D03*
X526911Y1002888D03*
X530611D03*
X521362Y1006093D03*
X526911Y1009297D03*
X534311Y1015705D03*
X523211D03*
X521361Y1012501D03*
Y999684D03*
X528762Y1006093D03*
Y999684D03*
X525061Y1006093D03*
X523211Y1009297D03*
X523212Y1002888D03*
X534311Y1009297D03*
Y1002888D03*
X532461Y1006093D03*
X528761Y1012501D03*
X521362Y1006093D03*
X525062Y1012501D03*
X532461D03*
X526911Y1009297D03*
X530611D03*
X519511D03*
X519513Y1002888D03*
X530611D03*
X532461Y999684D03*
X526911Y1002888D03*
X525062Y999684D03*
Y1031727D03*
X532461Y1018910D03*
Y1031727D03*
X526911Y1028523D03*
X521362Y1025318D03*
X526911Y1022114D03*
X530611D03*
Y1028523D03*
X525062Y1018910D03*
X528762Y1025318D03*
X523211Y1028523D03*
X525061Y1025318D03*
X528762Y1031727D03*
X521361D03*
X519512Y1015705D03*
X521362Y1018910D03*
X523211Y1022114D03*
X526912Y1015705D03*
X528762Y1018910D03*
X530611Y1015705D03*
X534311Y1028523D03*
X534310Y1022114D03*
X532461Y1025318D03*
X523211Y1015705D03*
X534311D03*
X525062Y1031727D03*
X526911Y1028523D03*
X532461Y1031727D03*
X530611Y1028523D03*
Y1022114D03*
X532461Y1018910D03*
X526911Y1022114D03*
X525062Y1018910D03*
X519511Y1028523D03*
Y1022114D03*
X521362Y1025318D03*
X534311Y1034931D03*
X532461Y1038136D03*
X530611Y1047749D03*
X523211Y1034931D03*
X530611D03*
X526911D03*
Y1047749D03*
X521362Y1044544D03*
X526911Y1041340D03*
X530611D03*
X525062Y1038136D03*
X528762Y1044544D03*
X525061D03*
X523212Y1041340D03*
X521362Y1038136D03*
X519512Y1034931D03*
X532462Y1044544D03*
X523211Y1047749D03*
X528762Y1038136D03*
X534311Y1041340D03*
Y1047749D03*
X526911Y1041340D03*
X525062Y1038136D03*
X530611Y1041340D03*
X532461Y1038136D03*
X526911Y1047749D03*
X530611D03*
X526911Y1034931D03*
X534311D03*
X523211D03*
X530611D03*
X519511Y1047749D03*
Y1041340D03*
X521362Y1044544D03*
X532462Y1050953D03*
X525061Y1050952D03*
X521362Y1063770D03*
X523211Y1054157D03*
X532462Y1057361D03*
X530611Y1060565D03*
X525062Y1057361D03*
X526911Y1060565D03*
X530611Y1054157D03*
X526911D03*
X534311D03*
X528762Y1057361D03*
Y1050952D03*
X523212Y1060565D03*
X521362Y1057361D03*
X521361Y1050952D03*
X519512Y1054157D03*
X528762Y1063770D03*
X525061D03*
X534311Y1060565D03*
X532462Y1063770D03*
X519511Y1060565D03*
X526911D03*
X525062Y1057361D03*
X530611Y1060565D03*
X532462Y1057361D03*
X525061Y1050952D03*
X532462Y1050953D03*
X523211Y1054157D03*
X521362Y1063770D03*
X534311Y1054157D03*
X526911D03*
X530611D03*
X532462Y1076587D03*
Y1070178D03*
X534311Y1073383D03*
X530611Y1066974D03*
X525062Y1070178D03*
X526911Y1079791D03*
X525062Y1076587D03*
X523211Y1073383D03*
X526911D03*
Y1066974D03*
X530611Y1073383D03*
Y1079791D03*
X528762Y1076587D03*
Y1070178D03*
X521362Y1076587D03*
X521361Y1070178D03*
X519512Y1073383D03*
X523211Y1066974D03*
X523212Y1079791D03*
X534311Y1066974D03*
Y1079791D03*
X530611D03*
X532462Y1076587D03*
X525062Y1070178D03*
X526911Y1066974D03*
X532462Y1070178D03*
X530611Y1066974D03*
X526911Y1079791D03*
X525062Y1076587D03*
X523211Y1073383D03*
X534311D03*
X526911D03*
X530611D03*
X519511Y1066974D03*
Y1079791D03*
X523211Y1092608D03*
X521362Y1082995D03*
X532461Y1095813D03*
X530611Y1092608D03*
X534310D03*
X532462Y1089404D03*
X525062Y1095813D03*
X526911Y1086200D03*
Y1092608D03*
X530611Y1086200D03*
X521362Y1095813D03*
X525062Y1089404D03*
X530611Y1099017D03*
X523211Y1086200D03*
X521361Y1089404D03*
X519511Y1092608D03*
X528762Y1089404D03*
Y1082995D03*
X525061D03*
X532462Y1082996D03*
X534311Y1086200D03*
X528761Y1095813D03*
X521362D03*
X532461D03*
X525062D03*
Y1089404D03*
X526911Y1086200D03*
X532462Y1089404D03*
X530611Y1086200D03*
X526911Y1092608D03*
X534310D03*
X523211D03*
X530611D03*
X519511Y1086200D03*
X521362Y1082995D03*
X526911Y1105426D03*
X521361Y1102221D03*
X519511Y1105426D03*
X519512Y1099017D03*
X532461Y1108630D03*
X530612Y1111834D03*
X523211D03*
X526911Y1099017D03*
X534311D03*
X532460Y1102221D03*
X521362Y1108630D03*
X525062D03*
X534311Y1111834D03*
X523211Y1105426D03*
X534311D03*
X528762Y1108630D03*
X519511Y1111834D03*
X526911D03*
X530611Y1099017D03*
X528762Y1102221D03*
X525062D03*
X523212Y1099017D03*
X530611Y1105426D03*
X523211Y1124651D03*
X525062Y1127856D03*
X521362Y1121447D03*
X526911Y1124651D03*
X530611D03*
Y1118243D03*
X528762Y1121447D03*
X523211Y1118243D03*
X521361Y1115039D03*
X519511Y1118243D03*
X532461Y1115039D03*
X528761Y1127856D03*
X521361D03*
X525062Y1115039D03*
X528762D03*
X526911Y1124651D03*
X521362Y1121447D03*
X525062Y1127856D03*
X523211Y1124651D03*
X519511D03*
X526911Y1118243D03*
X525062Y1121447D03*
X534311Y1118243D03*
X532461Y1121446D03*
X534311Y1124650D03*
X532461Y1127855D03*
X534312Y1137469D03*
X532462Y1134264D03*
X526912Y1137469D03*
X523212D03*
X525061Y1140973D03*
X521362Y1134264D03*
X530612Y1137469D03*
Y1131060D03*
X526912D03*
X523211D03*
X519511D03*
X528761Y1134264D03*
X521361Y1140973D03*
X534311Y1131060D03*
X532462Y1134264D03*
X525061Y1140973D03*
X523212Y1137469D03*
X534312D03*
X526912D03*
X521362Y1134264D03*
X519512Y1137469D03*
X525062Y1134264D03*
X528761Y1140973D03*
X532461D03*
X531151Y1578182D03*
X519091D03*
X526891D03*
X531151Y1590094D03*
X519091D03*
X526891D03*
X532191Y1614292D03*
Y1602380D03*
X524391Y1614292D03*
Y1602380D03*
X520131D03*
Y1614292D03*
X528937Y1675383D03*
Y1679920D03*
X521063Y1679320D03*
X528937Y1684454D03*
Y1689556D03*
Y1694093D03*
Y1698627D03*
X521063Y1688391D03*
Y1693493D03*
Y1698030D03*
Y1683857D03*
X528937Y1703729D03*
Y1708266D03*
Y1712800D03*
X521063Y1707666D03*
Y1712203D03*
Y1702564D03*
X528937Y1726974D03*
Y1722440D03*
Y1717903D03*
X521063Y1730911D03*
Y1726377D03*
Y1721840D03*
Y1716737D03*
X539429Y851380D03*
X543129D03*
X541279Y854584D03*
X537580Y848176D03*
X535729Y844671D03*
Y851380D03*
X543129D03*
X539429D03*
X543128Y864197D03*
X541279Y860993D03*
X539429Y857789D03*
X546828Y864197D03*
X543130Y857789D03*
X539429Y870606D03*
X543129D03*
X544979Y860993D03*
Y854584D03*
X539428Y864197D03*
X537579Y854584D03*
Y860993D03*
X544979Y867401D03*
X541279D03*
X537579D03*
X535729Y864197D03*
X543128D03*
X546828D03*
X535729Y857789D03*
X543130D03*
X539429D03*
X541279Y860993D03*
Y854584D03*
X539428Y877014D03*
X543129D03*
X539429Y883423D03*
X543129D03*
X537578Y873810D03*
Y880219D03*
X544979Y873810D03*
Y880219D03*
X546828Y877014D03*
X546829Y870606D03*
X541279Y873810D03*
X535729Y870606D03*
Y883423D03*
X541279Y880219D03*
X546829Y883423D03*
X539429D03*
X537578Y880219D03*
X543129Y883423D03*
X544979Y880219D03*
X537578Y873810D03*
X539429Y870606D03*
X544979Y873810D03*
X543129Y870606D03*
X539428Y877014D03*
X546828D03*
X535729D03*
X543129D03*
X537579Y893036D03*
X541279Y886627D03*
X544979D03*
X537579D03*
X535729Y889832D03*
X550529D03*
X537579Y899445D03*
X548679Y912262D03*
X537579D03*
X539429Y909057D03*
X537579Y905853D03*
X535729Y909057D03*
X543129D03*
X535729Y902649D03*
X548679Y905853D03*
X543129Y928283D03*
X539429D03*
X537579Y918670D03*
X537578Y925079D03*
X535729Y928283D03*
Y921875D03*
X548678Y925079D03*
X537578Y931488D03*
X548678D03*
X537579Y937896D03*
X537578Y944304D03*
X535729Y941100D03*
X548678Y944304D03*
X539429Y947509D03*
X535729D03*
X549278Y949619D03*
X549719Y962436D03*
X537579Y957122D03*
Y950713D03*
X535729Y960326D03*
Y966735D03*
X537579Y963530D03*
X548146Y965640D03*
X539429Y979552D03*
X537579Y982756D03*
X541279Y969939D03*
X539429Y973143D03*
X535729D03*
X543729Y984866D03*
X539862Y1006092D03*
X539861Y999684D03*
X536161D03*
Y1006093D03*
X543563Y1006092D03*
X549254Y1000648D03*
X536161Y1012501D03*
Y1025318D03*
X539861Y1018910D03*
X541712Y1015705D03*
X545412D03*
X538012D03*
X536161Y1018910D03*
X549112Y1015705D03*
X536161Y1031727D03*
X545412Y1034931D03*
X539862Y1044544D03*
X539861Y1038136D03*
X541711Y1034931D03*
X538011D03*
X536161Y1038136D03*
X549112Y1034931D03*
X541711Y1054157D03*
X538011D03*
X536161Y1057361D03*
X545411Y1054157D03*
X538011Y1060565D03*
X536161Y1050952D03*
X549422Y1064850D03*
X538011Y1066974D03*
X541711Y1073383D03*
X545411Y1066974D03*
X539861Y1076587D03*
X536161D03*
X536162Y1070178D03*
X538011Y1073383D03*
X547262Y1070178D03*
X536162Y1082996D03*
X538011Y1092608D03*
X536161Y1089404D03*
X545411Y1092608D03*
X547262Y1082996D03*
X543561Y1095813D03*
X536161D03*
X547261D03*
X545412Y1105426D03*
X541711D03*
X539861Y1108630D03*
Y1102221D03*
X536161D03*
X541711Y1111834D03*
X545411D03*
X538011Y1105426D03*
X536161Y1108630D03*
X538011Y1111834D03*
X543561Y1108630D03*
X545411Y1124651D03*
Y1118243D03*
X543562Y1115039D03*
X539862D03*
X538011Y1124651D03*
X536161Y1115039D03*
X541711Y1118243D03*
X538010Y1118242D03*
X543561Y1121446D03*
X539861Y1127855D03*
X536161D03*
Y1121446D03*
X539861D03*
X541711Y1124650D03*
X543561Y1127855D03*
X541711Y1131060D03*
X536162Y1134264D03*
X538012Y1131059D03*
X543211Y1578182D03*
X538951D03*
X543211Y1590094D03*
X538951D03*
X548511Y1614292D03*
Y1602380D03*
X536451D03*
Y1614292D03*
X544251Y1602380D03*
Y1614292D03*
X544685Y1675383D03*
Y1679920D03*
X536811Y1679320D03*
X544685Y1684454D03*
Y1689556D03*
Y1694093D03*
Y1698627D03*
X536811Y1688391D03*
Y1693493D03*
Y1698030D03*
Y1683857D03*
X544685Y1703729D03*
Y1708266D03*
Y1712800D03*
X536811Y1707666D03*
Y1712203D03*
Y1702564D03*
X544685Y1726974D03*
Y1722440D03*
Y1717903D03*
X536811Y1730911D03*
Y1726377D03*
Y1721840D03*
Y1716737D03*
X551429Y979057D03*
X550701Y972608D03*
X550961Y1031727D03*
X555271Y1578182D03*
X563071D03*
X551011D03*
X555271Y1590094D03*
X563071D03*
X551011D03*
X560571Y1614292D03*
Y1602380D03*
X556311Y1614292D03*
Y1602380D03*
X552559Y1679320D03*
X564370Y1675383D03*
Y1679920D03*
X552559Y1688391D03*
Y1693493D03*
Y1698030D03*
Y1683857D03*
X564370Y1684454D03*
Y1689556D03*
Y1694093D03*
Y1698627D03*
X552559Y1707666D03*
Y1712203D03*
Y1702564D03*
X564370Y1703729D03*
Y1708266D03*
Y1712800D03*
X552559Y1730911D03*
Y1726377D03*
Y1721840D03*
Y1716737D03*
X564370Y1726974D03*
Y1722440D03*
Y1717903D03*
X579391Y1578182D03*
X567331D03*
X575131D03*
X579391Y1590094D03*
X567331D03*
X575131D03*
X580431Y1614292D03*
X572631D03*
X580431Y1602380D03*
X572631D03*
X568371D03*
Y1614292D03*
X580118Y1675383D03*
Y1679920D03*
X572244Y1679320D03*
X580118Y1684454D03*
Y1689556D03*
Y1694093D03*
Y1698627D03*
X572244Y1688391D03*
Y1693493D03*
Y1698030D03*
Y1683857D03*
X580118Y1703729D03*
Y1708266D03*
Y1712800D03*
X572244Y1707666D03*
Y1712203D03*
Y1702564D03*
X580118Y1726974D03*
Y1722440D03*
Y1717903D03*
X572244Y1730911D03*
Y1726377D03*
Y1721840D03*
Y1716737D03*
X599251Y1578182D03*
X591451D03*
X587191D03*
X599251Y1590094D03*
X591451D03*
X587191D03*
X596751Y1614292D03*
Y1602380D03*
X584691D03*
Y1614292D03*
X592491Y1602380D03*
Y1614292D03*
X595866Y1675383D03*
Y1679920D03*
X587992Y1679320D03*
X595866Y1684454D03*
Y1689556D03*
Y1694093D03*
Y1698627D03*
X587992Y1688391D03*
Y1693493D03*
Y1698030D03*
Y1683857D03*
X595866Y1703729D03*
Y1708266D03*
Y1712800D03*
X587992Y1707666D03*
Y1712203D03*
Y1702564D03*
X595866Y1726974D03*
Y1722440D03*
Y1717903D03*
X587992Y1730911D03*
Y1726377D03*
Y1721840D03*
Y1716737D03*
X615571Y1578182D03*
X603511D03*
X611311D03*
X615571Y1590094D03*
X603511D03*
X611311D03*
X608811Y1602380D03*
Y1614292D03*
X604551Y1602380D03*
Y1614292D03*
X611614Y1675383D03*
Y1679920D03*
X603740Y1679320D03*
X611614Y1684454D03*
Y1689556D03*
Y1694093D03*
Y1698627D03*
X603740Y1688391D03*
Y1693493D03*
Y1698030D03*
Y1683857D03*
X611614Y1703729D03*
Y1708266D03*
Y1712800D03*
X603740Y1707666D03*
Y1712203D03*
Y1702564D03*
X611614Y1726974D03*
Y1722440D03*
Y1717903D03*
X603740Y1730911D03*
Y1726377D03*
Y1721840D03*
Y1716737D03*
X629599Y770144D03*
X620899D03*
X629658Y766478D03*
X629599Y783530D03*
X620899D03*
X629599Y776837D03*
X620899D03*
X620846Y800263D03*
X629599D03*
Y793570D03*
X620899D03*
Y820341D03*
X629599D03*
X620076Y813648D03*
X630593D03*
X619632Y806955D03*
X630792D03*
X620899Y830381D03*
X629599D03*
X620005Y850459D03*
X630754D03*
X620899Y843766D03*
X629599D03*
Y837074D03*
X620899D03*
Y867192D03*
X629599D03*
X620058Y857152D03*
X630481D03*
X620799Y883924D03*
X620899Y880577D03*
X629599D03*
X620899Y873885D03*
X629599D03*
X620799Y883924D03*
Y900656D03*
Y897310D03*
Y890617D03*
X630756Y893963D03*
X620899D03*
X629599Y887270D03*
X620899D03*
X620799Y890617D03*
Y897310D03*
Y900656D03*
Y907349D03*
Y914042D03*
X620899Y910696D03*
X629599D03*
Y917389D03*
X620899D03*
X629599Y904003D03*
X620899D03*
X620799Y914042D03*
Y907349D03*
X630399Y930697D03*
X619905Y930774D03*
X620899Y924081D03*
X629599D03*
Y947507D03*
X620899D03*
X619964Y940814D03*
X630777D03*
X620799Y957546D03*
Y960892D03*
X629599Y964239D03*
X620899D03*
X629599Y954200D03*
X620899D03*
X620799Y960892D03*
Y957546D03*
X620899Y977625D03*
X629599D03*
Y970932D03*
X620899D03*
Y991011D03*
X629599D03*
Y984318D03*
X620899D03*
X623347Y999665D03*
X625780Y1000198D03*
X620899Y1031168D03*
X629599D03*
X620899Y1017782D03*
X629599D03*
X620899Y1024475D03*
X629599D03*
X620899Y1044554D03*
X629599D03*
X620899Y1037861D03*
X629599D03*
X620899Y1057940D03*
X629599D03*
Y1051247D03*
X620899D03*
Y1061286D03*
Y1078018D03*
X629599D03*
X630399Y1071326D03*
X619999D03*
X620899Y1064633D03*
X629599D03*
X620899Y1088058D03*
X629599D03*
Y1094751D03*
X620899D03*
Y1108137D03*
X629599D03*
Y1101444D03*
X620899D03*
X630363Y1124674D03*
X620369Y1124969D03*
X630399Y1114829D03*
X620099D03*
X620899Y1131562D03*
X629599D03*
Y1144948D03*
X620899D03*
X629599Y1138255D03*
X620899D03*
X620511Y1161680D03*
X629833Y1161581D03*
X629599Y1151641D03*
X620899D03*
X620799Y1178412D03*
X629599Y1175066D03*
X620899D03*
X629599Y1168373D03*
X620899D03*
X620799Y1191798D03*
Y1185105D03*
Y1195144D03*
X630623Y1188452D03*
X620899D03*
X629599Y1181759D03*
X620899D03*
X620799Y1185105D03*
Y1178412D03*
Y1191798D03*
Y1208530D03*
Y1201837D03*
X629599Y1205184D03*
X620899D03*
Y1198491D03*
X629599D03*
X620799Y1208530D03*
Y1201837D03*
Y1195144D03*
X620899Y1225263D03*
X629599D03*
Y1218570D03*
X620899D03*
X629599Y1211877D03*
X620899D03*
X629599Y1241995D03*
X620899D03*
X630922Y1235302D03*
X620036D03*
X620899Y1248688D03*
X629599D03*
X629931Y1258727D03*
X629699Y1255381D03*
X625246Y1273164D03*
X627646D03*
X631270Y1264942D03*
X627631Y1578182D03*
X623371D03*
X627631Y1590094D03*
X623371D03*
X628671Y1602380D03*
Y1614292D03*
X620871D03*
Y1602380D03*
X616611Y1614292D03*
Y1602380D03*
X619488Y1679320D03*
Y1688391D03*
Y1693493D03*
Y1698030D03*
Y1683857D03*
Y1707666D03*
Y1712203D03*
Y1702564D03*
Y1730911D03*
Y1726377D03*
Y1721840D03*
Y1716737D03*
X637041Y766798D03*
X645741D03*
Y773491D03*
X637041D03*
X645741Y780184D03*
X637041D03*
Y803609D03*
X645741D03*
X637041Y796916D03*
X645741D03*
Y790223D03*
X637041D03*
X636221Y810302D03*
X646844D03*
X646774Y816995D03*
X637041D03*
X645741Y833727D03*
X637041D03*
Y827034D03*
X645741D03*
X637041Y847113D03*
X645801D03*
X637041Y840420D03*
X645741D03*
X646819Y853806D03*
X636332Y853955D03*
X645918Y863845D03*
X636266D03*
X636941Y880577D03*
Y887270D03*
X637041Y877231D03*
X645741D03*
X637041Y870538D03*
X645741D03*
Y883924D03*
X637041D03*
X636941Y880577D03*
Y897310D03*
Y893963D03*
Y904003D03*
X637041Y900656D03*
X645741D03*
X637041Y890617D03*
X645741D03*
X636941Y887270D03*
Y897310D03*
Y893963D03*
Y910696D03*
X637041Y914042D03*
X645741D03*
Y907349D03*
X637041D03*
X636941Y910696D03*
Y904003D03*
X646393Y927526D03*
X636026Y927428D03*
X645741Y920735D03*
X637041D03*
X645741Y944160D03*
X637041D03*
X636170Y937467D03*
X646703D03*
X645741Y960892D03*
X637041D03*
Y950853D03*
X645741D03*
X636941Y957546D03*
Y954200D03*
X637041Y980971D03*
X645741D03*
X637041Y974278D03*
X645741D03*
X637041Y967585D03*
X645741D03*
X637041Y987664D03*
X645741D03*
X644347Y1003135D03*
X640327D03*
X640467Y1000735D03*
X647447Y1002865D03*
X647397Y1000135D03*
X644257Y1000325D03*
X637041Y1027822D03*
X645741D03*
Y1017782D03*
X637041D03*
X645741Y1047900D03*
X637041D03*
Y1041207D03*
X645741D03*
X637041Y1034515D03*
X645741D03*
X637041Y1061286D03*
X645741D03*
Y1054593D03*
X637041D03*
X636141Y1074672D03*
X646541D03*
X645741Y1067979D03*
X636841D03*
X637041Y1091404D03*
X645741D03*
Y1084711D03*
X636241D03*
X645741Y1111483D03*
X637041D03*
X645741Y1098097D03*
X637041D03*
X645741Y1104790D03*
X637041D03*
Y1121522D03*
X645741D03*
X637041Y1128915D03*
X645741Y1128215D03*
X646584Y1135108D03*
X635744Y1134908D03*
X645741Y1141601D03*
X637041D03*
X645741Y1148294D03*
X637041D03*
X645741Y1158333D03*
X637041D03*
X636941Y1175066D03*
X637041Y1171719D03*
X645741D03*
Y1165026D03*
X637041D03*
X636941Y1175066D03*
Y1188451D03*
Y1191798D03*
Y1181759D03*
X637041Y1185105D03*
X645741D03*
Y1178412D03*
X637041D03*
X636941Y1181759D03*
Y1191798D03*
Y1188451D03*
Y1198491D03*
Y1205184D03*
X645741Y1208530D03*
X637041D03*
X645741Y1201837D03*
X637041D03*
Y1195144D03*
X645741D03*
X636941Y1205184D03*
Y1198491D03*
X636005Y1221916D03*
X646570D03*
X645741Y1215223D03*
X637041D03*
X645741Y1238648D03*
X637041D03*
X635995Y1231862D03*
X646539Y1231955D03*
X645741Y1245341D03*
X637041D03*
X634213Y1258679D03*
X636946Y1258414D03*
X637041Y1252034D03*
X645897Y1248785D03*
X647877Y1254076D03*
X642746Y1273364D03*
X639946D03*
X636877Y1261235D03*
X647491Y1578088D03*
X639691Y1578182D03*
X635431D03*
X647491Y1590094D03*
X639691D03*
X635431D03*
X644991Y1614292D03*
Y1602380D03*
X632931D03*
Y1614292D03*
X640731D03*
Y1602380D03*
X650599Y770144D03*
X659299D03*
X650599Y783530D03*
X659299D03*
X650599Y776837D03*
X659299D03*
Y800263D03*
X650599D03*
Y793570D03*
X659299D03*
Y806955D03*
X650599D03*
X660432Y813648D03*
X650599D03*
X660199Y820341D03*
X650599D03*
X659299Y830381D03*
X650599D03*
X659299Y850459D03*
X650599D03*
X659299Y843766D03*
X650599D03*
Y837074D03*
X659299D03*
Y857152D03*
X650599D03*
X649563Y867192D03*
X660299D03*
X659299Y873885D03*
X650599D03*
Y880577D03*
X659299D03*
X650599Y893963D03*
X659299D03*
X650599Y887270D03*
X659299D03*
Y917389D03*
X650599D03*
X659299Y910696D03*
X650599D03*
Y904003D03*
X659299D03*
X660504Y924081D03*
X650599D03*
X660174Y930774D03*
X649661D03*
X659299Y947507D03*
X650599D03*
X659299Y940814D03*
X650599D03*
X650499Y957546D03*
Y960892D03*
X659299Y964239D03*
X650599D03*
Y954200D03*
X659299D03*
X650499Y960892D03*
Y957546D03*
X659299Y977625D03*
X650599D03*
X659299Y970932D03*
X650599D03*
X659299Y991011D03*
X650599D03*
X659299Y984318D03*
X650599D03*
X650107Y1002825D03*
X659299Y1031168D03*
X650599D03*
X659299Y1017782D03*
X650599D03*
X659299Y1024475D03*
X650599D03*
X659299Y1044554D03*
X650599D03*
X659299Y1037861D03*
X650599D03*
X659299Y1051247D03*
X650599D03*
Y1057940D03*
X659299D03*
X660099Y1078018D03*
X649799D03*
X659299Y1071326D03*
X650599D03*
X659299Y1064633D03*
X650599D03*
X659299Y1094751D03*
X650599D03*
X660099Y1088058D03*
X649799D03*
X650599Y1108137D03*
X659299D03*
X650599Y1101444D03*
X659299D03*
X660199Y1124869D03*
X649932Y1124640D03*
X659299Y1114829D03*
X650599D03*
X659299Y1130762D03*
X650599D03*
X659299Y1138255D03*
X650599D03*
X659299Y1144948D03*
X650599D03*
X659299Y1151641D03*
X650599D03*
Y1161680D03*
X659299D03*
X650599Y1175066D03*
X659299D03*
X650599Y1168373D03*
X659299D03*
X650599Y1188452D03*
X659299D03*
X650599Y1181759D03*
X659299D03*
X650599Y1205184D03*
X659299D03*
X650599Y1198491D03*
X659299D03*
X660070Y1225263D03*
X649913D03*
X659299Y1218570D03*
X650599D03*
X659299Y1211877D03*
X650599D03*
X659299Y1241995D03*
X650599D03*
X660234Y1235302D03*
X649701D03*
X650599Y1248688D03*
X659299D03*
X659546Y1257664D03*
X650599Y1258727D03*
X656446Y1273364D03*
X653646D03*
X649587Y1266766D03*
X651751Y1578182D03*
X659551D03*
X651751Y1590094D03*
X659551D03*
X657051Y1602380D03*
Y1614292D03*
X652791Y1602286D03*
Y1614292D03*
X680299Y773491D03*
Y770144D03*
X675441Y766798D03*
X666741D03*
X680299D03*
Y786877D03*
Y780184D03*
Y783530D03*
Y776837D03*
X666741Y773491D03*
X675441D03*
X666741Y780184D03*
X675441D03*
X680299D03*
Y773491D03*
Y786877D03*
Y803609D03*
Y790223D03*
Y796916D03*
X675441Y803609D03*
X666741D03*
X680299Y800263D03*
Y793570D03*
X666741Y796916D03*
X675441D03*
X666741Y790223D03*
X675441D03*
X680299Y803609D03*
Y796916D03*
Y790223D03*
Y816995D03*
Y810302D03*
X676403Y816995D03*
X665803D03*
X675441Y810302D03*
X666741D03*
X680299Y820341D03*
Y813648D03*
Y806955D03*
Y816995D03*
Y810302D03*
Y823688D03*
Y833727D03*
Y827034D03*
X675441Y833727D03*
X666741D03*
X676625Y827034D03*
X665876D03*
X680299Y830381D03*
Y833727D03*
Y823688D03*
Y827034D03*
Y847113D03*
Y840420D03*
Y853806D03*
X675441Y847113D03*
X666741D03*
X680299Y850459D03*
Y843766D03*
Y837074D03*
X666741Y840420D03*
X675441D03*
X680299Y847113D03*
Y840420D03*
Y860499D03*
Y863845D03*
Y870538D03*
X676417Y853806D03*
X665890D03*
X680299Y867192D03*
Y857152D03*
X665916Y863845D03*
X676600D03*
X680299Y853806D03*
Y860499D03*
Y863845D03*
Y883924D03*
Y877231D03*
X675441D03*
X666741D03*
X675441Y870538D03*
X666741D03*
Y883924D03*
X675441D03*
X680299Y880577D03*
Y873885D03*
Y883924D03*
Y877231D03*
Y870538D03*
Y897310D03*
Y900656D03*
Y890617D03*
X666741Y900656D03*
X675441D03*
X680299Y893963D03*
Y887270D03*
X666741Y890617D03*
X675441D03*
X680299D03*
Y897310D03*
Y900656D03*
Y907349D03*
Y914042D03*
X675441D03*
X666741D03*
X680299Y917389D03*
Y910696D03*
Y904003D03*
X666741Y907349D03*
X675441D03*
X680299Y914042D03*
Y907349D03*
Y920735D03*
Y934121D03*
Y927428D03*
X676488D03*
X665896D03*
X675441Y920735D03*
X666741D03*
X680299Y930774D03*
Y924081D03*
Y927428D03*
Y920735D03*
Y934121D03*
Y937467D03*
Y944160D03*
Y950853D03*
X675441Y944160D03*
X666741D03*
X676359Y937467D03*
X665923D03*
X680299Y947507D03*
Y940814D03*
Y944160D03*
Y937467D03*
Y957546D03*
Y960892D03*
Y967585D03*
Y964239D03*
X675441Y960892D03*
X666741D03*
X680299Y954200D03*
X666741Y950853D03*
X675441D03*
X680299Y960892D03*
Y950853D03*
Y957546D03*
X666641D03*
Y954200D03*
X680299Y980971D03*
Y974278D03*
X675441Y980971D03*
X666741D03*
X680299Y970932D03*
X675441Y974278D03*
X666741D03*
X675441Y967585D03*
X666741D03*
X680299Y977625D03*
Y980971D03*
Y974278D03*
Y967585D03*
Y994357D03*
Y987664D03*
X675441D03*
X666741D03*
X680299Y991011D03*
Y984318D03*
Y994357D03*
Y987664D03*
X672063Y998632D03*
X679999Y1027822D03*
X680299Y1021129D03*
Y1031168D03*
Y1024475D03*
X675441Y1027822D03*
X666741D03*
X675441Y1017782D03*
X666741D03*
X680299D03*
X679999Y1027822D03*
X680299Y1021129D03*
X679999Y1041207D03*
Y1034514D03*
Y1047900D03*
X675441D03*
X666741D03*
X680299Y1037861D03*
X675441Y1041207D03*
X666741D03*
X675441Y1034515D03*
X666741D03*
X680299Y1044554D03*
X679999Y1047900D03*
Y1041207D03*
Y1034514D03*
Y1054593D03*
X680299Y1057940D03*
Y1051247D03*
X675441Y1054593D03*
X666741D03*
Y1061286D03*
X675441D03*
X680299D03*
X679999Y1054593D03*
X680299Y1067979D03*
Y1074672D03*
Y1081365D03*
X676341Y1074672D03*
X665841D03*
X675441Y1067979D03*
X666741D03*
X680299Y1078018D03*
Y1071326D03*
Y1064633D03*
Y1074672D03*
Y1067979D03*
Y1084711D03*
Y1091404D03*
Y1098097D03*
X675441Y1091404D03*
X666741D03*
X676241Y1084711D03*
X665941D03*
X680299Y1094751D03*
Y1088058D03*
Y1091404D03*
Y1081365D03*
Y1084711D03*
Y1104790D03*
Y1111483D03*
X666741D03*
X675441D03*
X680299Y1108137D03*
Y1101444D03*
X666741Y1104790D03*
X675441D03*
X666741Y1098097D03*
X675441D03*
X680299D03*
Y1111483D03*
Y1104790D03*
Y1118176D03*
Y1121522D03*
Y1128215D03*
X666741D03*
X675441D03*
X680299Y1124869D03*
Y1114829D03*
X666741Y1121522D03*
X675441D03*
X680299Y1128215D03*
Y1118176D03*
Y1121522D03*
Y1141601D03*
Y1134908D03*
Y1144948D03*
Y1138255D03*
Y1131562D03*
X666741Y1141601D03*
X675441D03*
X666741Y1134908D03*
X675441D03*
X680299Y1141601D03*
Y1134908D03*
Y1158333D03*
Y1148294D03*
Y1154987D03*
X676652Y1148294D03*
X665602D03*
X676241Y1158333D03*
X665941D03*
X680299Y1161680D03*
Y1151641D03*
Y1148294D03*
Y1154987D03*
Y1158333D03*
Y1171719D03*
Y1165026D03*
Y1178412D03*
X675441Y1165026D03*
X666741D03*
X680299Y1175066D03*
Y1168373D03*
X666741Y1171719D03*
X675441D03*
X680299D03*
Y1165026D03*
Y1191798D03*
Y1185105D03*
Y1195144D03*
Y1188452D03*
Y1181759D03*
X666741Y1185105D03*
X675441D03*
X666741Y1178412D03*
X675441D03*
X680299Y1185105D03*
Y1178412D03*
Y1191798D03*
Y1208530D03*
Y1201837D03*
Y1205184D03*
Y1198491D03*
X666741Y1208530D03*
X675441D03*
X666741Y1201837D03*
X675441D03*
X666741Y1195144D03*
X675441D03*
X680299Y1208530D03*
Y1201837D03*
Y1195144D03*
Y1215223D03*
Y1221916D03*
Y1228609D03*
Y1218570D03*
Y1225263D03*
X676448Y1221916D03*
X665651D03*
X675441Y1215223D03*
X666741D03*
X680299Y1211877D03*
Y1221916D03*
Y1215223D03*
Y1231955D03*
Y1238648D03*
Y1245341D03*
X675441Y1238648D03*
X666741D03*
X676462Y1231955D03*
X665912D03*
X680299Y1241995D03*
Y1235302D03*
Y1238648D03*
Y1228609D03*
Y1231955D03*
X675441Y1245341D03*
X666741D03*
X676046Y1257964D03*
X680299Y1248688D03*
Y1245341D03*
Y1258727D03*
X666741Y1252034D03*
X675537Y1248885D03*
X672446Y1273364D03*
X669646D03*
X666741Y1262074D03*
X666646Y1264464D03*
X680046Y1264964D03*
X664851Y1602380D03*
Y1614292D03*
X696441Y770144D03*
Y766798D03*
X688999Y770144D03*
X696441D03*
Y776837D03*
Y786877D03*
Y783530D03*
Y773491D03*
Y780184D03*
X688999Y783530D03*
Y776837D03*
X696441D03*
Y786877D03*
Y783530D03*
Y800263D03*
Y793570D03*
Y803609D03*
Y796916D03*
Y790223D03*
X688999Y800263D03*
Y793570D03*
X696441Y800263D03*
Y793570D03*
Y806955D03*
Y813648D03*
Y820341D03*
Y816995D03*
Y810302D03*
X689888Y820341D03*
X688999Y813648D03*
Y806955D03*
X696441Y813648D03*
Y806955D03*
Y820341D03*
Y823688D03*
Y830381D03*
Y837074D03*
Y833727D03*
Y827034D03*
X688999Y830381D03*
X696441D03*
Y823688D03*
Y850459D03*
Y843766D03*
Y847113D03*
X688999Y850459D03*
X696441Y840420D03*
X688999Y843766D03*
Y837074D03*
X696441Y850459D03*
Y843766D03*
Y837074D03*
Y867192D03*
Y857152D03*
Y860499D03*
Y863845D03*
Y853806D03*
X688999Y867192D03*
X689896Y857152D03*
X696441Y867192D03*
Y860499D03*
Y857152D03*
Y873885D03*
Y880577D03*
Y887270D03*
Y883924D03*
Y877231D03*
Y870538D03*
X688999Y880577D03*
Y873885D03*
X696441D03*
Y880577D03*
Y897310D03*
Y893963D03*
Y904003D03*
Y900656D03*
Y890617D03*
X688999Y893963D03*
Y887270D03*
X696441D03*
Y897310D03*
Y893963D03*
Y917389D03*
Y910696D03*
Y914042D03*
Y907349D03*
X688999Y917389D03*
Y910696D03*
Y904003D03*
X696441Y917389D03*
Y910696D03*
Y904003D03*
Y924081D03*
Y930774D03*
Y934121D03*
Y927428D03*
Y920735D03*
X690104Y930774D03*
X688999Y924081D03*
X696441D03*
Y934121D03*
Y930774D03*
Y947507D03*
Y940814D03*
Y944160D03*
Y937467D03*
X688999Y947507D03*
Y940814D03*
X696441Y947507D03*
Y940814D03*
Y964239D03*
Y960892D03*
Y950853D03*
X688999Y964239D03*
Y954200D03*
X696441Y964239D03*
Y957546D03*
Y954200D03*
Y970932D03*
Y977625D03*
Y984318D03*
Y980971D03*
Y974278D03*
Y967585D03*
X688999Y970932D03*
Y977625D03*
X696441D03*
Y970932D03*
Y991011D03*
Y987664D03*
X688999Y991011D03*
Y984318D03*
X696441Y991011D03*
Y984318D03*
Y994357D03*
Y1021129D03*
Y1031168D03*
Y1024475D03*
Y1027822D03*
Y1017782D03*
X688999Y1031168D03*
Y1024475D03*
Y1017782D03*
X696441Y1021129D03*
Y1024475D03*
Y1031168D03*
X696141Y1037861D03*
Y1044554D03*
X696441Y1047900D03*
Y1041207D03*
Y1034515D03*
X688999Y1037861D03*
Y1044554D03*
X696141D03*
Y1037861D03*
X696441Y1051247D03*
Y1064633D03*
Y1054593D03*
Y1061286D03*
X688999Y1057940D03*
Y1051247D03*
X696441D03*
Y1071325D03*
Y1078018D03*
Y1081365D03*
Y1074672D03*
Y1067979D03*
X688999Y1077118D03*
Y1071326D03*
Y1064633D03*
X696441Y1071325D03*
Y1064633D03*
Y1078018D03*
Y1094751D03*
Y1088058D03*
Y1091404D03*
Y1084711D03*
X688999Y1094751D03*
Y1088058D03*
X696441Y1094751D03*
Y1088058D03*
Y1081365D03*
Y1101444D03*
Y1108136D03*
Y1114829D03*
Y1111483D03*
Y1104790D03*
Y1098097D03*
X688999Y1108137D03*
Y1101444D03*
X696441Y1108136D03*
Y1101444D03*
Y1118176D03*
Y1124869D03*
Y1131562D03*
Y1128215D03*
Y1121522D03*
X688999Y1124869D03*
Y1114829D03*
X696441Y1124869D03*
Y1118176D03*
Y1114829D03*
Y1144947D03*
Y1138255D03*
Y1141601D03*
Y1134908D03*
X688999Y1144948D03*
Y1138255D03*
Y1131562D03*
X696441Y1144947D03*
Y1138255D03*
Y1131562D03*
Y1161680D03*
Y1151640D03*
Y1154987D03*
Y1158333D03*
Y1148294D03*
X688999Y1161680D03*
X689999Y1151641D03*
X696441Y1161680D03*
Y1154987D03*
Y1151640D03*
Y1175066D03*
Y1168373D03*
Y1171719D03*
Y1165026D03*
X688999Y1175066D03*
Y1168373D03*
X696441Y1175066D03*
Y1168373D03*
Y1188451D03*
Y1181758D03*
Y1191798D03*
Y1185105D03*
Y1178412D03*
X688999Y1188452D03*
Y1181759D03*
X696441Y1181758D03*
Y1191798D03*
Y1188451D03*
Y1205184D03*
Y1198491D03*
Y1211877D03*
Y1208530D03*
Y1201837D03*
Y1195144D03*
X688999Y1205184D03*
Y1198491D03*
X696441Y1205184D03*
Y1198491D03*
Y1225262D03*
Y1218569D03*
Y1228609D03*
Y1221916D03*
Y1215223D03*
X688999Y1218570D03*
X689799Y1225263D03*
X688999Y1211877D03*
X696441Y1218569D03*
Y1211877D03*
Y1225262D03*
Y1241995D03*
Y1235302D03*
Y1238648D03*
Y1231955D03*
X688999Y1241995D03*
Y1235302D03*
X696441Y1241995D03*
Y1235302D03*
Y1228609D03*
X688916Y1256964D03*
X696441Y1245341D03*
X688999Y1248688D03*
X696441Y1255381D03*
Y1248688D03*
X686146Y1273364D03*
X683346D03*
X696046Y1263764D03*
X709999Y770144D03*
X705141Y766798D03*
X709899D03*
X709999Y783530D03*
Y776837D03*
X705141Y773491D03*
Y780184D03*
X709999Y800263D03*
Y793570D03*
X705141Y803609D03*
Y796916D03*
Y790223D03*
X709999Y820341D03*
Y813648D03*
Y806955D03*
X705141Y816995D03*
Y810302D03*
X709999Y830381D03*
X705141Y833727D03*
Y827034D03*
Y847113D03*
X709999Y850459D03*
Y843766D03*
Y837074D03*
X705141Y840420D03*
Y863845D03*
Y853806D03*
X709999Y867192D03*
Y857152D03*
X705141Y883924D03*
Y877231D03*
Y870538D03*
X709999Y880577D03*
Y873885D03*
X705141Y900656D03*
Y890617D03*
X709999Y893963D03*
Y887270D03*
X705141Y914042D03*
Y907349D03*
X709999Y917389D03*
Y910696D03*
Y904003D03*
X705141Y927428D03*
Y920735D03*
X709999Y930774D03*
Y924081D03*
X705141Y944160D03*
Y937467D03*
X709999Y947507D03*
Y940814D03*
X709899Y957546D03*
Y960892D03*
X709999Y967585D03*
X705141Y960892D03*
Y950853D03*
X709999Y964239D03*
Y954200D03*
X709899Y960892D03*
Y957546D03*
X705141Y980971D03*
Y974278D03*
Y967585D03*
X709999Y977625D03*
Y970932D03*
Y967585D03*
X705141Y987664D03*
X709999Y991011D03*
Y984318D03*
X705141Y1027822D03*
Y1017782D03*
X709999Y1031168D03*
Y1024475D03*
Y1017782D03*
X705141Y1047900D03*
Y1041207D03*
Y1034515D03*
X709999Y1044554D03*
Y1037861D03*
Y1054593D03*
X705141D03*
Y1061286D03*
X709999Y1057940D03*
Y1051247D03*
Y1054593D03*
X705141Y1074672D03*
Y1067979D03*
X709999Y1078018D03*
Y1071326D03*
Y1064633D03*
X705141Y1091404D03*
Y1084711D03*
X709999Y1094751D03*
Y1088058D03*
X705141Y1111483D03*
Y1104790D03*
Y1098097D03*
X709999Y1108137D03*
Y1101444D03*
X705141Y1128215D03*
Y1121522D03*
X709999Y1124869D03*
Y1114829D03*
X705141Y1141601D03*
Y1134908D03*
X709999Y1144948D03*
Y1138255D03*
Y1131562D03*
X705141Y1158333D03*
Y1148294D03*
X709999Y1161680D03*
Y1151641D03*
X705141Y1171719D03*
Y1165026D03*
X709999Y1175066D03*
Y1168373D03*
X705141Y1185105D03*
Y1178412D03*
X709999Y1188452D03*
Y1181759D03*
X705141Y1208530D03*
Y1201837D03*
Y1195144D03*
X709999Y1205184D03*
Y1198491D03*
X705141Y1221916D03*
Y1215223D03*
X709999Y1225263D03*
Y1218570D03*
Y1211877D03*
X705141Y1238648D03*
Y1231955D03*
X709999Y1241995D03*
Y1235302D03*
X705141Y1245341D03*
X709999Y1248688D03*
Y1258727D03*
X705037Y1252034D03*
X706493Y1256563D03*
X713046Y1273364D03*
X702146D03*
X699346D03*
X705167Y1262074D03*
X709977Y1264985D03*
X726141Y766798D03*
X718699Y770144D03*
X726141Y773491D03*
Y780184D03*
X718699Y783530D03*
Y776837D03*
X726141Y803609D03*
Y796916D03*
Y790223D03*
X718699Y800263D03*
Y793570D03*
X726141Y816995D03*
Y810302D03*
X718699Y820341D03*
Y813648D03*
Y806955D03*
X726141Y833727D03*
Y827034D03*
X718699Y830381D03*
X726141Y847113D03*
Y840420D03*
X718699Y850459D03*
Y843766D03*
Y837074D03*
X726141Y863845D03*
Y853806D03*
X718699Y867192D03*
Y857152D03*
X726141Y883924D03*
Y877231D03*
Y870538D03*
X718699Y880577D03*
Y873885D03*
X726141Y900656D03*
Y890617D03*
X718699Y893963D03*
Y887270D03*
X726141Y914042D03*
Y907349D03*
X718699Y917389D03*
Y910696D03*
Y904003D03*
X726141Y927428D03*
Y920735D03*
X718699Y930774D03*
Y924081D03*
X726141Y944160D03*
Y937467D03*
X718699Y947507D03*
Y940814D03*
X726141Y964239D03*
Y960892D03*
Y950853D03*
X718699Y964239D03*
Y954200D03*
X726141Y964239D03*
X726041Y957546D03*
Y954200D03*
X726141Y980971D03*
Y974278D03*
Y967585D03*
X718699Y977625D03*
Y970932D03*
X726141Y987664D03*
X718699Y991011D03*
Y984318D03*
X726041Y994357D03*
X726141Y1024475D03*
Y1021129D03*
Y1027822D03*
Y1017782D03*
X718699Y1031168D03*
Y1024475D03*
Y1017782D03*
X726141Y1021129D03*
Y1024475D03*
Y1047900D03*
Y1041207D03*
Y1034515D03*
X718699Y1044554D03*
Y1037861D03*
X726141Y1051247D03*
Y1061286D03*
Y1054593D03*
X718699Y1057940D03*
Y1051247D03*
X726141D03*
Y1057940D03*
Y1074672D03*
Y1067979D03*
X718699Y1078018D03*
Y1071326D03*
Y1064633D03*
X726141Y1091404D03*
Y1084711D03*
X718699Y1094751D03*
Y1088058D03*
X726141Y1111483D03*
Y1104790D03*
Y1098097D03*
X718699Y1108137D03*
Y1101444D03*
X726141Y1128215D03*
Y1121522D03*
X718699Y1124869D03*
Y1114829D03*
X726141Y1141601D03*
Y1134908D03*
X718699Y1144948D03*
Y1138255D03*
Y1131562D03*
X726141Y1158333D03*
Y1148294D03*
X718699Y1161680D03*
Y1151641D03*
X726141Y1171719D03*
Y1165026D03*
X718699Y1175066D03*
Y1168373D03*
X726141Y1185105D03*
Y1178412D03*
X718699Y1188452D03*
Y1181759D03*
X726141Y1208530D03*
Y1201837D03*
Y1195144D03*
X718699Y1205184D03*
Y1198491D03*
X726141Y1221916D03*
Y1215223D03*
X718699Y1225263D03*
Y1218570D03*
Y1211877D03*
X726141Y1238648D03*
Y1231955D03*
X718699Y1241995D03*
Y1235302D03*
X726141Y1245341D03*
X719046Y1257064D03*
X718699Y1248688D03*
X726141D03*
X729046Y1273364D03*
X715846D03*
X726141Y1262074D03*
X726107Y1265420D03*
X739699Y773491D03*
Y770144D03*
X734841Y766798D03*
X739699D03*
Y780184D03*
Y786877D03*
Y783530D03*
Y776837D03*
X734841Y773491D03*
Y780184D03*
X739699D03*
Y773491D03*
Y786877D03*
Y790223D03*
Y796916D03*
Y803609D03*
Y800263D03*
Y793570D03*
X734841Y803609D03*
Y796916D03*
Y790223D03*
X739699Y803609D03*
Y796916D03*
Y790223D03*
Y810302D03*
Y816995D03*
Y820341D03*
Y813648D03*
Y806955D03*
X734841Y816995D03*
Y810302D03*
X739699Y816995D03*
Y810302D03*
Y827034D03*
Y823688D03*
Y833727D03*
Y830381D03*
X734841Y833727D03*
Y827034D03*
X739699Y833727D03*
Y823688D03*
Y827034D03*
Y847113D03*
Y840420D03*
Y853806D03*
Y850459D03*
Y843766D03*
Y837074D03*
X734841Y847113D03*
Y840420D03*
X739699Y847113D03*
Y840420D03*
Y863845D03*
Y860499D03*
Y870538D03*
Y867192D03*
Y857152D03*
X734841Y863845D03*
Y853806D03*
X739699D03*
Y860499D03*
Y863845D03*
Y877231D03*
Y883924D03*
Y880577D03*
Y873885D03*
X734841Y883924D03*
Y877231D03*
Y870538D03*
X739699Y883924D03*
Y877231D03*
Y870538D03*
Y900656D03*
Y897310D03*
Y890617D03*
Y893963D03*
Y887270D03*
X734841Y900656D03*
Y890617D03*
X739699D03*
Y897310D03*
Y900656D03*
Y907349D03*
Y914042D03*
Y917389D03*
Y910696D03*
Y904003D03*
X734841Y914042D03*
Y907349D03*
X739699Y914042D03*
Y907349D03*
Y934121D03*
Y920735D03*
Y927428D03*
Y930774D03*
Y924081D03*
X734841Y927428D03*
Y920735D03*
X739699Y927428D03*
Y920735D03*
Y934121D03*
Y937467D03*
Y944160D03*
Y950853D03*
Y947507D03*
Y940814D03*
X734841Y944160D03*
Y937467D03*
X739699Y944160D03*
Y937467D03*
Y957546D03*
Y960892D03*
Y967585D03*
Y964239D03*
Y954200D03*
X734841Y960892D03*
Y950853D03*
X739699Y960892D03*
Y950853D03*
Y957546D03*
Y974278D03*
Y980971D03*
Y977625D03*
Y970932D03*
X734841Y980971D03*
Y974278D03*
Y967585D03*
X739699Y980971D03*
Y974278D03*
Y967585D03*
Y987664D03*
Y994357D03*
Y991011D03*
Y984318D03*
X734841Y987664D03*
X739699Y994357D03*
Y987664D03*
Y1021129D03*
Y1027822D03*
Y1031168D03*
Y1024475D03*
Y1017782D03*
X734841Y1027822D03*
Y1017782D03*
X739699Y1027822D03*
Y1021129D03*
Y1034514D03*
Y1041207D03*
Y1047900D03*
Y1044554D03*
Y1037861D03*
X734841Y1047900D03*
Y1041207D03*
Y1034515D03*
X739699Y1047900D03*
Y1041207D03*
Y1034514D03*
Y1054593D03*
Y1057940D03*
Y1051247D03*
X734841Y1061286D03*
Y1054593D03*
X739699Y1061286D03*
Y1054593D03*
Y1067979D03*
Y1074672D03*
Y1081365D03*
Y1078018D03*
Y1071326D03*
Y1064633D03*
X734841Y1074672D03*
Y1067979D03*
X739699Y1074672D03*
Y1067979D03*
Y1084711D03*
Y1091404D03*
Y1098097D03*
Y1094751D03*
Y1088058D03*
X734841Y1091404D03*
Y1084711D03*
X739699Y1091404D03*
Y1081365D03*
Y1084711D03*
Y1104790D03*
Y1111483D03*
Y1108137D03*
Y1101444D03*
X734841Y1111483D03*
Y1104790D03*
Y1098097D03*
X739699D03*
Y1111483D03*
Y1104790D03*
Y1118176D03*
Y1121522D03*
Y1128215D03*
Y1124869D03*
Y1114829D03*
X734841Y1128215D03*
Y1121522D03*
X739699Y1128215D03*
Y1118176D03*
Y1121522D03*
Y1134908D03*
Y1141601D03*
Y1144948D03*
Y1138255D03*
Y1131562D03*
X734841Y1141601D03*
Y1134908D03*
X739699Y1141601D03*
Y1134908D03*
Y1148294D03*
Y1158333D03*
Y1154987D03*
Y1161680D03*
Y1151641D03*
X734841Y1158333D03*
Y1148294D03*
X739699D03*
Y1154987D03*
Y1158333D03*
Y1165026D03*
Y1171719D03*
Y1178412D03*
Y1175066D03*
Y1168373D03*
X734841Y1171719D03*
Y1165026D03*
X739699Y1171719D03*
Y1165026D03*
Y1185105D03*
Y1191798D03*
Y1195144D03*
Y1188452D03*
Y1181759D03*
X734841Y1185105D03*
Y1178412D03*
X739699Y1185105D03*
Y1178412D03*
Y1191798D03*
Y1201837D03*
Y1208530D03*
Y1205184D03*
Y1198491D03*
X734841Y1208530D03*
Y1201837D03*
Y1195144D03*
X739699Y1208530D03*
Y1201837D03*
Y1195144D03*
Y1215223D03*
Y1221916D03*
Y1228609D03*
Y1225263D03*
Y1218570D03*
Y1211877D03*
X734841Y1221916D03*
Y1215223D03*
X739699Y1221916D03*
Y1215223D03*
Y1231955D03*
Y1238648D03*
Y1245341D03*
Y1241995D03*
Y1235302D03*
X734841Y1238648D03*
Y1231955D03*
X739699Y1238648D03*
Y1228609D03*
Y1231955D03*
Y1248688D03*
X734841Y1245341D03*
X739699D03*
Y1258727D03*
X734967Y1252034D03*
X745546Y1273364D03*
X742746D03*
X731372Y1273464D03*
X739697Y1265420D03*
X755841Y770144D03*
Y766798D03*
X748399Y770144D03*
X755841D03*
Y783530D03*
Y776837D03*
Y786877D03*
Y780184D03*
Y773491D03*
X748399Y783530D03*
Y776837D03*
X755841D03*
Y786877D03*
Y783530D03*
Y793570D03*
Y800263D03*
Y803609D03*
Y796916D03*
Y790223D03*
X748399Y800263D03*
Y793570D03*
X755841Y800263D03*
Y793570D03*
Y806955D03*
Y813648D03*
Y820341D03*
Y816995D03*
Y810302D03*
X748399Y820341D03*
Y813648D03*
Y806955D03*
X755841Y813648D03*
Y806955D03*
Y820341D03*
Y823688D03*
Y830381D03*
Y837074D03*
Y833727D03*
Y827034D03*
X748399Y830381D03*
X755841D03*
Y823688D03*
Y843766D03*
Y850459D03*
Y847113D03*
Y840420D03*
X748399Y850459D03*
Y843766D03*
Y837074D03*
X755841Y850459D03*
Y843766D03*
Y837074D03*
Y867192D03*
Y857152D03*
Y860499D03*
Y863845D03*
Y853806D03*
X748399Y867192D03*
Y857152D03*
X755841Y867192D03*
Y860499D03*
Y857152D03*
Y880577D03*
Y873885D03*
Y887270D03*
Y883924D03*
Y877231D03*
Y870538D03*
X748399Y880577D03*
Y873885D03*
X755841D03*
Y880577D03*
Y893963D03*
Y897310D03*
Y904003D03*
Y900656D03*
Y890617D03*
X748399Y893963D03*
Y887270D03*
X755841D03*
Y897310D03*
Y893963D03*
Y910696D03*
Y917389D03*
Y914042D03*
Y907349D03*
X748399Y917389D03*
Y910696D03*
Y904003D03*
X755841Y917389D03*
Y910696D03*
Y904003D03*
Y930774D03*
Y934121D03*
Y924081D03*
Y927428D03*
Y920735D03*
X748399Y930774D03*
Y924081D03*
X755841D03*
Y934121D03*
Y930774D03*
Y940814D03*
Y947507D03*
Y944160D03*
Y937467D03*
X748399Y947507D03*
Y940814D03*
X755841Y947507D03*
Y940814D03*
Y964239D03*
Y960892D03*
Y950853D03*
X748399Y964239D03*
Y954200D03*
X755841Y964239D03*
Y957546D03*
Y954200D03*
X755741Y970932D03*
X755841Y977625D03*
Y984318D03*
Y980971D03*
Y974278D03*
Y967585D03*
X748399Y977625D03*
Y970932D03*
X755841Y977625D03*
X755741Y970932D03*
X755841Y991011D03*
Y987664D03*
X748399Y991011D03*
Y984318D03*
X755841Y991011D03*
Y984318D03*
Y994357D03*
Y1031168D03*
Y1024475D03*
Y1021129D03*
Y1027822D03*
Y1017782D03*
X748399Y1031168D03*
Y1024475D03*
Y1017782D03*
X755841Y1021129D03*
Y1024475D03*
Y1031168D03*
X755541Y1037861D03*
Y1044554D03*
X755841Y1047900D03*
Y1041207D03*
Y1034515D03*
X748399Y1044554D03*
Y1037861D03*
X755541Y1044554D03*
Y1037861D03*
X755841Y1051247D03*
X755741Y1064633D03*
X755841Y1054593D03*
Y1061286D03*
X748399Y1057940D03*
Y1051247D03*
X755841D03*
X755541Y1057940D03*
X755841Y1078018D03*
X755676Y1071326D03*
X755841Y1081365D03*
Y1067979D03*
Y1074672D03*
X748399Y1078018D03*
Y1071326D03*
Y1064633D03*
X755676Y1071326D03*
X755741Y1064633D03*
X755841Y1078018D03*
Y1088058D03*
Y1094751D03*
Y1084711D03*
Y1091404D03*
X748399Y1094751D03*
Y1088058D03*
X755841Y1094751D03*
Y1088058D03*
Y1081365D03*
Y1101444D03*
X755676Y1108137D03*
X755841Y1114829D03*
Y1111483D03*
Y1104790D03*
Y1098097D03*
X748399Y1108137D03*
Y1101444D03*
X755676Y1108137D03*
X755841Y1101444D03*
Y1118176D03*
Y1124869D03*
Y1131562D03*
Y1128215D03*
Y1121522D03*
X748399Y1124869D03*
Y1114829D03*
X755841Y1124869D03*
Y1118176D03*
Y1114829D03*
Y1138255D03*
Y1144947D03*
Y1141601D03*
Y1134908D03*
X748399Y1144948D03*
Y1138255D03*
Y1131562D03*
X755841Y1144947D03*
Y1138255D03*
Y1131562D03*
Y1151640D03*
Y1154987D03*
Y1161680D03*
Y1158333D03*
Y1148294D03*
X748399Y1161680D03*
Y1151641D03*
X755841Y1161680D03*
Y1154987D03*
Y1151640D03*
Y1168373D03*
Y1175066D03*
Y1171719D03*
Y1165026D03*
X748399Y1175066D03*
Y1168373D03*
X755841Y1175066D03*
Y1168373D03*
X755676Y1181759D03*
X755841Y1191798D03*
X755676Y1188452D03*
X755841Y1185105D03*
Y1178412D03*
X748399Y1188452D03*
Y1181759D03*
X755676D03*
X755841Y1191798D03*
X755676Y1188452D03*
X755841Y1198491D03*
Y1205184D03*
Y1211877D03*
Y1208530D03*
Y1201837D03*
Y1195144D03*
X748399Y1205184D03*
Y1198491D03*
X755841Y1205184D03*
Y1198491D03*
Y1218569D03*
Y1225262D03*
Y1228609D03*
Y1221916D03*
Y1215223D03*
X748399Y1225263D03*
Y1218570D03*
Y1211877D03*
X755841Y1218569D03*
Y1211877D03*
Y1225262D03*
Y1235302D03*
Y1241995D03*
Y1238648D03*
Y1231955D03*
X748399Y1241995D03*
Y1235302D03*
X755841Y1241995D03*
Y1235302D03*
Y1228609D03*
Y1245341D03*
X748283Y1256964D03*
X748399Y1248688D03*
X750890Y1248500D03*
X755890Y1255381D03*
X755841Y1252034D03*
Y1248688D03*
X750040Y1254179D03*
X758746Y1273364D03*
X761546D03*
X755841Y1262074D03*
X755797Y1265420D03*
X769399Y770144D03*
X778099D03*
X764541Y766798D03*
X769399D03*
Y783530D03*
X778099D03*
X769399Y776837D03*
X778099D03*
X764541Y780184D03*
Y773491D03*
X769399Y800263D03*
X778099D03*
X769399Y793570D03*
X778099D03*
X764541Y803609D03*
Y796916D03*
Y790223D03*
X769399Y820341D03*
X778099D03*
X769399Y813648D03*
X778099D03*
X769399Y806955D03*
X778099D03*
X764541Y816995D03*
Y810302D03*
X769399Y830381D03*
X778099D03*
X764541Y833727D03*
Y827034D03*
X769399Y850459D03*
X778099D03*
Y843766D03*
X769399D03*
Y837074D03*
X778099D03*
X764541Y847113D03*
Y840420D03*
X778099Y867192D03*
X769399D03*
Y857152D03*
X778099D03*
X764541Y863845D03*
Y853806D03*
X769399Y880577D03*
X778099D03*
X769399Y873885D03*
X778099D03*
X764541Y883924D03*
Y877231D03*
Y870538D03*
X778099Y893963D03*
X769399D03*
Y887270D03*
X778099D03*
X764541Y900656D03*
Y890617D03*
X769399Y917389D03*
X778099D03*
X769399Y910696D03*
X778099D03*
X769399Y904003D03*
X778099D03*
X764541Y914042D03*
Y907349D03*
X769399Y930774D03*
X778099D03*
X769399Y924081D03*
X778099D03*
X764541Y927428D03*
Y920735D03*
X769399Y947507D03*
X778099D03*
X769399Y940814D03*
X778099D03*
X764541Y944160D03*
Y937467D03*
X769399Y957546D03*
Y960892D03*
Y967585D03*
Y964239D03*
X778099D03*
X769399Y954200D03*
X778099D03*
X764541Y960892D03*
Y950853D03*
X769399Y960892D03*
Y957546D03*
Y977625D03*
X778099D03*
X769399Y970932D03*
X778099D03*
X764541Y980971D03*
Y974278D03*
Y967585D03*
X769399D03*
Y991011D03*
X778099D03*
X769399Y984318D03*
X778099D03*
X764541Y987664D03*
X769399Y1031168D03*
X778099D03*
X769399Y1024475D03*
X778099D03*
X769399Y1017782D03*
X778099D03*
X764541Y1027822D03*
Y1017782D03*
X778099Y1044554D03*
X769399D03*
Y1037861D03*
X778099D03*
X764541Y1047900D03*
Y1041207D03*
Y1034515D03*
X769399Y1054593D03*
Y1057940D03*
X778099D03*
X769399Y1051247D03*
X778099D03*
X764541Y1054593D03*
Y1061286D03*
X769399Y1054593D03*
X778099Y1078018D03*
X769399D03*
X778099Y1071326D03*
X769399D03*
Y1064633D03*
X778099D03*
X764541Y1067979D03*
Y1074672D03*
X778099Y1094751D03*
X769399D03*
X778099Y1088058D03*
X769399D03*
X764541Y1084711D03*
Y1091404D03*
X778099Y1108137D03*
X769399D03*
X778099Y1101444D03*
X769399D03*
X764541Y1111483D03*
Y1104790D03*
Y1098097D03*
X778099Y1124869D03*
X769399D03*
X778099Y1114829D03*
X769399D03*
X764541Y1128215D03*
Y1121522D03*
X778099Y1144948D03*
X769399D03*
X778099Y1138255D03*
X769399D03*
X778099Y1131562D03*
X769399D03*
X764541Y1141601D03*
Y1134908D03*
X778099Y1161680D03*
X769399D03*
X778099Y1151641D03*
X769399D03*
X764541Y1158333D03*
Y1148294D03*
X778099Y1175066D03*
X769399D03*
X778099Y1168373D03*
X769399D03*
X764541Y1171719D03*
Y1165026D03*
X778099Y1188452D03*
X769399D03*
X778099Y1181759D03*
X769399D03*
X764541Y1185105D03*
Y1178412D03*
X769399Y1205184D03*
X778099D03*
Y1198491D03*
X769399D03*
X764541Y1208530D03*
Y1201837D03*
Y1195144D03*
X778099Y1225263D03*
X769399D03*
X778099Y1218570D03*
X769399D03*
Y1211877D03*
X778099D03*
X764541Y1221916D03*
Y1215223D03*
X778099Y1241995D03*
X769399D03*
X778099Y1235302D03*
X769399D03*
X764541Y1238648D03*
Y1231955D03*
X778346Y1257264D03*
X778099Y1248688D03*
X769399D03*
X764541Y1245341D03*
X769399Y1258727D03*
X766148Y1255882D03*
X772446Y1273364D03*
X775246D03*
X769399Y1265420D03*
X785541Y766798D03*
X794241D03*
X785541Y773491D03*
X794241D03*
X785541Y780184D03*
X794241D03*
X785541Y803609D03*
X794241D03*
X785541Y790223D03*
X794241D03*
X785541Y796916D03*
X794241D03*
X785541Y816995D03*
X794241D03*
X785541Y810302D03*
X794241D03*
X785541Y833727D03*
X794241D03*
X785541Y827034D03*
X794241D03*
X785541Y840420D03*
X794241D03*
X785541Y847113D03*
X794241D03*
X785541Y853806D03*
X794241D03*
X785541Y863845D03*
X794241D03*
X785541Y883924D03*
X794241D03*
X785541Y870538D03*
X794241D03*
X785541Y877231D03*
X794241D03*
X785541Y900656D03*
X794241D03*
X785541Y890617D03*
X794241D03*
X785541Y907349D03*
X794241D03*
X785541Y914042D03*
X794241D03*
X785541Y920735D03*
X794241D03*
X785541Y927428D03*
X794241D03*
X785541Y937467D03*
X794241D03*
X785541Y944160D03*
X794241D03*
X785541Y964239D03*
Y960892D03*
X794241D03*
X785541Y950853D03*
X794241D03*
X785541Y964239D03*
Y957546D03*
Y954200D03*
Y980971D03*
X794241D03*
X785541Y974278D03*
X794241D03*
X785541Y967585D03*
X794241D03*
X785541Y987664D03*
X794241D03*
X785541Y994357D03*
Y1024475D03*
Y1021129D03*
Y1027822D03*
X794241D03*
X785541Y1017782D03*
X794241D03*
X785541Y1021129D03*
Y1024475D03*
Y1047900D03*
X794241D03*
X785541Y1041207D03*
X794241D03*
X785541Y1034515D03*
X794241D03*
X785541Y1051247D03*
Y1054593D03*
X794241D03*
X785541Y1061286D03*
X794241D03*
X785541Y1051247D03*
Y1074672D03*
X794241D03*
X785541Y1067979D03*
X794241D03*
X785541Y1091404D03*
X794241D03*
X785541Y1084711D03*
X794241D03*
X785541Y1111483D03*
X794241D03*
X785541Y1104790D03*
X794241D03*
X785541Y1098097D03*
X794241D03*
X785541Y1128215D03*
X794241D03*
X785541Y1121522D03*
X794241D03*
X785541Y1141601D03*
X794241D03*
X785541Y1134908D03*
X794241D03*
X785541Y1158333D03*
X794241D03*
X785541Y1148294D03*
X794241D03*
X785541Y1171719D03*
X794241D03*
X785541Y1165026D03*
X794241D03*
X785541Y1178412D03*
X794241D03*
X785541Y1185105D03*
X794241D03*
X785541Y1208530D03*
X794241D03*
X785541Y1195144D03*
X794241D03*
X785541Y1201837D03*
X794241D03*
X785541Y1221916D03*
X794241D03*
X785541Y1215223D03*
X794241D03*
X785541Y1238648D03*
X794241D03*
X785541Y1231955D03*
X794241D03*
X785541Y1245341D03*
X794241D03*
X794157Y1252034D03*
X785541Y1248688D03*
X788446Y1273364D03*
X791246D03*
X785541Y1265420D03*
Y1262074D03*
X799099Y773491D03*
Y770144D03*
X807799D03*
X797417Y767345D03*
X799099Y780184D03*
Y786877D03*
Y783530D03*
X807799D03*
X799099Y776837D03*
X807799D03*
X799099Y780184D03*
Y773491D03*
Y786877D03*
Y796916D03*
Y790223D03*
Y803609D03*
Y800263D03*
X807799D03*
X799099Y793570D03*
X807799D03*
X799099Y803609D03*
Y796916D03*
Y790223D03*
Y810302D03*
Y816995D03*
Y820341D03*
X807799D03*
X799099Y806955D03*
X807799D03*
X799099Y813648D03*
X807799D03*
X799099Y816995D03*
Y810302D03*
Y827034D03*
Y823688D03*
Y833727D03*
Y830381D03*
X807799D03*
X799099Y833727D03*
Y823688D03*
Y827034D03*
Y840420D03*
Y847113D03*
Y853806D03*
Y850459D03*
X807799D03*
X799099Y837074D03*
X807799D03*
X799099Y843766D03*
X807799D03*
X799099Y847113D03*
Y840420D03*
Y860499D03*
Y863845D03*
Y870538D03*
Y867192D03*
X807799D03*
X799099Y857152D03*
X807799D03*
X799099Y853806D03*
Y860499D03*
Y863845D03*
Y883924D03*
Y877231D03*
Y873885D03*
X807799D03*
X799099Y880577D03*
X807799D03*
X799099Y883924D03*
Y877231D03*
Y870538D03*
Y890617D03*
Y897310D03*
Y900656D03*
Y887270D03*
X807799D03*
X799099Y893963D03*
X807799D03*
X799099Y890617D03*
Y897310D03*
Y900656D03*
Y914042D03*
Y907349D03*
Y917389D03*
X807799D03*
X799099Y904003D03*
X807799D03*
X799099Y910696D03*
X807799D03*
X799099Y914042D03*
Y907349D03*
Y927428D03*
Y920735D03*
Y934121D03*
Y930774D03*
X807799D03*
X799099Y924081D03*
X807799D03*
X799099Y927428D03*
Y920735D03*
Y934121D03*
Y944160D03*
Y937467D03*
Y950853D03*
Y947507D03*
X807799D03*
X799099Y940814D03*
X807799D03*
X799099Y944160D03*
Y937467D03*
Y957546D03*
Y960892D03*
Y967585D03*
Y964239D03*
X807799D03*
X799099Y954200D03*
X807799D03*
X799099Y960892D03*
Y950853D03*
Y957546D03*
Y980971D03*
Y974278D03*
Y970932D03*
X807799D03*
X799099Y977625D03*
X807799D03*
X799099Y980971D03*
Y974278D03*
Y967585D03*
Y994357D03*
Y987664D03*
Y991011D03*
X807799D03*
X799099Y984318D03*
X807799D03*
X799099Y994357D03*
Y987664D03*
Y1027822D03*
Y1021129D03*
Y1031168D03*
X807799D03*
X799099Y1024475D03*
X807799D03*
X799099Y1017782D03*
X807799D03*
X799099Y1027822D03*
Y1021129D03*
Y1034515D03*
Y1047900D03*
Y1041207D03*
Y1037861D03*
X807799D03*
X799099Y1044554D03*
X807799D03*
X799099Y1047900D03*
Y1041207D03*
Y1034515D03*
Y1054593D03*
Y1057940D03*
X807799D03*
X799099Y1051247D03*
X807799D03*
X799099Y1061286D03*
Y1054593D03*
Y1067979D03*
Y1074672D03*
Y1081365D03*
Y1078018D03*
X807799D03*
X799099Y1071326D03*
X807799D03*
X799099Y1064633D03*
X807799D03*
X799099Y1074672D03*
Y1067979D03*
Y1084711D03*
Y1091404D03*
Y1098097D03*
Y1094751D03*
X807799D03*
X799099Y1088058D03*
X807799D03*
X799099Y1091404D03*
Y1081365D03*
Y1084711D03*
Y1111483D03*
Y1104790D03*
Y1108137D03*
X807799D03*
X799099Y1101444D03*
X807799D03*
X799099Y1098097D03*
Y1111483D03*
Y1104790D03*
Y1118176D03*
Y1128215D03*
Y1121522D03*
Y1124869D03*
X807799D03*
X799099Y1114829D03*
X807799D03*
X799099Y1128215D03*
Y1118176D03*
Y1121522D03*
Y1134908D03*
Y1141601D03*
Y1144948D03*
X807799D03*
X799099Y1138255D03*
X807799D03*
X799099Y1131562D03*
X807799D03*
X799099Y1141601D03*
Y1134908D03*
Y1148294D03*
Y1154987D03*
Y1158333D03*
Y1161680D03*
X807799D03*
X799099Y1151641D03*
X807799D03*
X799099Y1148294D03*
Y1154987D03*
Y1158333D03*
Y1165026D03*
Y1171719D03*
Y1178412D03*
Y1175066D03*
X807799D03*
X799099Y1168373D03*
X807799D03*
X799099Y1171719D03*
Y1165026D03*
Y1185105D03*
Y1191798D03*
Y1195144D03*
Y1188452D03*
X807799D03*
X799099Y1181759D03*
X807799D03*
X799099Y1185105D03*
Y1178412D03*
Y1191798D03*
Y1201837D03*
Y1208530D03*
Y1205184D03*
X807799D03*
X799099Y1198491D03*
X807799D03*
X799099Y1208530D03*
Y1201837D03*
Y1195144D03*
Y1215223D03*
Y1221916D03*
Y1228609D03*
Y1225263D03*
X807799D03*
X799099Y1211877D03*
X807799D03*
X799099Y1218570D03*
X807799D03*
X799099Y1221916D03*
Y1215223D03*
Y1231955D03*
Y1238648D03*
Y1245341D03*
Y1241995D03*
X807799D03*
X799099Y1235302D03*
X807799D03*
X799099Y1238648D03*
Y1228609D03*
Y1231955D03*
Y1248688D03*
X807799D03*
X808046Y1257664D03*
X799099Y1245341D03*
Y1258727D03*
X804946Y1273364D03*
X802146D03*
X799099Y1265420D03*
X815241Y770144D03*
Y766798D03*
X823941D03*
X815241Y770144D03*
Y776837D03*
Y783530D03*
Y786877D03*
Y773491D03*
X823941D03*
X815241Y780184D03*
X823941D03*
X815241Y776837D03*
Y786877D03*
Y783530D03*
Y800263D03*
Y793570D03*
Y803609D03*
X823941D03*
X815241Y790223D03*
X823941D03*
X815241Y796916D03*
X823941D03*
X815241Y800263D03*
Y793570D03*
Y806955D03*
Y813648D03*
Y820341D03*
Y816995D03*
X823941D03*
X815241Y810302D03*
X823941D03*
X815241Y813648D03*
Y806955D03*
Y820341D03*
Y823688D03*
Y830381D03*
Y837074D03*
Y833727D03*
X823941D03*
X815241Y827034D03*
X823941D03*
X815241Y830381D03*
Y823688D03*
Y850459D03*
Y843766D03*
Y840420D03*
X823941D03*
X815241Y847113D03*
X823941D03*
X815241Y850459D03*
Y843766D03*
Y837074D03*
Y867192D03*
Y860499D03*
Y857152D03*
Y853806D03*
X823941D03*
X815241Y863845D03*
X823941D03*
X815241Y867192D03*
Y860499D03*
Y857152D03*
Y873885D03*
Y880577D03*
Y887270D03*
Y883924D03*
X823941D03*
X815241Y870538D03*
X823941D03*
X815241Y877231D03*
X823941D03*
X815241Y873885D03*
Y880577D03*
Y897310D03*
Y893963D03*
Y904003D03*
Y900656D03*
X823941D03*
X815241Y890617D03*
X823941D03*
X815241Y887270D03*
Y897310D03*
Y893963D03*
Y917389D03*
Y910696D03*
Y907349D03*
X823941D03*
X815241Y914042D03*
X823941D03*
X815241Y917389D03*
Y910696D03*
Y904003D03*
Y924081D03*
Y934121D03*
Y930774D03*
Y920735D03*
X823941D03*
X815241Y927428D03*
X823941D03*
X815241Y924081D03*
Y934121D03*
Y930774D03*
Y947507D03*
Y940814D03*
Y937467D03*
X823941D03*
X815241Y944160D03*
X823941D03*
X815241Y947507D03*
Y940814D03*
Y964239D03*
X828799Y957546D03*
Y960892D03*
Y967585D03*
X815241Y960892D03*
X823941D03*
X815241Y950853D03*
X823941D03*
X815241Y964239D03*
Y957546D03*
Y954200D03*
Y977625D03*
Y970932D03*
Y984318D03*
Y980971D03*
X823941D03*
X815241Y974278D03*
X823941D03*
X815241Y967585D03*
X823941D03*
X815241Y977625D03*
Y970932D03*
Y991011D03*
Y987664D03*
X823941D03*
X815241Y991011D03*
Y984318D03*
Y994357D03*
Y1021129D03*
Y1024475D03*
Y1031168D03*
Y1027822D03*
X823941D03*
X815241Y1017782D03*
X823941D03*
X815241Y1021129D03*
Y1024475D03*
Y1031168D03*
Y1044554D03*
Y1037861D03*
Y1047900D03*
X823941D03*
X815241Y1041207D03*
X823941D03*
X815241Y1034515D03*
X823941D03*
X815241Y1044554D03*
Y1037861D03*
X814941Y1051247D03*
X828799Y1054593D03*
X815241Y1064633D03*
Y1054593D03*
X823941D03*
X815241Y1061286D03*
X823941D03*
X814941Y1051247D03*
X815241Y1071325D03*
Y1078018D03*
Y1081365D03*
Y1074672D03*
X823941D03*
X815241Y1067979D03*
X823941D03*
X815241Y1071325D03*
Y1064633D03*
Y1078018D03*
Y1094751D03*
Y1088058D03*
Y1091404D03*
X823941D03*
X815241Y1084711D03*
X823941D03*
X815241Y1094751D03*
Y1088058D03*
Y1081365D03*
Y1101444D03*
Y1108136D03*
Y1114829D03*
Y1111483D03*
X823941D03*
X815241Y1104790D03*
X823941D03*
X815241Y1098097D03*
X823941D03*
X815241Y1108136D03*
Y1101444D03*
Y1118176D03*
Y1124869D03*
Y1131562D03*
Y1128215D03*
X823941D03*
X815241Y1121522D03*
X823941D03*
X815241Y1124869D03*
Y1118176D03*
Y1114829D03*
Y1144947D03*
Y1138255D03*
Y1141601D03*
X823941D03*
X815241Y1134908D03*
X823941D03*
X815241Y1144947D03*
Y1138255D03*
Y1131562D03*
Y1151640D03*
Y1161680D03*
Y1154987D03*
Y1158333D03*
X823941D03*
X815241Y1148294D03*
X823941D03*
X815241Y1161680D03*
Y1154987D03*
Y1151640D03*
Y1168373D03*
Y1175066D03*
Y1171719D03*
X823941D03*
X815241Y1165026D03*
X823941D03*
X815241Y1175066D03*
Y1168373D03*
Y1181758D03*
Y1191798D03*
Y1188451D03*
Y1178412D03*
X823941D03*
X815241Y1185105D03*
X823941D03*
X815241Y1181758D03*
Y1191798D03*
Y1188451D03*
Y1198491D03*
Y1205184D03*
Y1211877D03*
Y1208530D03*
X823941D03*
X815241Y1195144D03*
X823941D03*
X815241Y1201837D03*
X823941D03*
X815241Y1205184D03*
Y1198491D03*
Y1218570D03*
Y1225263D03*
Y1228609D03*
Y1221916D03*
X823941D03*
X815241Y1215223D03*
X823941D03*
X815241Y1218570D03*
Y1211877D03*
Y1225263D03*
Y1235302D03*
Y1241995D03*
Y1238648D03*
X823941D03*
X815241Y1231955D03*
X823941D03*
X815241Y1241995D03*
Y1235302D03*
Y1228609D03*
Y1245341D03*
X823941D03*
X823877Y1252034D03*
X815241Y1248688D03*
X826501Y1254553D03*
X820946Y1273364D03*
X818146D03*
X815241Y1265420D03*
Y1262074D03*
X828799Y770144D03*
X837499D03*
X828699Y766798D03*
X828799Y783530D03*
X837499D03*
X828799Y776837D03*
X837499D03*
Y800263D03*
X828799D03*
X837499Y793570D03*
X828799D03*
Y820341D03*
X837499D03*
X828799Y813648D03*
X837499D03*
X828799Y806955D03*
X837499D03*
X828799Y830381D03*
X837499D03*
X828799Y850459D03*
X837499D03*
X828799Y843766D03*
X837499D03*
X828799Y837074D03*
X837499D03*
X828799Y867192D03*
X837499D03*
X828799Y857152D03*
X837499D03*
X828799Y880577D03*
X837499D03*
X828799Y873885D03*
X837499D03*
X828799Y893963D03*
X837499D03*
X828799Y887270D03*
X837499D03*
X828799Y917389D03*
X837499D03*
Y904003D03*
X828799D03*
X837499Y910696D03*
X828799D03*
Y930774D03*
X837499D03*
X828799Y924081D03*
X837499D03*
X828799Y947507D03*
X837499D03*
X828799Y940814D03*
X837499D03*
X844941Y964239D03*
X828799D03*
X837499D03*
X828799Y954200D03*
X837499D03*
X828799Y960892D03*
Y957546D03*
Y977625D03*
X837499D03*
X828799Y970932D03*
X837499D03*
X828799Y967585D03*
Y991011D03*
X837499D03*
X828799Y984318D03*
X837499D03*
X844941Y1021129D03*
Y1024475D03*
X828799Y1031168D03*
X837499D03*
X828799Y1024475D03*
X837499D03*
X828799Y1017782D03*
X837499D03*
X828799Y1044554D03*
X837499D03*
X828799Y1037861D03*
X837499D03*
X844941Y1051247D03*
X828799Y1057940D03*
X837499D03*
X828799Y1051247D03*
X837499D03*
X828799Y1054593D03*
Y1078018D03*
X837499D03*
X828799Y1071326D03*
X837499D03*
X828799Y1064633D03*
X837499D03*
X828799Y1094751D03*
X837499D03*
Y1088058D03*
X828799D03*
X837499Y1108137D03*
X828799D03*
Y1101444D03*
X837499D03*
Y1124869D03*
X828799D03*
X837499Y1114829D03*
X828799D03*
X837499Y1144948D03*
X828799D03*
X837499Y1138255D03*
X828799D03*
X837499Y1131562D03*
X828799D03*
X837499Y1161680D03*
X828799D03*
X837499Y1151641D03*
X828799D03*
X837499Y1175066D03*
X828799D03*
X837499Y1168373D03*
X828799D03*
Y1188452D03*
X837499D03*
Y1181759D03*
X828799D03*
X837499Y1205184D03*
X828799D03*
X837499Y1198491D03*
X828799D03*
X837499Y1225263D03*
X828799D03*
X837499Y1218570D03*
X828799D03*
X837499Y1211877D03*
X828799D03*
X837499Y1241995D03*
X828799D03*
X837499Y1235302D03*
X828799D03*
X837499Y1248688D03*
X828799D03*
X837846Y1256964D03*
X828799Y1258727D03*
X839246Y1273064D03*
X842046D03*
X831846Y1273364D03*
X834646D03*
X828799Y1265420D03*
X844941Y766798D03*
X853641D03*
X844941Y780184D03*
X853641D03*
X844941Y773491D03*
X853641D03*
X844941Y803609D03*
X853641D03*
X844941Y796916D03*
X853641D03*
X844941Y790223D03*
X853641D03*
X844941Y816995D03*
X853641D03*
X844941Y810302D03*
X853641D03*
X844941Y833727D03*
X853641D03*
X844941Y827034D03*
X853641D03*
X844941Y847113D03*
X853641D03*
X844941Y840420D03*
X853641D03*
X844941Y863845D03*
X853641D03*
X844941Y853806D03*
X853641D03*
X844941Y883924D03*
X853641D03*
X844941Y877231D03*
X853641D03*
X844941Y870538D03*
X853641D03*
X844941Y900656D03*
X853641D03*
X844941Y890617D03*
X853641D03*
X844941Y914042D03*
X853641D03*
X844941Y907349D03*
X853641D03*
X844941Y927428D03*
X853641D03*
X844941Y920735D03*
X853641D03*
X844941Y944160D03*
X853641D03*
X844941Y937467D03*
X853641D03*
X844941Y960892D03*
X853641D03*
X844941Y950853D03*
X853641D03*
X844941Y964239D03*
X844841Y957546D03*
Y954200D03*
X844941Y980971D03*
X853641D03*
X844941Y974278D03*
X853641D03*
X844941Y967585D03*
X853641D03*
X844941Y987664D03*
X853641D03*
X844841Y994357D03*
X844941Y1027822D03*
X853641D03*
X844941Y1017782D03*
X853641D03*
X844941Y1021129D03*
Y1024475D03*
Y1047900D03*
X853641D03*
X844941Y1041207D03*
X853641D03*
X844941Y1034515D03*
X853641D03*
X844941Y1061286D03*
X853641D03*
X844941Y1054593D03*
X853641D03*
X844941Y1051247D03*
Y1074672D03*
X853641D03*
X844941Y1067979D03*
X853641D03*
X844941Y1091404D03*
X853641D03*
X844941Y1084711D03*
X853641D03*
X844941Y1111483D03*
X853641D03*
X844941Y1104790D03*
X853641D03*
X844941Y1098097D03*
X853641D03*
X844941Y1128215D03*
X853641D03*
X844941Y1121522D03*
X853641D03*
X844941Y1141601D03*
X853641D03*
X844941Y1134908D03*
X853641D03*
X844941Y1158333D03*
X853641D03*
X844941Y1148294D03*
X853641D03*
X844941Y1171719D03*
X853641D03*
X844941Y1165026D03*
X853641D03*
X844941Y1185105D03*
X853641D03*
X844941Y1178412D03*
X853641D03*
X844941Y1208530D03*
X853641D03*
X844941Y1201837D03*
X853641D03*
X844941Y1195144D03*
X853641D03*
X844941Y1221916D03*
X853641D03*
X844941Y1215223D03*
X853641D03*
X844941Y1238648D03*
X853641D03*
X844941Y1231955D03*
X853641D03*
X844941Y1245341D03*
X853641D03*
X844941Y1258727D03*
Y1252034D03*
X844997Y1248155D03*
X844941Y1265420D03*
Y1262074D03*
X918264Y506011D03*
X1003841Y770144D03*
Y783530D03*
Y776837D03*
Y800263D03*
Y793570D03*
Y820341D03*
Y813648D03*
Y806955D03*
Y830381D03*
Y850459D03*
Y843766D03*
Y837074D03*
Y867192D03*
Y857152D03*
Y880577D03*
Y873885D03*
Y893963D03*
Y887270D03*
Y917389D03*
Y910696D03*
Y904003D03*
Y930774D03*
Y924081D03*
Y947507D03*
Y940814D03*
Y964239D03*
Y954200D03*
Y977625D03*
Y970932D03*
Y991011D03*
Y984318D03*
Y1031168D03*
Y1024475D03*
Y1017782D03*
Y1044554D03*
Y1037861D03*
Y1057940D03*
Y1051247D03*
Y1078018D03*
Y1071326D03*
Y1064633D03*
Y1094751D03*
Y1088058D03*
Y1108137D03*
Y1101444D03*
Y1124869D03*
Y1114829D03*
Y1144948D03*
Y1138255D03*
Y1131562D03*
Y1161680D03*
Y1151641D03*
Y1175066D03*
Y1168373D03*
Y1188452D03*
Y1181759D03*
Y1205184D03*
Y1198491D03*
Y1225263D03*
Y1218570D03*
Y1211877D03*
Y1241995D03*
Y1235302D03*
Y1248688D03*
X1003831Y1259077D03*
X1003841Y1265420D03*
Y1262074D03*
X1019983Y766798D03*
X1012541Y770144D03*
X1012769Y766798D03*
X1019983Y780184D03*
Y773491D03*
X1012541Y783530D03*
Y776837D03*
X1019983Y803609D03*
Y796916D03*
Y790223D03*
X1012541Y800263D03*
Y793570D03*
X1019983Y816995D03*
Y810302D03*
X1012541Y820341D03*
Y813648D03*
Y806955D03*
X1019983Y833727D03*
Y827034D03*
X1012541Y830381D03*
X1019983Y847113D03*
Y840420D03*
X1012541Y850459D03*
Y843766D03*
Y837074D03*
X1019983Y863845D03*
Y853806D03*
X1012541Y867192D03*
Y857152D03*
X1019983Y883924D03*
Y877231D03*
Y870538D03*
X1012541Y880577D03*
Y873885D03*
X1019983Y900656D03*
Y890617D03*
X1012541Y893963D03*
Y887270D03*
X1019983Y914042D03*
Y907349D03*
X1012541Y917389D03*
Y910696D03*
Y904003D03*
X1019983Y927428D03*
Y920735D03*
X1012541Y930774D03*
Y924081D03*
X1019983Y944160D03*
Y937467D03*
X1012541Y947507D03*
Y940814D03*
Y960892D03*
Y957546D03*
Y967585D03*
X1019983Y960892D03*
Y950853D03*
X1012541Y964239D03*
Y954200D03*
Y960892D03*
Y957546D03*
X1019983Y980971D03*
Y974278D03*
Y967585D03*
X1012541Y977625D03*
Y970932D03*
Y967585D03*
X1019983Y987664D03*
X1012541Y991011D03*
Y984318D03*
X1019983Y994357D03*
Y1027822D03*
Y1017782D03*
X1012541Y1031168D03*
Y1024475D03*
Y1017782D03*
X1019983Y1047900D03*
Y1041207D03*
Y1034515D03*
X1012541Y1044554D03*
Y1037861D03*
Y1054593D03*
X1019983Y1061286D03*
Y1054593D03*
X1012541Y1057940D03*
Y1051247D03*
Y1054593D03*
X1019983Y1067979D03*
Y1074672D03*
X1012541Y1078018D03*
Y1071326D03*
Y1064633D03*
X1019983Y1091404D03*
Y1084711D03*
X1012541Y1094751D03*
Y1088058D03*
X1019983Y1111483D03*
Y1104790D03*
Y1098097D03*
X1012541Y1108137D03*
Y1101444D03*
X1019983Y1128215D03*
Y1121522D03*
X1012541Y1124869D03*
Y1114829D03*
X1019983Y1141601D03*
Y1134908D03*
X1012541Y1144948D03*
Y1138255D03*
Y1131562D03*
X1019983Y1158333D03*
Y1148294D03*
X1012541Y1161680D03*
Y1151641D03*
X1019983Y1171719D03*
Y1165026D03*
X1012541Y1175066D03*
Y1168373D03*
X1019983Y1185105D03*
Y1178412D03*
X1012541Y1188452D03*
Y1181759D03*
X1019983Y1208530D03*
Y1201837D03*
Y1195144D03*
X1012541Y1205184D03*
Y1198491D03*
X1019983Y1221916D03*
Y1215223D03*
X1012541Y1225263D03*
Y1218570D03*
Y1211877D03*
X1019983Y1238648D03*
Y1231955D03*
X1012541Y1241995D03*
Y1235302D03*
X1012543Y1257198D03*
X1019983Y1245341D03*
X1012541Y1248688D03*
X1017900Y1247632D03*
X1019983Y1255381D03*
Y1252034D03*
Y1248688D03*
X1017111Y1273299D03*
X1014111D03*
X1019983Y1262074D03*
Y1265420D03*
X1033541Y770144D03*
X1028683Y766798D03*
X1033441D03*
X1033541Y783530D03*
Y776837D03*
X1028683Y780184D03*
Y773491D03*
X1033541Y800263D03*
Y793570D03*
X1028683Y803609D03*
Y796916D03*
Y790223D03*
X1033541Y820341D03*
Y813648D03*
Y806955D03*
X1028683Y816995D03*
Y810302D03*
X1033541Y830381D03*
X1028683Y833727D03*
Y827034D03*
X1033541Y850459D03*
Y843766D03*
Y837074D03*
X1028683Y847113D03*
Y840420D03*
X1033541Y867192D03*
Y857152D03*
X1028683Y863845D03*
Y853806D03*
X1033541Y880577D03*
Y873885D03*
X1028683Y883924D03*
Y877231D03*
Y870538D03*
X1033541Y893963D03*
Y887270D03*
X1028683Y900656D03*
Y890617D03*
X1033541Y917389D03*
Y910696D03*
Y904003D03*
X1028683Y914042D03*
Y907349D03*
X1033541Y930774D03*
Y924081D03*
X1028683Y927428D03*
Y920735D03*
X1033541Y947507D03*
Y940814D03*
X1028683Y944160D03*
Y937467D03*
Y964239D03*
X1033541D03*
Y954200D03*
X1028683Y960892D03*
Y950853D03*
Y964239D03*
Y957546D03*
Y954200D03*
X1033541Y977625D03*
Y970932D03*
X1028683Y980971D03*
Y974278D03*
Y967585D03*
X1033541Y991011D03*
Y984318D03*
X1028683Y987664D03*
Y1021129D03*
Y1024475D03*
X1033541Y1031168D03*
Y1017782D03*
Y1024475D03*
X1028683Y1027822D03*
Y1017782D03*
Y1021129D03*
Y1024475D03*
X1033541Y1044554D03*
Y1037861D03*
X1028683Y1047900D03*
Y1041207D03*
Y1034515D03*
Y1051247D03*
X1033541Y1057940D03*
Y1051247D03*
X1028683Y1061286D03*
Y1054593D03*
Y1051247D03*
X1033541Y1078018D03*
Y1071326D03*
Y1064633D03*
X1028683Y1067979D03*
Y1074672D03*
X1033541Y1094751D03*
Y1088058D03*
X1028683Y1091404D03*
Y1084711D03*
X1033541Y1108137D03*
Y1101444D03*
X1028683Y1111483D03*
Y1104790D03*
Y1098097D03*
X1033541Y1114829D03*
Y1124869D03*
X1028683Y1128215D03*
Y1121522D03*
X1033541Y1144948D03*
Y1138255D03*
Y1131562D03*
X1028683Y1141601D03*
Y1134908D03*
X1033541Y1161680D03*
Y1151641D03*
X1028683Y1158333D03*
Y1148294D03*
X1033541Y1175066D03*
Y1168373D03*
X1028683Y1171719D03*
Y1165026D03*
X1033541Y1188452D03*
Y1181759D03*
X1028683Y1185105D03*
Y1178412D03*
X1033541Y1205184D03*
Y1198491D03*
X1028683Y1208530D03*
Y1201837D03*
Y1195144D03*
X1033541Y1225263D03*
Y1218570D03*
Y1211877D03*
X1028683Y1221916D03*
Y1215223D03*
X1033541Y1241995D03*
Y1235302D03*
X1028683Y1238648D03*
Y1231955D03*
X1033541Y1248688D03*
X1028683Y1245341D03*
X1033541Y1258727D03*
X1036588Y1273344D03*
X1022888D03*
X1025688D03*
X1033541Y1265420D03*
X1042241Y773491D03*
X1049683Y766798D03*
X1042241Y770144D03*
Y780184D03*
Y786877D03*
X1049683Y780184D03*
Y773491D03*
X1042241Y783530D03*
Y776837D03*
Y780184D03*
Y773491D03*
Y786877D03*
Y796916D03*
Y790223D03*
Y803609D03*
X1049683D03*
Y796916D03*
Y790223D03*
X1042241Y800263D03*
Y793570D03*
Y803609D03*
Y796916D03*
Y790223D03*
Y816995D03*
Y810302D03*
X1049683Y816995D03*
Y810302D03*
X1042241Y820341D03*
Y813648D03*
Y806955D03*
Y816995D03*
Y810302D03*
Y833727D03*
Y823688D03*
Y827034D03*
X1049683Y833727D03*
Y827034D03*
X1042241Y830381D03*
Y833727D03*
Y823688D03*
Y827034D03*
Y840420D03*
Y847113D03*
Y853806D03*
X1049683Y847113D03*
Y840420D03*
X1042241Y850459D03*
Y843766D03*
Y837074D03*
Y847113D03*
Y840420D03*
Y860499D03*
Y863845D03*
Y870538D03*
X1049683Y863845D03*
Y853806D03*
X1042241Y867192D03*
Y857152D03*
Y853806D03*
Y860499D03*
Y863845D03*
Y883924D03*
Y877231D03*
X1049683Y883924D03*
Y877231D03*
Y870538D03*
X1042241Y880577D03*
Y873885D03*
Y883924D03*
Y877231D03*
Y870538D03*
Y890617D03*
Y897310D03*
Y900656D03*
X1049683D03*
Y890617D03*
X1042241Y893963D03*
Y887270D03*
Y890617D03*
Y897310D03*
Y900656D03*
Y914042D03*
Y907349D03*
X1049683Y914042D03*
Y907349D03*
X1042241Y917389D03*
Y910696D03*
Y904003D03*
Y914042D03*
Y907349D03*
Y927428D03*
Y920735D03*
Y934121D03*
X1049683Y927428D03*
Y920735D03*
X1042241Y930774D03*
Y924081D03*
Y927428D03*
Y920735D03*
Y934121D03*
Y944160D03*
Y937467D03*
Y950853D03*
X1049683Y944160D03*
Y937467D03*
X1042241Y947507D03*
Y940814D03*
Y944160D03*
Y937467D03*
Y960892D03*
Y957546D03*
Y967585D03*
X1049683Y960892D03*
Y950853D03*
X1042241Y964239D03*
Y954200D03*
Y960892D03*
Y950853D03*
Y957546D03*
Y980971D03*
Y974278D03*
X1049683Y980971D03*
Y974278D03*
Y967585D03*
X1042241Y977625D03*
Y970932D03*
Y980971D03*
Y974278D03*
Y967585D03*
Y994357D03*
Y987664D03*
X1049683D03*
X1042241Y991011D03*
Y984318D03*
Y994357D03*
Y987664D03*
Y1027822D03*
Y1021129D03*
X1049683Y1027822D03*
Y1017782D03*
X1042241Y1031168D03*
Y1017782D03*
Y1024475D03*
Y1027822D03*
Y1021129D03*
Y1034515D03*
Y1047900D03*
Y1041207D03*
X1049683Y1047900D03*
Y1041207D03*
Y1034515D03*
X1042241Y1044554D03*
Y1037861D03*
Y1047900D03*
Y1041207D03*
Y1034515D03*
Y1054593D03*
X1049683Y1061286D03*
Y1054593D03*
X1042241Y1057940D03*
Y1051247D03*
Y1061286D03*
Y1054593D03*
Y1067979D03*
Y1074672D03*
Y1081365D03*
X1049683Y1074672D03*
Y1067979D03*
X1042241Y1078018D03*
Y1071326D03*
Y1064633D03*
Y1074672D03*
Y1067979D03*
Y1084711D03*
Y1091404D03*
Y1098097D03*
X1049683Y1091404D03*
Y1084711D03*
X1042241Y1094751D03*
Y1088058D03*
Y1091404D03*
Y1081365D03*
Y1084711D03*
Y1111483D03*
Y1104790D03*
X1049683Y1111483D03*
Y1104790D03*
Y1098097D03*
X1042241Y1108137D03*
Y1101444D03*
Y1098097D03*
Y1111483D03*
Y1104790D03*
Y1118176D03*
Y1128215D03*
Y1121522D03*
Y1114829D03*
X1049683Y1128215D03*
Y1121522D03*
X1042241Y1124869D03*
Y1128215D03*
Y1118176D03*
Y1121522D03*
Y1134908D03*
Y1141601D03*
X1049683D03*
Y1134908D03*
X1042241Y1144948D03*
Y1138255D03*
Y1131562D03*
Y1141601D03*
Y1134908D03*
Y1148294D03*
Y1154987D03*
Y1158333D03*
Y1161680D03*
X1049683Y1158333D03*
Y1148294D03*
X1042241Y1151641D03*
Y1148294D03*
Y1154987D03*
Y1158333D03*
Y1165026D03*
Y1171719D03*
Y1178412D03*
X1049683Y1171719D03*
Y1165026D03*
X1042241Y1175066D03*
Y1168373D03*
Y1171719D03*
Y1165026D03*
Y1185105D03*
Y1191798D03*
Y1195144D03*
X1049683Y1185105D03*
Y1178412D03*
X1042241Y1188452D03*
Y1181759D03*
Y1185105D03*
Y1178412D03*
Y1191798D03*
Y1201837D03*
Y1208530D03*
X1049683D03*
Y1201837D03*
Y1195144D03*
X1042241Y1205184D03*
Y1198491D03*
Y1208530D03*
Y1201837D03*
Y1195144D03*
Y1215223D03*
Y1221916D03*
Y1228609D03*
X1049683Y1215223D03*
Y1221916D03*
X1042241Y1225263D03*
Y1218570D03*
Y1211877D03*
Y1221916D03*
Y1215223D03*
Y1231955D03*
Y1238648D03*
Y1245341D03*
X1049683Y1238648D03*
Y1231955D03*
X1042241Y1241995D03*
Y1235302D03*
Y1238648D03*
Y1228609D03*
Y1231955D03*
X1042331Y1257488D03*
X1049683Y1245341D03*
X1042241Y1248688D03*
Y1245341D03*
X1049683Y1258727D03*
X1052588Y1273344D03*
X1039388D03*
X1049683Y1265420D03*
Y1262074D03*
X1058383Y770144D03*
X1063241D03*
X1058383Y766798D03*
Y770144D03*
X1063141Y766798D03*
X1058383Y776837D03*
Y783530D03*
Y786877D03*
X1063241Y783530D03*
Y776837D03*
X1058383Y780184D03*
Y773491D03*
Y776837D03*
Y786877D03*
Y783530D03*
Y800263D03*
Y793570D03*
X1063241Y800263D03*
Y793570D03*
X1058383Y803609D03*
Y796916D03*
Y790223D03*
Y800263D03*
Y793570D03*
Y813648D03*
Y806955D03*
Y820341D03*
X1063241D03*
Y813648D03*
Y806955D03*
X1058383Y816995D03*
Y810302D03*
Y813648D03*
Y806955D03*
Y820341D03*
Y830381D03*
Y823688D03*
Y837074D03*
X1063241Y830381D03*
X1058383Y833727D03*
Y827034D03*
Y830381D03*
Y823688D03*
Y850459D03*
Y843766D03*
X1063241Y850459D03*
Y843766D03*
Y837074D03*
X1058383Y847113D03*
Y840420D03*
Y850459D03*
Y843766D03*
Y837074D03*
Y867192D03*
Y860499D03*
Y857152D03*
X1063241Y867192D03*
Y857152D03*
X1058383Y863845D03*
Y853806D03*
Y867192D03*
Y860499D03*
Y857152D03*
Y873885D03*
Y880577D03*
Y887270D03*
X1063241Y880577D03*
Y873885D03*
X1058383Y883924D03*
Y877231D03*
Y870538D03*
Y873885D03*
Y880577D03*
Y897310D03*
Y893963D03*
Y904003D03*
X1063241Y893963D03*
Y887270D03*
X1058383Y900656D03*
Y890617D03*
Y887270D03*
Y897310D03*
Y893963D03*
Y917389D03*
Y910696D03*
X1063241Y917389D03*
Y910696D03*
Y904003D03*
X1058383Y914042D03*
Y907349D03*
Y917389D03*
Y910696D03*
Y904003D03*
Y924081D03*
Y934121D03*
Y930774D03*
X1063241D03*
Y924081D03*
X1058383Y927428D03*
Y920735D03*
Y924081D03*
Y934121D03*
Y930774D03*
Y947507D03*
Y940814D03*
X1063241Y947507D03*
Y940814D03*
X1058383Y944160D03*
Y937467D03*
Y947507D03*
Y940814D03*
Y964239D03*
X1071941Y960892D03*
Y957546D03*
Y967585D03*
X1063241Y964239D03*
Y954200D03*
X1058383Y960892D03*
Y950853D03*
Y964239D03*
Y957546D03*
Y954200D03*
Y977625D03*
Y970932D03*
Y984318D03*
X1063241Y977625D03*
Y970932D03*
X1058383Y980971D03*
Y974278D03*
Y967585D03*
Y977625D03*
Y970932D03*
Y991011D03*
X1063241D03*
Y984318D03*
X1058383Y987664D03*
Y991011D03*
Y984318D03*
Y994357D03*
Y1021129D03*
Y1024475D03*
Y1031168D03*
X1063241D03*
Y1024475D03*
Y1017782D03*
X1058383Y1027822D03*
Y1017782D03*
Y1021129D03*
Y1024475D03*
Y1031168D03*
Y1044554D03*
Y1037861D03*
X1063241Y1044554D03*
Y1037861D03*
X1058383Y1047900D03*
Y1041207D03*
Y1034515D03*
Y1044554D03*
Y1037861D03*
Y1051247D03*
X1071941Y1054593D03*
X1058383Y1064633D03*
X1063241Y1057940D03*
Y1051247D03*
X1058383Y1061286D03*
Y1054593D03*
Y1051247D03*
Y1071326D03*
Y1078018D03*
Y1081365D03*
X1063241Y1078018D03*
Y1071326D03*
Y1064633D03*
X1058383Y1074672D03*
Y1067979D03*
Y1071326D03*
Y1064633D03*
Y1078018D03*
Y1094751D03*
Y1088058D03*
X1063241Y1094751D03*
Y1088058D03*
X1058383Y1091404D03*
Y1084711D03*
Y1094751D03*
Y1088058D03*
Y1081365D03*
Y1101444D03*
Y1108137D03*
Y1114829D03*
X1063241Y1108137D03*
Y1101444D03*
X1058383Y1111483D03*
Y1104790D03*
Y1098097D03*
Y1108137D03*
Y1101444D03*
Y1118176D03*
Y1124869D03*
Y1131562D03*
X1063241Y1124869D03*
Y1114829D03*
X1058383Y1128215D03*
Y1121522D03*
Y1124869D03*
Y1118176D03*
Y1114829D03*
Y1144948D03*
Y1138255D03*
X1063241Y1144948D03*
Y1138255D03*
Y1131562D03*
X1058383Y1141601D03*
Y1134908D03*
Y1144948D03*
Y1138255D03*
Y1131562D03*
Y1151641D03*
Y1161680D03*
Y1154987D03*
X1063241Y1161680D03*
Y1151641D03*
X1058383Y1158333D03*
Y1148294D03*
Y1161680D03*
Y1154987D03*
Y1151641D03*
Y1168373D03*
Y1175066D03*
X1063241D03*
Y1168373D03*
X1058383Y1171719D03*
Y1165026D03*
Y1175066D03*
Y1168373D03*
Y1181759D03*
Y1188452D03*
Y1191798D03*
X1063241Y1188452D03*
Y1181759D03*
X1058383Y1185105D03*
Y1178412D03*
Y1181759D03*
Y1191798D03*
Y1188452D03*
Y1198491D03*
Y1205184D03*
Y1211877D03*
X1063241Y1205184D03*
Y1198491D03*
X1058383Y1208530D03*
Y1201837D03*
Y1195144D03*
Y1205184D03*
Y1198491D03*
Y1218570D03*
Y1225263D03*
Y1228609D03*
X1063241Y1225263D03*
Y1218570D03*
Y1211877D03*
X1058383Y1215223D03*
Y1221916D03*
Y1218570D03*
Y1211877D03*
Y1225263D03*
Y1235302D03*
Y1241995D03*
X1063241D03*
Y1235302D03*
X1058383Y1238648D03*
Y1231955D03*
Y1241995D03*
Y1235302D03*
Y1228609D03*
X1063241Y1248688D03*
X1058383Y1245341D03*
X1063241Y1258727D03*
X1058383Y1248688D03*
X1069088Y1273344D03*
X1066288D03*
X1055388D03*
X1063241Y1265420D03*
X1079383Y766798D03*
X1071941Y770144D03*
X1079383Y780184D03*
Y773491D03*
X1071941Y783530D03*
Y776837D03*
X1079383Y803609D03*
Y796916D03*
Y790223D03*
X1071941Y800263D03*
Y793570D03*
X1079383Y816995D03*
Y810302D03*
X1071941Y820341D03*
Y813648D03*
Y806955D03*
X1079383Y833727D03*
Y827034D03*
X1071941Y830381D03*
X1079383Y847113D03*
Y840420D03*
X1071941Y850459D03*
Y843766D03*
Y837074D03*
X1079383Y863845D03*
Y853806D03*
X1071941Y867192D03*
Y857152D03*
X1079383Y883924D03*
Y877231D03*
Y870538D03*
X1071941Y880577D03*
Y873885D03*
X1079383Y900656D03*
Y890617D03*
X1071941Y893963D03*
Y887270D03*
X1079383Y914042D03*
Y907349D03*
X1071941Y917389D03*
Y910696D03*
Y904003D03*
X1079383Y927428D03*
Y920735D03*
X1071941Y930774D03*
Y924081D03*
X1079383Y944160D03*
Y937467D03*
X1071941Y947507D03*
Y940814D03*
X1088083Y964239D03*
X1079383Y960892D03*
Y950853D03*
X1071941Y964239D03*
Y954200D03*
Y960892D03*
Y957546D03*
X1079383Y980971D03*
Y974278D03*
Y967585D03*
X1071941Y977625D03*
Y970932D03*
Y967585D03*
X1079383Y987664D03*
X1071941Y991011D03*
Y984318D03*
X1079383Y994357D03*
X1088083Y1021129D03*
Y1024475D03*
X1079383Y1027822D03*
Y1017782D03*
X1071941Y1031168D03*
Y1024475D03*
Y1017782D03*
X1079383Y1047900D03*
Y1041207D03*
Y1034515D03*
X1071941Y1044554D03*
Y1037861D03*
X1088083Y1051247D03*
X1079383Y1061286D03*
Y1054593D03*
X1071941Y1057940D03*
Y1051247D03*
Y1054593D03*
X1079383Y1074672D03*
Y1067979D03*
X1071941Y1078018D03*
Y1071326D03*
Y1064633D03*
X1079383Y1091404D03*
Y1084711D03*
X1071941Y1094751D03*
Y1088058D03*
X1079383Y1111483D03*
Y1104790D03*
Y1098097D03*
X1071941Y1108137D03*
Y1101444D03*
X1079383Y1128215D03*
Y1121522D03*
X1071941Y1124869D03*
Y1114829D03*
X1079383Y1141601D03*
Y1134908D03*
X1071941Y1144948D03*
Y1138255D03*
Y1131562D03*
X1079383Y1158333D03*
Y1148294D03*
X1071941Y1161680D03*
Y1151641D03*
X1079383Y1171719D03*
Y1165026D03*
X1071941Y1175066D03*
Y1168373D03*
X1079383Y1185105D03*
Y1178412D03*
X1071941Y1188452D03*
Y1181759D03*
X1079383Y1208530D03*
Y1201837D03*
Y1195144D03*
X1071941Y1205184D03*
Y1198491D03*
X1079383Y1221916D03*
Y1215223D03*
X1071941Y1225263D03*
Y1218570D03*
Y1211877D03*
X1079383Y1238648D03*
Y1231955D03*
X1071941Y1241995D03*
Y1235302D03*
X1071991Y1257262D03*
X1079383Y1245341D03*
X1071941Y1248688D03*
X1079383Y1258727D03*
X1085088Y1273344D03*
X1082288D03*
X1079383Y1265420D03*
Y1262074D03*
X1101641Y773491D03*
X1092941Y770144D03*
X1101641D03*
X1088083Y766798D03*
X1092709Y766775D03*
X1101641Y780184D03*
Y786877D03*
X1092941Y783530D03*
X1101641D03*
X1092941Y776837D03*
X1101641D03*
X1088083Y780184D03*
Y773491D03*
X1101641Y780184D03*
Y773491D03*
Y786877D03*
Y796916D03*
Y790223D03*
Y803609D03*
Y800263D03*
X1092941D03*
X1101641Y793570D03*
X1092941D03*
X1088083Y803609D03*
Y796916D03*
Y790223D03*
X1101641Y803609D03*
Y796916D03*
Y790223D03*
Y816995D03*
Y810302D03*
Y820341D03*
X1092941D03*
X1101641Y813648D03*
X1092941D03*
X1101641Y806955D03*
X1092941D03*
X1088083Y816995D03*
Y810302D03*
X1101641Y816995D03*
Y810302D03*
Y833727D03*
Y823688D03*
Y827034D03*
Y830381D03*
X1092941D03*
X1088083Y833727D03*
Y827034D03*
X1101641Y833727D03*
Y823688D03*
Y827034D03*
Y847113D03*
Y840420D03*
Y853806D03*
Y850459D03*
X1092941D03*
X1101641Y843766D03*
X1092941D03*
X1101641Y837074D03*
X1092941D03*
X1088083Y847113D03*
Y840420D03*
X1101641Y847113D03*
Y840420D03*
Y863845D03*
Y860499D03*
Y870538D03*
Y867192D03*
X1092941D03*
X1101641Y857152D03*
X1092941D03*
X1088083Y863845D03*
Y853806D03*
X1101641D03*
Y860499D03*
Y863845D03*
Y883924D03*
Y877231D03*
Y880577D03*
X1092941D03*
X1101641Y873885D03*
X1092941D03*
X1088083Y883924D03*
Y877231D03*
Y870538D03*
X1101641Y883924D03*
Y877231D03*
Y870538D03*
Y890617D03*
Y897310D03*
Y900656D03*
Y893963D03*
X1092941D03*
X1101641Y887270D03*
X1092941D03*
X1088083Y900656D03*
Y890617D03*
X1101641D03*
Y897310D03*
Y900656D03*
Y914042D03*
Y907349D03*
Y917389D03*
X1092941D03*
X1101641Y910696D03*
X1092941D03*
X1101641Y904003D03*
X1092941D03*
X1088083Y914042D03*
Y907349D03*
X1101641Y914042D03*
Y907349D03*
Y927428D03*
Y920735D03*
Y934121D03*
Y930774D03*
X1092941D03*
X1101641Y924081D03*
X1092941D03*
X1088083Y927428D03*
Y920735D03*
X1101641Y927428D03*
Y920735D03*
Y934121D03*
Y944160D03*
Y937467D03*
Y950853D03*
Y947507D03*
X1092941D03*
X1101641Y940814D03*
X1092941D03*
X1088083Y944160D03*
Y937467D03*
X1101641Y944160D03*
Y937467D03*
Y960892D03*
Y957546D03*
Y967585D03*
Y964239D03*
X1092941D03*
X1101641Y954200D03*
X1092941D03*
X1088083Y960892D03*
Y950853D03*
X1101641Y960892D03*
Y950853D03*
X1088083Y964239D03*
X1101641Y957546D03*
X1088083D03*
Y954200D03*
X1101641Y980971D03*
Y974278D03*
Y977625D03*
X1092941D03*
X1101641Y970932D03*
X1092941D03*
X1088083Y980971D03*
Y974278D03*
Y967585D03*
X1101641Y980971D03*
Y974278D03*
Y967585D03*
Y994357D03*
Y987664D03*
Y991011D03*
X1092941D03*
X1101641Y984318D03*
X1092941D03*
X1088083Y987664D03*
X1101641Y994357D03*
Y987664D03*
Y1027822D03*
Y1021129D03*
Y1031168D03*
X1092941D03*
X1101641Y1024475D03*
X1092941D03*
X1101641Y1017782D03*
X1092941D03*
X1088083Y1027822D03*
Y1017782D03*
Y1021129D03*
Y1024475D03*
X1101641Y1027822D03*
Y1021129D03*
Y1034515D03*
Y1047900D03*
Y1041207D03*
Y1044554D03*
X1092941D03*
X1101641Y1037861D03*
X1092941D03*
X1088083Y1047900D03*
Y1041207D03*
Y1034515D03*
X1101641Y1047900D03*
Y1041207D03*
Y1034515D03*
Y1054593D03*
Y1057940D03*
X1092941D03*
X1101641Y1051247D03*
X1092941D03*
X1088083Y1061286D03*
Y1054593D03*
X1101641Y1061286D03*
X1088083Y1051247D03*
X1101641Y1054593D03*
Y1067979D03*
Y1074672D03*
Y1081365D03*
Y1078018D03*
X1092941D03*
X1101641Y1071326D03*
X1092941D03*
X1101641Y1064633D03*
X1092941D03*
X1088083Y1074672D03*
Y1067979D03*
X1101641Y1074672D03*
Y1067979D03*
Y1084711D03*
Y1091404D03*
Y1098097D03*
Y1094751D03*
X1092941D03*
X1101641Y1088058D03*
X1092941D03*
X1088083Y1091404D03*
Y1084711D03*
X1101641Y1091404D03*
Y1081365D03*
Y1084711D03*
Y1111483D03*
Y1104790D03*
Y1108137D03*
X1092941D03*
X1101641Y1101444D03*
X1092941D03*
X1088083Y1111483D03*
Y1104790D03*
Y1098097D03*
X1101641D03*
Y1111483D03*
Y1104790D03*
Y1118176D03*
Y1128215D03*
Y1121522D03*
Y1124869D03*
X1092941D03*
X1101641Y1114829D03*
X1092941D03*
X1088083Y1128215D03*
Y1121522D03*
X1101641Y1128215D03*
Y1118176D03*
Y1121522D03*
Y1134908D03*
Y1141601D03*
Y1144948D03*
X1092941D03*
X1101641Y1138255D03*
X1092941D03*
X1101641Y1131562D03*
X1092941D03*
X1088083Y1141601D03*
Y1134908D03*
X1101641Y1141601D03*
Y1134908D03*
Y1148294D03*
Y1154987D03*
Y1158333D03*
X1092941Y1161680D03*
X1101641D03*
Y1151641D03*
X1092941D03*
X1088083Y1158333D03*
Y1148294D03*
X1101641D03*
Y1154987D03*
Y1158333D03*
Y1165026D03*
Y1171719D03*
Y1178412D03*
Y1175066D03*
X1092941D03*
X1101641Y1168373D03*
X1092941D03*
X1088083Y1171719D03*
Y1165026D03*
X1101641Y1171719D03*
Y1165026D03*
Y1185105D03*
Y1191798D03*
Y1195144D03*
Y1181759D03*
X1092941D03*
Y1188452D03*
X1101641D03*
X1088083Y1185105D03*
Y1178412D03*
X1101641Y1185105D03*
Y1178412D03*
Y1191798D03*
Y1201837D03*
Y1208530D03*
X1092941Y1205184D03*
X1101641D03*
X1092941Y1198491D03*
X1101641D03*
X1088083Y1208530D03*
Y1201837D03*
Y1195144D03*
X1101641Y1208530D03*
Y1201837D03*
Y1195144D03*
Y1215223D03*
Y1221916D03*
Y1228609D03*
Y1225263D03*
X1092941D03*
X1101641Y1218570D03*
X1092941D03*
Y1211877D03*
X1101641D03*
X1088083Y1221916D03*
Y1215223D03*
X1101641Y1221916D03*
Y1215223D03*
Y1231955D03*
Y1238648D03*
Y1245341D03*
Y1241995D03*
X1092941D03*
X1101641Y1235302D03*
X1092941D03*
X1088083Y1238648D03*
Y1231955D03*
X1101641Y1238648D03*
Y1228609D03*
Y1231955D03*
X1101554Y1257102D03*
X1101641Y1248688D03*
X1092941D03*
X1088083Y1245341D03*
X1090273Y1246800D03*
X1101641Y1245341D03*
X1092941Y1258727D03*
X1088083Y1248688D03*
X1098788Y1273344D03*
X1095988D03*
X1092941Y1265420D03*
X1117783Y770144D03*
X1109083Y766798D03*
X1117783D03*
Y770144D03*
Y776837D03*
Y783530D03*
Y786877D03*
Y780184D03*
X1109083D03*
X1117783Y773491D03*
X1109083D03*
X1117783Y776837D03*
Y786877D03*
Y783530D03*
Y800263D03*
Y793570D03*
Y803609D03*
X1109083D03*
X1117783Y796916D03*
X1109083D03*
Y790223D03*
X1117783D03*
Y800263D03*
Y793570D03*
Y813648D03*
Y806955D03*
Y820341D03*
Y816995D03*
X1109083D03*
X1117783Y810302D03*
X1109083D03*
X1117783Y813648D03*
Y806955D03*
Y820341D03*
Y830381D03*
Y823688D03*
Y837074D03*
Y833727D03*
X1109083D03*
X1117783Y827034D03*
X1109083D03*
X1117783Y830381D03*
Y823688D03*
Y850459D03*
Y843766D03*
Y847113D03*
X1109083D03*
X1117783Y840420D03*
X1109083D03*
X1117783Y850459D03*
Y843766D03*
Y837074D03*
Y867192D03*
Y860499D03*
Y857152D03*
Y863845D03*
X1109083D03*
X1117783Y853806D03*
X1109083D03*
X1117783Y867192D03*
Y860499D03*
Y857152D03*
Y873885D03*
Y880577D03*
Y887270D03*
Y883924D03*
X1109083D03*
X1117783Y877231D03*
X1109083D03*
X1117783Y870538D03*
X1109083D03*
X1117783Y873885D03*
Y880577D03*
Y897310D03*
Y893963D03*
Y904003D03*
Y900656D03*
X1109083D03*
X1117783Y890617D03*
X1109083D03*
X1117783Y887270D03*
Y897310D03*
Y893963D03*
Y917389D03*
Y910696D03*
Y914042D03*
X1109083D03*
X1117783Y907349D03*
X1109083D03*
X1117783Y917389D03*
Y910696D03*
Y904003D03*
Y924081D03*
Y934121D03*
Y930774D03*
Y927428D03*
X1109083D03*
X1117783Y920735D03*
X1109083D03*
X1117783Y924081D03*
Y934121D03*
Y930774D03*
Y947507D03*
Y940814D03*
Y944160D03*
X1109083D03*
X1117783Y937467D03*
X1109083D03*
X1117783Y947507D03*
Y940814D03*
Y964239D03*
Y960892D03*
X1109083D03*
X1117783Y950853D03*
X1109083D03*
X1117783Y964239D03*
Y957546D03*
Y954200D03*
Y977625D03*
Y970932D03*
Y984318D03*
Y980971D03*
X1109083D03*
X1117783Y974278D03*
X1109083D03*
X1117783Y967585D03*
X1109083D03*
X1117783Y977625D03*
Y970932D03*
Y991011D03*
Y987664D03*
X1109083D03*
X1117783Y991011D03*
Y984318D03*
Y994357D03*
Y1021129D03*
Y1024475D03*
Y1031168D03*
Y1027822D03*
X1109083D03*
X1117783Y1017782D03*
X1109083D03*
X1117783Y1021129D03*
Y1024475D03*
Y1031168D03*
Y1044554D03*
Y1037861D03*
Y1047900D03*
X1109083D03*
X1117783Y1041207D03*
X1109083D03*
X1117783Y1034515D03*
X1109083D03*
X1117783Y1044554D03*
Y1037861D03*
Y1051247D03*
Y1064633D03*
Y1061286D03*
X1109083D03*
X1117783Y1054593D03*
X1109083D03*
X1117783Y1051247D03*
Y1057940D03*
Y1071326D03*
Y1078018D03*
Y1081365D03*
Y1074672D03*
X1109083D03*
X1117783Y1067979D03*
X1109083D03*
X1117783Y1071326D03*
Y1064633D03*
Y1078018D03*
Y1094751D03*
Y1088058D03*
Y1091404D03*
X1109083D03*
X1117783Y1084711D03*
X1109083D03*
X1117783Y1094751D03*
Y1088058D03*
Y1081365D03*
Y1101444D03*
Y1108137D03*
Y1114829D03*
Y1111483D03*
X1109083D03*
X1117783Y1104790D03*
X1109083D03*
X1117783Y1098097D03*
X1109083D03*
X1117783Y1108137D03*
Y1101444D03*
Y1118176D03*
Y1124869D03*
Y1131562D03*
Y1128215D03*
X1109083D03*
X1117783Y1121522D03*
X1109083D03*
X1117783Y1124869D03*
Y1118176D03*
Y1114829D03*
Y1144948D03*
Y1138255D03*
Y1141601D03*
X1109083D03*
X1117783Y1134908D03*
X1109083D03*
X1117783Y1144948D03*
Y1138255D03*
Y1131562D03*
Y1151641D03*
Y1161680D03*
Y1154987D03*
Y1158333D03*
X1109083D03*
X1117783Y1148294D03*
X1109083D03*
X1117783Y1161680D03*
Y1154987D03*
Y1151641D03*
Y1168373D03*
Y1175066D03*
Y1171719D03*
X1109083D03*
X1117783Y1165026D03*
X1109083D03*
X1117783Y1175066D03*
Y1168373D03*
Y1181759D03*
Y1188452D03*
Y1191798D03*
Y1185105D03*
X1109083D03*
X1117783Y1178412D03*
X1109083D03*
X1117783Y1181759D03*
Y1191798D03*
Y1188452D03*
Y1198491D03*
Y1205184D03*
Y1211877D03*
Y1208530D03*
X1109083D03*
X1117783Y1201837D03*
X1109083D03*
X1117783Y1195144D03*
X1109083D03*
X1117783Y1205184D03*
Y1198491D03*
Y1218570D03*
Y1225263D03*
Y1228609D03*
Y1221916D03*
X1109083D03*
X1117783Y1215223D03*
X1109083D03*
X1117783Y1218570D03*
Y1211877D03*
Y1225263D03*
Y1235302D03*
Y1241995D03*
Y1238648D03*
X1109083D03*
X1117783Y1231955D03*
X1109083D03*
X1117783Y1241995D03*
Y1235302D03*
Y1228609D03*
Y1245341D03*
X1109083D03*
X1117783Y1248688D03*
X1111988Y1273344D03*
X1114788D03*
X1109083Y1265420D03*
X1109050Y1262972D03*
X1131341Y770144D03*
X1122641D03*
X1122541Y766798D03*
X1131341Y783530D03*
X1122641D03*
X1131341Y776837D03*
X1122641D03*
X1131341Y800263D03*
X1122641D03*
X1131341Y793570D03*
X1122641D03*
X1131341Y820341D03*
X1122641D03*
X1131341Y813648D03*
X1122641D03*
X1131341Y806955D03*
X1122641D03*
X1131341Y830381D03*
X1122641D03*
X1131341Y850459D03*
X1122641D03*
X1131341Y843766D03*
X1122641D03*
X1131341Y837074D03*
X1122641D03*
X1131341Y867192D03*
X1122641D03*
X1131341Y857152D03*
X1122641D03*
X1131341Y880577D03*
X1122641D03*
X1131341Y873885D03*
X1122641D03*
X1131341Y893963D03*
X1122641D03*
X1131341Y887270D03*
X1122641D03*
X1131341Y917389D03*
X1122641D03*
X1131341Y910696D03*
X1122641D03*
X1131341Y904003D03*
X1122641D03*
X1131341Y930774D03*
X1122641D03*
X1131341Y924081D03*
X1122641D03*
Y947507D03*
X1131341D03*
Y940814D03*
X1122641D03*
X1131341Y960892D03*
Y957546D03*
Y967585D03*
Y964239D03*
X1122641D03*
X1131341Y954200D03*
X1122641D03*
X1131341Y960892D03*
Y957546D03*
Y977625D03*
X1122641D03*
X1131341Y970932D03*
X1122641D03*
X1131341Y967585D03*
Y991011D03*
X1122641D03*
X1131341Y984318D03*
X1122641D03*
X1131341Y1031168D03*
X1122641D03*
X1131341Y1024475D03*
X1122641D03*
X1131341Y1017782D03*
X1122641D03*
X1131341Y1044554D03*
X1122641D03*
X1131341Y1037861D03*
X1122641D03*
X1131341Y1054593D03*
Y1057940D03*
X1122641D03*
X1131341Y1051247D03*
X1122641D03*
X1131341Y1054593D03*
Y1078018D03*
X1122641D03*
X1131341Y1071326D03*
X1122641D03*
X1131341Y1064633D03*
X1122641D03*
X1131341Y1094751D03*
X1122641D03*
X1131341Y1088058D03*
X1122641D03*
X1131341Y1108137D03*
X1122641D03*
X1131341Y1101444D03*
X1122641D03*
X1131341Y1124869D03*
X1122641D03*
X1131341Y1114829D03*
X1122641D03*
X1131341Y1144948D03*
X1122641D03*
X1131341Y1138255D03*
X1122641D03*
X1131341Y1131562D03*
X1122641D03*
X1131341Y1161680D03*
X1122641D03*
X1131341Y1151641D03*
X1122641D03*
X1131341Y1175066D03*
X1122641D03*
X1131341Y1168373D03*
X1122641D03*
X1131341Y1188452D03*
X1122641D03*
X1131341Y1181759D03*
X1122641D03*
X1131341Y1205184D03*
X1122641D03*
X1131341Y1198491D03*
X1122641D03*
X1131341Y1225263D03*
X1122641D03*
X1131341Y1218570D03*
X1122641D03*
X1131341Y1211877D03*
X1122641D03*
X1131341Y1241995D03*
X1122641D03*
X1131341Y1235302D03*
X1122641D03*
X1131434Y1257291D03*
X1122641Y1248688D03*
X1131341D03*
X1122641Y1258727D03*
X1126188Y1273344D03*
X1128988D03*
X1122620Y1264622D03*
X1152341Y770144D03*
X1147483Y766798D03*
X1138783D03*
X1152341Y783530D03*
Y776837D03*
X1147483Y780184D03*
X1138783D03*
Y773491D03*
X1147483D03*
X1152341Y800263D03*
X1147483Y803609D03*
X1138783D03*
X1152341Y793570D03*
X1147483Y796916D03*
X1138783D03*
X1147483Y790223D03*
X1138783D03*
X1152341Y820341D03*
X1147483Y816995D03*
X1138783D03*
X1152341Y813648D03*
Y806955D03*
X1147483Y810302D03*
X1138783D03*
X1147483Y833727D03*
X1138783D03*
X1152341Y830381D03*
X1147483Y827034D03*
X1138783D03*
X1152341Y850459D03*
Y843766D03*
Y837074D03*
X1147483Y847113D03*
X1138783D03*
X1147483Y840420D03*
X1138783D03*
X1152341Y867192D03*
Y857152D03*
X1147483Y863845D03*
X1138783D03*
X1147483Y853806D03*
X1138783D03*
X1152341Y880577D03*
Y873885D03*
X1147483Y883924D03*
X1138783D03*
X1147483Y877231D03*
X1138783D03*
X1147483Y870538D03*
X1138783D03*
X1152341Y893963D03*
Y887270D03*
X1138783Y900656D03*
X1147483D03*
X1138783Y890617D03*
X1147483D03*
X1152341Y917389D03*
Y910696D03*
Y904003D03*
X1147483Y914042D03*
X1138783D03*
X1147483Y907349D03*
X1138783D03*
X1152341Y930774D03*
Y924081D03*
X1147483Y927428D03*
X1138783D03*
X1147483Y920735D03*
X1138783D03*
X1152341Y947507D03*
Y940814D03*
X1147483Y944160D03*
X1138783D03*
X1147483Y937467D03*
X1138783D03*
X1147483Y964239D03*
X1152341D03*
Y954200D03*
X1147483Y960892D03*
X1138783D03*
X1147483Y950853D03*
X1138783D03*
X1147483Y964239D03*
Y957546D03*
Y954200D03*
X1152341Y977625D03*
Y970932D03*
X1147483Y980971D03*
X1138783D03*
X1147483Y974278D03*
X1138783D03*
X1147483Y967585D03*
X1138783D03*
X1152341Y991011D03*
Y984318D03*
X1147483Y987664D03*
X1138783D03*
Y994357D03*
X1147483Y1021129D03*
Y1024475D03*
X1152341Y1031168D03*
Y1024475D03*
Y1017782D03*
X1147483Y1027822D03*
X1138783D03*
X1147483Y1017782D03*
X1138783D03*
X1147483Y1021129D03*
Y1024475D03*
X1152341Y1044554D03*
Y1037861D03*
X1138783Y1047900D03*
X1147483D03*
Y1041207D03*
X1138783D03*
X1147483Y1034515D03*
X1138783D03*
X1147483Y1051247D03*
X1152341Y1057940D03*
Y1051247D03*
X1147483Y1061286D03*
X1138783D03*
X1147483Y1054593D03*
X1138783D03*
X1147483Y1051247D03*
X1152341Y1078018D03*
Y1071326D03*
Y1064633D03*
X1147483Y1074672D03*
X1138783D03*
X1147483Y1067979D03*
X1138783D03*
X1152341Y1094751D03*
Y1088058D03*
X1147483Y1091404D03*
X1138783D03*
X1147483Y1084711D03*
X1138783D03*
X1152341Y1108137D03*
Y1101444D03*
X1147483Y1111483D03*
X1138783D03*
X1147483Y1104790D03*
X1138783D03*
X1147483Y1098097D03*
X1138783D03*
X1152341Y1124869D03*
Y1114829D03*
X1147483Y1128215D03*
X1138783D03*
X1147483Y1121522D03*
X1138783D03*
X1152341Y1144948D03*
Y1138255D03*
Y1131562D03*
X1147483Y1141601D03*
X1138783D03*
X1147483Y1134908D03*
X1138783D03*
X1152341Y1161680D03*
Y1151641D03*
X1147483Y1158333D03*
X1138783D03*
Y1148294D03*
X1147483D03*
X1152341Y1175066D03*
Y1168373D03*
X1147483Y1171719D03*
X1138783D03*
X1147483Y1165026D03*
X1138783D03*
X1152341Y1188452D03*
Y1181759D03*
X1147483Y1185105D03*
X1138783D03*
X1147483Y1178412D03*
X1138783D03*
X1152341Y1205184D03*
Y1198491D03*
X1147483Y1208530D03*
X1138783D03*
X1147483Y1201837D03*
X1138783D03*
X1147483Y1195144D03*
X1138783D03*
X1152341Y1225263D03*
Y1218570D03*
Y1211877D03*
X1147483Y1221916D03*
X1138783D03*
X1147483Y1215223D03*
X1138783D03*
X1152341Y1241995D03*
Y1235302D03*
X1147483Y1238648D03*
X1138783D03*
X1147483Y1231955D03*
X1138783D03*
X1152341Y1248688D03*
X1147483Y1245341D03*
X1138783D03*
X1152341Y1258727D03*
X1138783D03*
Y1252034D03*
X1147483Y1248688D03*
X1152381Y1269684D03*
X1147681D03*
X1138201Y1270277D03*
X1152341Y1265420D03*
X1138783Y1262027D03*
X1137980Y1264212D03*
X1161041Y773491D03*
X1168483Y766798D03*
X1161041Y770144D03*
Y780184D03*
Y786877D03*
X1168483Y780184D03*
Y773491D03*
X1161041Y783530D03*
Y776837D03*
Y780184D03*
Y773491D03*
Y786877D03*
Y796916D03*
Y790223D03*
Y803609D03*
X1168483D03*
Y796916D03*
Y790223D03*
X1161041Y800263D03*
Y793570D03*
Y803609D03*
Y796916D03*
Y790223D03*
Y816995D03*
Y810302D03*
X1168483Y816995D03*
Y810302D03*
X1161041Y820341D03*
Y813648D03*
Y806955D03*
Y816995D03*
Y810302D03*
Y833727D03*
Y823688D03*
Y827034D03*
X1168483Y833727D03*
X1167633Y827034D03*
X1161041Y830381D03*
Y833727D03*
Y823688D03*
Y827034D03*
Y847113D03*
Y840420D03*
Y853806D03*
X1168483Y847113D03*
Y840420D03*
X1161041Y850459D03*
Y843766D03*
Y837074D03*
Y847113D03*
Y840420D03*
Y860499D03*
Y863845D03*
Y870538D03*
X1167633Y863845D03*
X1161041Y867192D03*
X1168483Y853806D03*
X1161041Y857152D03*
Y853806D03*
Y860499D03*
Y863845D03*
Y883924D03*
Y877231D03*
X1168483Y883924D03*
Y877231D03*
Y870538D03*
X1161041Y880577D03*
Y873885D03*
Y883924D03*
Y877231D03*
Y870538D03*
Y890617D03*
Y897310D03*
Y900656D03*
X1168483D03*
Y890617D03*
X1161041Y893963D03*
Y887270D03*
Y890617D03*
Y897310D03*
Y900656D03*
Y914042D03*
Y907349D03*
X1168483Y914042D03*
Y907349D03*
X1161041Y917389D03*
Y910696D03*
Y904003D03*
Y914042D03*
Y907349D03*
Y927428D03*
Y920735D03*
Y934121D03*
X1167633Y927428D03*
X1168483Y920735D03*
X1161041Y930774D03*
Y924081D03*
Y927428D03*
Y920735D03*
Y934121D03*
Y944160D03*
Y937467D03*
Y950853D03*
X1168483Y937467D03*
Y944160D03*
X1161041Y947507D03*
Y940814D03*
Y944160D03*
Y937467D03*
Y960892D03*
Y957546D03*
Y967585D03*
X1168483Y960892D03*
Y950853D03*
X1161041Y964239D03*
Y954200D03*
Y960892D03*
Y950853D03*
Y957546D03*
Y980971D03*
Y974278D03*
X1168483D03*
Y980971D03*
Y967585D03*
X1161041Y977625D03*
Y970932D03*
Y980971D03*
Y974278D03*
Y967585D03*
Y994357D03*
Y987664D03*
X1168483D03*
X1161041Y991011D03*
Y984318D03*
Y994357D03*
Y987664D03*
Y1027822D03*
Y1021129D03*
X1168483Y1027822D03*
Y1017782D03*
X1161041Y1031168D03*
Y1024475D03*
Y1017782D03*
Y1027822D03*
Y1021129D03*
Y1034515D03*
Y1047900D03*
Y1041207D03*
X1168483Y1047900D03*
Y1041207D03*
Y1034515D03*
X1161041Y1044554D03*
Y1037861D03*
Y1047900D03*
Y1041207D03*
Y1034515D03*
Y1054593D03*
X1168483D03*
Y1061286D03*
X1161041Y1057940D03*
Y1051247D03*
Y1061286D03*
Y1054593D03*
Y1067979D03*
Y1074672D03*
Y1081365D03*
X1168483Y1074672D03*
Y1067979D03*
X1161041Y1078018D03*
Y1071326D03*
Y1064633D03*
Y1074672D03*
Y1067979D03*
Y1084711D03*
Y1091404D03*
Y1098097D03*
X1168483Y1091404D03*
X1167633Y1084711D03*
X1161041Y1094751D03*
Y1088058D03*
Y1091404D03*
Y1081365D03*
Y1084711D03*
Y1104790D03*
Y1111483D03*
X1168483D03*
Y1104790D03*
Y1098097D03*
X1161041Y1108137D03*
Y1101444D03*
Y1098097D03*
Y1111483D03*
Y1104790D03*
Y1118176D03*
Y1128215D03*
Y1121522D03*
X1168483Y1128215D03*
Y1121522D03*
X1161041Y1124869D03*
Y1114829D03*
Y1128215D03*
Y1118176D03*
Y1121522D03*
Y1134908D03*
Y1141601D03*
X1168483D03*
Y1134908D03*
X1161041Y1144948D03*
Y1138255D03*
Y1131562D03*
Y1141601D03*
Y1134908D03*
Y1148294D03*
Y1154987D03*
Y1158333D03*
X1167633D03*
X1168483Y1148294D03*
X1161041Y1161680D03*
Y1151641D03*
Y1148294D03*
Y1154987D03*
Y1158333D03*
Y1165026D03*
Y1171719D03*
Y1178412D03*
X1168483Y1171719D03*
Y1165026D03*
X1161041Y1175066D03*
Y1168373D03*
Y1171719D03*
Y1165026D03*
Y1185105D03*
Y1191798D03*
Y1195144D03*
X1168483Y1185105D03*
Y1178412D03*
X1161041Y1188452D03*
Y1181759D03*
Y1185105D03*
Y1178412D03*
Y1191798D03*
Y1201837D03*
Y1208530D03*
X1168483D03*
Y1201837D03*
Y1195144D03*
X1161041Y1205184D03*
Y1198491D03*
Y1208530D03*
Y1201837D03*
Y1195144D03*
Y1215223D03*
Y1221916D03*
Y1228609D03*
X1168483Y1221916D03*
Y1215223D03*
X1161041Y1225263D03*
Y1218570D03*
Y1211877D03*
Y1221916D03*
Y1215223D03*
Y1231955D03*
Y1238648D03*
Y1245341D03*
X1168483Y1238648D03*
X1167633Y1231955D03*
X1161041Y1241995D03*
Y1235302D03*
Y1238648D03*
Y1228609D03*
Y1231955D03*
X1161065Y1258871D03*
X1168483Y1245341D03*
X1161041Y1248688D03*
Y1245341D03*
X1168483Y1258727D03*
Y1252034D03*
X1161781Y1269684D03*
X1168483Y1265420D03*
Y1262074D03*
X1177183Y770144D03*
X1182041D03*
X1177183Y766798D03*
Y770144D03*
Y776837D03*
Y783530D03*
Y786877D03*
X1182041Y783530D03*
Y776837D03*
X1177183Y780184D03*
Y773491D03*
Y776837D03*
Y786877D03*
Y783530D03*
Y800263D03*
Y793570D03*
X1182041Y800263D03*
Y793570D03*
X1177183Y803609D03*
Y796916D03*
Y790223D03*
Y800263D03*
Y793570D03*
Y813648D03*
Y806955D03*
Y820341D03*
X1182041Y813648D03*
Y806955D03*
X1181191Y820341D03*
X1177183Y816995D03*
Y810302D03*
Y813648D03*
Y806955D03*
Y820341D03*
Y830381D03*
Y823688D03*
Y837074D03*
X1181191Y830381D03*
X1177183Y833727D03*
Y827034D03*
Y830381D03*
Y823688D03*
Y850459D03*
Y843766D03*
X1182041Y850459D03*
Y837074D03*
Y843766D03*
X1177183Y847113D03*
Y840420D03*
Y850459D03*
Y843766D03*
Y837074D03*
Y867192D03*
Y860499D03*
Y857152D03*
X1181191Y867192D03*
X1177183Y863845D03*
X1181191Y857152D03*
X1177183Y853806D03*
Y867192D03*
Y860499D03*
Y857152D03*
Y873885D03*
Y880577D03*
Y887270D03*
X1182041Y873885D03*
Y880577D03*
X1177183Y883924D03*
Y877231D03*
Y870538D03*
Y873885D03*
Y880577D03*
Y897310D03*
Y893963D03*
Y904003D03*
X1182041Y893963D03*
Y887270D03*
X1177183Y900656D03*
Y890617D03*
Y887270D03*
Y897310D03*
Y893963D03*
Y917389D03*
Y910696D03*
X1182041Y917389D03*
Y910696D03*
Y904003D03*
X1177183Y914042D03*
Y907349D03*
Y917389D03*
Y910696D03*
Y904003D03*
Y924081D03*
Y934121D03*
Y930774D03*
X1181191D03*
Y924081D03*
X1177183Y927428D03*
Y920735D03*
Y924081D03*
Y934121D03*
Y930774D03*
Y947507D03*
Y940814D03*
X1182041D03*
Y947507D03*
X1177183Y937467D03*
Y944160D03*
Y947507D03*
Y940814D03*
Y964239D03*
X1182041D03*
Y954200D03*
X1177183Y960892D03*
Y950853D03*
Y964239D03*
Y957546D03*
Y954200D03*
Y977625D03*
Y970932D03*
Y984318D03*
X1182041Y970932D03*
Y977625D03*
X1177183Y974278D03*
Y980971D03*
Y967585D03*
Y977625D03*
Y970932D03*
Y991011D03*
X1182041D03*
Y984318D03*
X1177183Y987664D03*
Y991011D03*
Y984318D03*
Y994357D03*
X1177283Y1021129D03*
Y1024475D03*
Y1031168D03*
X1182041D03*
Y1017782D03*
Y1024475D03*
X1177183Y1027822D03*
Y1017782D03*
X1177283Y1021129D03*
Y1024475D03*
Y1031168D03*
Y1044554D03*
Y1037861D03*
X1182041Y1044554D03*
Y1037861D03*
X1177183Y1047900D03*
Y1041207D03*
Y1034515D03*
X1177283Y1044554D03*
Y1037861D03*
Y1051247D03*
Y1064633D03*
X1182041Y1057940D03*
Y1051247D03*
X1177183Y1054593D03*
Y1061286D03*
X1177283Y1051247D03*
Y1071326D03*
Y1078018D03*
Y1081366D03*
X1181191Y1078018D03*
X1182041Y1071326D03*
Y1064633D03*
X1177183Y1074672D03*
Y1067979D03*
X1177283Y1071326D03*
Y1064633D03*
Y1078018D03*
Y1094752D03*
Y1088059D03*
X1182041Y1094751D03*
X1181191Y1088058D03*
X1177183Y1091404D03*
Y1084711D03*
X1177283Y1094752D03*
Y1088059D03*
Y1081366D03*
Y1101444D03*
Y1108137D03*
Y1114830D03*
X1182041Y1101444D03*
Y1108137D03*
X1177183Y1111483D03*
Y1104790D03*
Y1098097D03*
X1177283Y1108137D03*
Y1101444D03*
Y1118177D03*
X1177183Y1124869D03*
Y1131562D03*
X1182041Y1114829D03*
Y1124869D03*
X1177183Y1128215D03*
Y1121522D03*
Y1124869D03*
X1177283Y1118177D03*
Y1114830D03*
Y1144948D03*
Y1138255D03*
X1182041Y1144948D03*
Y1138255D03*
Y1131562D03*
X1177183Y1141601D03*
Y1134908D03*
X1177283Y1144948D03*
Y1138255D03*
X1177183Y1131562D03*
X1177283Y1151641D03*
Y1161680D03*
Y1154988D03*
X1181191Y1161680D03*
Y1151641D03*
X1177183Y1158333D03*
Y1148294D03*
X1177283Y1161680D03*
Y1154988D03*
Y1151641D03*
Y1168373D03*
Y1175066D03*
X1182041Y1168373D03*
Y1175066D03*
X1177183Y1171719D03*
Y1165026D03*
X1177283Y1175066D03*
Y1168373D03*
Y1181759D03*
Y1188452D03*
Y1191799D03*
X1182041Y1188452D03*
Y1181759D03*
X1177183Y1185105D03*
Y1178412D03*
X1177283Y1181759D03*
Y1191799D03*
Y1188452D03*
Y1198491D03*
Y1205184D03*
Y1211877D03*
X1182041Y1205184D03*
Y1198491D03*
X1177183Y1208530D03*
Y1201837D03*
Y1195144D03*
X1177283Y1205184D03*
Y1198491D03*
Y1218570D03*
Y1225263D03*
Y1228609D03*
X1181191Y1225263D03*
X1182041Y1211877D03*
Y1218570D03*
X1177183Y1221916D03*
Y1215223D03*
X1177283Y1218570D03*
Y1211877D03*
Y1225263D03*
Y1235302D03*
X1177250Y1241995D03*
X1182041D03*
X1181191Y1235302D03*
X1177183Y1238648D03*
Y1231955D03*
X1177250Y1241995D03*
X1177283Y1235302D03*
Y1228609D03*
X1182041Y1248688D03*
X1177183Y1245341D03*
X1177120Y1248688D03*
X1176867Y1270029D03*
X1182041Y1265420D03*
X1181850Y1260192D03*
X1198183Y766798D03*
X1190741Y770144D03*
X1198183Y780184D03*
Y773491D03*
X1190741Y783530D03*
Y776837D03*
X1198183Y803609D03*
Y796916D03*
Y790223D03*
X1190741Y800263D03*
Y793570D03*
X1197333Y816995D03*
X1198183Y810302D03*
X1190741Y813648D03*
Y806955D03*
X1191591Y820341D03*
X1198183Y833727D03*
X1197333Y827034D03*
X1191591Y830381D03*
X1198183Y847113D03*
Y840420D03*
X1190741Y850459D03*
Y837074D03*
Y843766D03*
X1197333Y863845D03*
X1191591Y867192D03*
X1198183Y853806D03*
X1191591Y857152D03*
X1198183Y877231D03*
X1197333Y870538D03*
X1198183Y883924D03*
X1190741Y873885D03*
Y880577D03*
X1198183Y900656D03*
Y890617D03*
X1190741Y893963D03*
Y887270D03*
X1198183Y914042D03*
Y907349D03*
X1190741Y917389D03*
Y910696D03*
Y904003D03*
X1197383Y927428D03*
X1198183Y920735D03*
X1191591Y930774D03*
Y924081D03*
X1198183Y944160D03*
X1197333Y937467D03*
X1190741Y940814D03*
Y947507D03*
Y960892D03*
Y957546D03*
X1198183Y960892D03*
Y950853D03*
X1190741Y964239D03*
Y954200D03*
Y960892D03*
Y957546D03*
X1198183D03*
Y954200D03*
Y980971D03*
Y974278D03*
Y967585D03*
X1190741Y970932D03*
Y977625D03*
X1198183Y987664D03*
X1190741Y991011D03*
Y984318D03*
X1198183Y994357D03*
Y1027822D03*
Y1017782D03*
X1190741Y1031168D03*
Y1017782D03*
Y1024475D03*
X1198183Y1047900D03*
Y1041207D03*
Y1034515D03*
X1190741Y1044554D03*
Y1037861D03*
X1198183Y1054593D03*
Y1061286D03*
X1190741Y1057940D03*
Y1051247D03*
X1197333Y1074672D03*
X1198183Y1067979D03*
X1191591Y1078018D03*
X1190741Y1071326D03*
Y1064633D03*
X1198183Y1091404D03*
X1197333Y1084711D03*
X1190741Y1094751D03*
X1191591Y1088058D03*
X1198183Y1111483D03*
Y1098097D03*
Y1104790D03*
X1190741Y1101444D03*
Y1108137D03*
X1198183Y1128215D03*
Y1121522D03*
X1190741Y1114829D03*
Y1124869D03*
X1198183Y1141601D03*
X1197333Y1134908D03*
X1190741Y1144948D03*
Y1138255D03*
Y1131562D03*
X1198183Y1158333D03*
X1197333Y1148294D03*
X1191591Y1161680D03*
Y1151641D03*
X1198183Y1165026D03*
Y1171719D03*
X1190741Y1168373D03*
Y1175066D03*
X1198183Y1185105D03*
Y1178412D03*
X1190741Y1188452D03*
Y1181759D03*
X1198183Y1208530D03*
Y1201837D03*
Y1195144D03*
X1190741Y1205184D03*
Y1198491D03*
X1198183Y1221916D03*
Y1215223D03*
X1191591Y1225263D03*
X1190741Y1211877D03*
Y1218570D03*
X1197333Y1238648D03*
Y1231955D03*
X1190741Y1241995D03*
X1191591Y1235302D03*
X1198183Y1245341D03*
X1190966Y1258711D03*
X1190741Y1248688D03*
X1198183Y1252034D03*
X1191538Y1270004D03*
X1198180Y1262112D03*
X1196470Y1265382D03*
X1194572Y1578182D03*
Y1590094D03*
X1199872Y1614292D03*
Y1602380D03*
X1211741Y770144D03*
X1206883Y766798D03*
X1211641D03*
X1211741Y783530D03*
Y776837D03*
X1206883Y780184D03*
Y773491D03*
X1211741Y800263D03*
Y793570D03*
X1206883Y803609D03*
Y796916D03*
Y790223D03*
X1210891Y820341D03*
Y813648D03*
X1211741Y806955D03*
X1207148Y817554D03*
X1206883Y810302D03*
X1211741Y830381D03*
X1206883Y833727D03*
X1207733Y827034D03*
X1211741Y850459D03*
Y837074D03*
Y843766D03*
X1206883Y847113D03*
Y840420D03*
X1210891Y867492D03*
X1207733Y863845D03*
X1210891Y857152D03*
X1206883Y853806D03*
X1211741Y874185D03*
Y880577D03*
X1206883Y877231D03*
X1207201Y871084D03*
X1206883Y883924D03*
X1211741Y893963D03*
Y887270D03*
X1206883Y900656D03*
Y890617D03*
X1211741Y917389D03*
Y910696D03*
Y904003D03*
X1206883Y914042D03*
Y907349D03*
X1211741Y930774D03*
Y924081D03*
X1207683Y927428D03*
X1206883Y920735D03*
X1211741Y947507D03*
X1211001Y940814D03*
X1206883Y944660D03*
X1207733Y937467D03*
X1211741Y964239D03*
Y954200D03*
X1206883Y960892D03*
Y950853D03*
X1211741Y977625D03*
Y970932D03*
X1206883Y980971D03*
Y974278D03*
Y967585D03*
X1211741Y991011D03*
X1206883Y987664D03*
X1211741Y984318D03*
X1213983Y1000437D03*
X1216663Y1000395D03*
X1212533Y1002557D03*
X1205033D03*
X1207533D03*
X1210033D03*
X1211741Y1031168D03*
X1206883Y1027822D03*
Y1017782D03*
X1211741D03*
Y1024475D03*
Y1044554D03*
Y1037861D03*
X1206883Y1047900D03*
Y1041207D03*
Y1034515D03*
X1211741Y1051247D03*
Y1057940D03*
X1206883Y1054593D03*
Y1061286D03*
X1210891Y1078018D03*
X1211741Y1064633D03*
Y1071326D03*
X1207733Y1074672D03*
X1206883Y1067979D03*
X1211741Y1094751D03*
X1210891Y1088058D03*
X1206883Y1091404D03*
Y1084711D03*
X1211741Y1108137D03*
Y1101444D03*
X1206883Y1111483D03*
Y1098097D03*
Y1104790D03*
X1210891Y1124869D03*
X1211741Y1114829D03*
X1206883Y1128215D03*
Y1121522D03*
X1211741Y1144948D03*
Y1138255D03*
X1210891Y1131562D03*
X1206883Y1141601D03*
X1207733Y1134908D03*
X1211741Y1151641D03*
Y1161680D03*
X1206883Y1158333D03*
X1207733Y1148294D03*
X1211741Y1175066D03*
Y1168373D03*
X1206883Y1165026D03*
Y1171719D03*
X1211741Y1188452D03*
Y1181759D03*
X1206883Y1185105D03*
Y1178412D03*
X1211741Y1205184D03*
Y1198491D03*
X1206883Y1208530D03*
Y1201837D03*
Y1195144D03*
X1210891Y1225263D03*
X1211741Y1218570D03*
Y1211877D03*
X1206883Y1221916D03*
Y1215223D03*
X1211741Y1241995D03*
X1211328Y1234977D03*
X1207733Y1238648D03*
Y1231955D03*
X1206883Y1245341D03*
X1211741Y1248688D03*
X1208830Y1256692D03*
X1206883Y1248688D03*
X1207048Y1255174D03*
X1204608Y1273119D03*
X1202043Y1273123D03*
X1211240Y1265502D03*
X1202372Y1578182D03*
X1214432D03*
X1206632D03*
X1202372Y1590094D03*
X1214432D03*
X1206632D03*
X1207672Y1602380D03*
Y1614292D03*
X1211932D03*
Y1602380D03*
X1227883Y766798D03*
X1220441Y770144D03*
X1227883Y780184D03*
Y773491D03*
X1220441Y783530D03*
Y776837D03*
X1227883Y803609D03*
Y796916D03*
Y790223D03*
X1220441Y800263D03*
Y793570D03*
X1227033Y816995D03*
X1227883Y810302D03*
X1221291Y820341D03*
Y813648D03*
X1220441Y806955D03*
X1227883Y833727D03*
X1227033Y827034D03*
X1220441Y830381D03*
X1227883Y847113D03*
Y840420D03*
X1220441Y850459D03*
Y837074D03*
Y843766D03*
X1227033Y863845D03*
X1221291Y867192D03*
X1227033Y853806D03*
X1221291Y857152D03*
X1220441Y883924D03*
X1227883Y870538D03*
Y883924D03*
Y877231D03*
X1220441Y873885D03*
Y880577D03*
Y883924D03*
Y890617D03*
Y897310D03*
Y900656D03*
X1227033D03*
X1227883Y890617D03*
X1220441Y893963D03*
Y887270D03*
Y890617D03*
Y897310D03*
Y900656D03*
Y914042D03*
Y907349D03*
X1227883Y914042D03*
Y907349D03*
X1220441Y917389D03*
Y910696D03*
Y904003D03*
Y914042D03*
Y907349D03*
X1227033Y927428D03*
X1227883Y920735D03*
X1221291Y930774D03*
X1220441Y924081D03*
X1227883Y944160D03*
X1227033Y937467D03*
X1220441Y947507D03*
X1221291Y940814D03*
X1220441Y960892D03*
Y957546D03*
X1227883Y960892D03*
Y950853D03*
X1220441Y964239D03*
Y954200D03*
Y960892D03*
Y957546D03*
X1227883D03*
Y954200D03*
Y974278D03*
Y967585D03*
X1220441Y977625D03*
Y970932D03*
X1227883Y980971D03*
Y987664D03*
X1220441Y991011D03*
Y984318D03*
X1227883Y994357D03*
X1233703Y999608D03*
X1231023Y999650D03*
X1227883Y1027822D03*
X1220441Y1031168D03*
X1227883Y1017782D03*
X1220441D03*
Y1024475D03*
X1227883Y1047900D03*
Y1041207D03*
Y1034515D03*
X1220441Y1044554D03*
Y1037861D03*
X1227883Y1061286D03*
Y1054593D03*
X1220441Y1051247D03*
Y1057940D03*
Y1061286D03*
X1227033Y1074672D03*
Y1067979D03*
X1221291Y1078018D03*
X1220441Y1064633D03*
Y1071326D03*
X1227883Y1091404D03*
Y1084711D03*
X1220441Y1094751D03*
X1221291Y1088058D03*
X1227883Y1104790D03*
X1227033Y1111483D03*
X1227883Y1098097D03*
X1220441Y1108137D03*
Y1101444D03*
X1227883Y1128215D03*
X1227033Y1121522D03*
X1221291Y1124869D03*
X1220441Y1114829D03*
X1227883Y1134908D03*
Y1141601D03*
X1220441Y1144948D03*
Y1138255D03*
X1221291Y1131562D03*
X1227883Y1158333D03*
Y1148294D03*
X1220441Y1151641D03*
Y1161680D03*
Y1178412D03*
X1227883Y1171719D03*
Y1165026D03*
X1220441Y1175066D03*
Y1168373D03*
Y1185105D03*
Y1191798D03*
Y1195144D03*
X1227883Y1185105D03*
Y1178412D03*
X1220441Y1188452D03*
Y1181759D03*
Y1185105D03*
Y1178412D03*
Y1191798D03*
Y1201837D03*
Y1208530D03*
X1227883D03*
Y1201837D03*
X1227033Y1195144D03*
X1220441Y1205184D03*
Y1198491D03*
Y1208530D03*
Y1201837D03*
Y1195144D03*
X1227033Y1221916D03*
X1227883Y1215223D03*
X1221291Y1225263D03*
X1220441Y1218570D03*
Y1211877D03*
X1227883Y1238648D03*
X1227033Y1231955D03*
X1220441Y1241995D03*
X1221291Y1235302D03*
X1220441Y1248688D03*
X1227883Y1245341D03*
X1226899Y1257968D03*
X1227847Y1251715D03*
X1220601Y1269684D03*
X1220931Y1260093D03*
X1233327Y1274515D03*
X1231377Y1275855D03*
X1227670Y1265162D03*
X1225540Y1266402D03*
X1218692Y1578182D03*
X1226492D03*
X1230752D03*
X1218692Y1590094D03*
X1226492D03*
X1230752D03*
X1219732Y1614292D03*
Y1602380D03*
X1231792Y1614292D03*
Y1602380D03*
X1223992D03*
Y1614292D03*
X1236583Y766798D03*
Y780184D03*
Y773491D03*
Y803609D03*
Y796916D03*
Y790223D03*
X1237433Y816995D03*
X1236583Y810302D03*
Y833727D03*
X1237433Y827034D03*
X1236583Y847113D03*
Y840420D03*
X1237433Y863845D03*
Y853806D03*
X1236583Y880577D03*
Y887270D03*
Y870538D03*
Y883924D03*
Y877231D03*
Y880577D03*
Y897310D03*
Y893963D03*
Y904003D03*
Y900656D03*
Y890617D03*
Y887270D03*
Y897310D03*
Y893963D03*
Y910696D03*
Y914042D03*
Y907349D03*
Y910696D03*
Y904003D03*
X1237433Y927428D03*
X1236583Y920735D03*
Y944160D03*
X1237433Y937467D03*
X1236583Y960892D03*
Y950853D03*
Y974278D03*
Y967585D03*
Y980971D03*
Y987664D03*
Y1027822D03*
Y1017782D03*
Y1047900D03*
Y1041207D03*
Y1034515D03*
Y1061286D03*
Y1054593D03*
Y1057940D03*
X1237433Y1074672D03*
Y1067979D03*
X1236583Y1091404D03*
Y1084711D03*
Y1104790D03*
X1237433Y1111483D03*
X1236583Y1098097D03*
Y1128215D03*
X1237433Y1121522D03*
X1236583Y1134908D03*
Y1141601D03*
Y1158333D03*
Y1148294D03*
Y1175066D03*
Y1171719D03*
Y1165026D03*
Y1175066D03*
Y1181759D03*
Y1188452D03*
Y1191798D03*
Y1185105D03*
Y1178412D03*
Y1181759D03*
Y1191798D03*
Y1188452D03*
Y1198491D03*
Y1205184D03*
Y1208530D03*
Y1201837D03*
Y1195144D03*
Y1205184D03*
Y1198491D03*
X1237433Y1221916D03*
X1236583Y1215223D03*
Y1238648D03*
X1237433Y1231955D03*
X1236583Y1245341D03*
Y1248688D03*
X1238552Y1578182D03*
X1242812D03*
X1238552Y1590094D03*
X1242812D03*
X1236052Y1602380D03*
Y1614292D03*
X1243852D03*
Y1602380D03*
X1248112D03*
Y1614292D03*
X1241142Y1675383D03*
Y1679920D03*
X1249016Y1679320D03*
X1241142Y1684454D03*
Y1689556D03*
Y1694093D03*
Y1698627D03*
X1249016Y1688391D03*
Y1693493D03*
Y1698030D03*
Y1683857D03*
X1241142Y1703729D03*
Y1708266D03*
Y1712800D03*
X1249016Y1707666D03*
Y1712203D03*
Y1702564D03*
X1241142Y1726974D03*
Y1722440D03*
Y1717903D03*
X1249016Y1730911D03*
Y1726377D03*
Y1721840D03*
Y1716737D03*
X1250612Y1578182D03*
X1262672D03*
X1254872D03*
X1250612Y1590094D03*
X1262672D03*
X1254872D03*
X1255912Y1614292D03*
Y1602380D03*
X1260172D03*
Y1614292D03*
X1256890Y1675383D03*
Y1679920D03*
X1264764Y1679320D03*
X1256890Y1684454D03*
Y1689556D03*
Y1694093D03*
Y1698627D03*
X1264764Y1688391D03*
Y1693493D03*
Y1698030D03*
Y1683857D03*
X1256890Y1703729D03*
Y1708266D03*
Y1712800D03*
X1264764Y1707666D03*
Y1712203D03*
Y1702564D03*
X1256890Y1726974D03*
Y1722440D03*
Y1717903D03*
X1264764Y1730911D03*
Y1726377D03*
Y1721840D03*
Y1716737D03*
X1266932Y1578182D03*
X1274732D03*
X1278992D03*
X1266932Y1590094D03*
X1274732D03*
X1278992D03*
X1267972Y1614292D03*
Y1602380D03*
X1272232D03*
Y1614292D03*
X1280032D03*
Y1602380D03*
X1272638Y1675383D03*
Y1679920D03*
X1280512Y1679320D03*
X1272638Y1684454D03*
Y1689556D03*
Y1694093D03*
Y1698627D03*
X1280512Y1688391D03*
Y1693493D03*
Y1698030D03*
Y1683857D03*
X1272638Y1703729D03*
Y1708266D03*
Y1712800D03*
X1280512Y1707666D03*
Y1712203D03*
Y1702564D03*
X1272638Y1726974D03*
Y1722440D03*
Y1717903D03*
X1280512Y1730911D03*
Y1726377D03*
Y1721840D03*
Y1716737D03*
X1297012Y157449D03*
X1293802Y159299D03*
Y162999D03*
X1297007Y161149D03*
X1297012Y168549D03*
X1297007Y164849D03*
X1293802Y166699D03*
X1293511Y179048D03*
X1296999Y183349D03*
X1297007Y172249D03*
X1296999Y175949D03*
X1293802Y183349D03*
Y170399D03*
X1294163Y175865D03*
X1296999Y194449D03*
Y198149D03*
X1293802Y187049D03*
Y190749D03*
Y198149D03*
Y194449D03*
Y201849D03*
X1296999Y187049D03*
X1293805Y211099D03*
X1293798Y205833D03*
X1296999Y216649D03*
Y209249D03*
X1293807Y218499D03*
Y214799D03*
X1296999Y212949D03*
Y205549D03*
X1294357Y224688D03*
X1296999Y224049D03*
X1293807Y222199D03*
X1286792Y1578182D03*
X1298852D03*
X1291052D03*
X1286792Y1590094D03*
X1298852D03*
X1291052D03*
X1284292Y1602380D03*
Y1614292D03*
X1292092D03*
Y1602380D03*
X1296352D03*
Y1614292D03*
X1296260Y1679320D03*
X1288386Y1675383D03*
Y1679920D03*
X1296260Y1688391D03*
Y1693493D03*
Y1698030D03*
Y1683857D03*
X1288386Y1684454D03*
Y1689556D03*
Y1694093D03*
Y1698627D03*
X1296260Y1707666D03*
Y1712203D03*
Y1702564D03*
X1288386Y1703729D03*
Y1708266D03*
Y1712800D03*
X1296260Y1730911D03*
Y1726377D03*
Y1721840D03*
Y1716737D03*
X1288386Y1726974D03*
Y1722440D03*
Y1717903D03*
X1303417Y164849D03*
X1300213Y162999D03*
X1300212Y166699D03*
X1306622D03*
X1300774Y155288D03*
X1309832Y161149D03*
X1303417D03*
X1309832Y168549D03*
X1303417D03*
X1309832Y157449D03*
X1306626Y162999D03*
Y159299D03*
X1313037Y162999D03*
X1309832Y164849D03*
X1313037Y159299D03*
X1303417Y157449D03*
X1300217Y159299D03*
X1313033Y166699D03*
X1300212Y170399D03*
X1306626D03*
X1303407Y183349D03*
X1309817Y175949D03*
X1300212Y174099D03*
X1313037Y170399D03*
X1300207Y177799D03*
X1303422Y172249D03*
X1313033Y174099D03*
X1306622D03*
X1300207Y185199D03*
X1306617Y181499D03*
Y185199D03*
X1309832Y172249D03*
X1313027Y181499D03*
Y185199D03*
X1303407Y175949D03*
Y179649D03*
X1309817D03*
X1300204Y181499D03*
X1309817Y194449D03*
X1306617Y188899D03*
X1303407Y194449D03*
X1306617Y196299D03*
X1300207D03*
X1303407Y187049D03*
X1300207Y192599D03*
X1309817Y187049D03*
X1306617Y192599D03*
X1313023Y199999D03*
X1306617D03*
X1300207D03*
X1303407Y201849D03*
X1300204Y188899D03*
X1313027Y192599D03*
X1309817Y190749D03*
Y198149D03*
X1303407D03*
X1300207Y203699D03*
Y207399D03*
X1303422Y209249D03*
X1313032Y214799D03*
X1306622Y218499D03*
X1303417Y212949D03*
Y216649D03*
X1300207Y214799D03*
X1309832Y209249D03*
X1313027Y203699D03*
X1300220Y218499D03*
X1303416Y205549D03*
X1306614Y203699D03*
X1300207Y211099D03*
X1303422Y220349D03*
X1301151Y225450D03*
X1309828Y224049D03*
X1306622Y222199D03*
X1300220D03*
X1313033D03*
X1303425Y224049D03*
X1309100Y236477D03*
X1300493Y238062D03*
X1313920Y854584D03*
X1312266Y857972D03*
X1313921Y880219D03*
X1312070Y883423D03*
X1310221Y886627D03*
X1313921D03*
X1312070Y877014D03*
X1310221Y880219D03*
X1308370Y877014D03*
X1313921Y880219D03*
X1312070Y883423D03*
X1313921Y893036D03*
X1312070Y889832D03*
Y896240D03*
X1310220Y893036D03*
X1313921D03*
X1312070Y889832D03*
X1310221Y886627D03*
X1313921D03*
X1308371Y902649D03*
X1312070Y915466D03*
X1308370D03*
X1308371Y921875D03*
X1312070Y934692D03*
X1308371Y941100D03*
X1308370Y934692D03*
X1312070Y953917D03*
X1308370D03*
X1310221Y957122D03*
X1308371Y973143D03*
X1310221Y976347D03*
X1307426Y978814D03*
X1311491Y985939D03*
X1314352Y996480D03*
X1314353Y1002888D03*
X1308803Y1006093D03*
X1314353Y1015705D03*
Y1022114D03*
X1308803Y1025318D03*
Y1018910D03*
X1314353Y1041340D03*
X1308803Y1044544D03*
X1310653Y1041340D03*
X1314353Y1060565D03*
X1309976Y1062790D03*
X1305774Y1092168D03*
X1312502Y1082995D03*
X1314353Y1111834D03*
Y1105426D03*
X1311486Y1097289D03*
X1312503Y1121447D03*
X1316203Y1127856D03*
Y1121447D03*
X1314353Y1124651D03*
X1312503Y1115039D03*
Y1127856D03*
X1314353Y1118243D03*
X1312503Y1121447D03*
X1314353Y1131060D03*
X1303112Y1578182D03*
X1310912D03*
X1315172D03*
X1303112Y1590094D03*
X1310912D03*
X1315172D03*
X1304152Y1602380D03*
Y1614292D03*
X1308412Y1602380D03*
Y1614292D03*
X1308071Y1675383D03*
Y1679920D03*
Y1684454D03*
Y1689556D03*
Y1694093D03*
Y1698627D03*
Y1703729D03*
Y1708266D03*
Y1712800D03*
Y1726974D03*
Y1722440D03*
Y1717903D03*
X1319452Y162999D03*
X1316242Y168549D03*
X1319442Y159299D03*
X1316241Y157449D03*
X1320469Y155288D03*
X1322652Y161149D03*
X1316242D03*
X1319452Y166699D03*
X1329062Y168549D03*
X1316242Y164849D03*
X1322652D03*
X1329062Y157449D03*
X1322652D03*
X1319442Y170399D03*
X1318502Y176574D03*
Y186024D03*
Y182874D03*
X1329062Y172249D03*
X1316237D03*
X1331102Y176574D03*
X1327952Y186024D03*
Y182874D03*
X1325853Y174099D03*
X1331102Y179724D03*
Y182874D03*
Y186024D03*
X1325085Y176402D03*
X1324802Y179724D03*
Y186024D03*
Y182874D03*
X1315352Y186024D03*
Y179724D03*
X1319442Y174099D03*
X1318502Y189174D03*
X1315352Y195474D03*
X1327952Y189174D03*
X1331102Y195474D03*
X1327952Y198624D03*
X1321652D03*
X1324802Y195474D03*
X1327952D03*
X1318502D03*
X1321652D03*
X1327952Y201774D03*
X1321652D03*
X1331102Y189174D03*
X1315405Y189227D03*
X1325852Y214799D03*
X1319442Y218499D03*
X1329062Y209249D03*
X1319442Y207399D03*
X1329062Y216649D03*
Y212949D03*
X1325852Y211099D03*
X1319442D03*
X1324802Y204924D03*
X1327952D03*
X1318502D03*
X1315352D03*
X1322652Y209249D03*
Y216649D03*
X1319442Y222199D03*
X1329061Y224049D03*
X1329062Y220349D03*
X1325856Y222199D03*
X1322652Y224049D03*
Y220349D03*
X1326377Y235784D03*
X1321986Y236726D03*
X1332421Y841467D03*
X1330569Y844971D03*
X1326869Y851380D03*
X1325020Y848176D03*
X1328720D03*
X1332420Y854584D03*
X1326869Y844971D03*
X1323170D03*
X1321320Y848176D03*
X1330571Y851380D03*
X1323170D03*
X1319469D03*
X1326869D03*
X1330569Y844971D03*
X1325020Y848176D03*
X1328720D03*
X1326871Y857789D03*
X1328720Y860993D03*
X1330571Y857789D03*
X1332420Y867401D03*
X1330571Y870606D03*
X1326871D03*
X1317620Y854584D03*
X1315770Y857789D03*
X1328721Y854584D03*
X1330571Y864197D03*
X1326871D03*
X1323171D03*
Y857789D03*
X1325020Y854584D03*
X1321321Y860993D03*
X1319469Y857789D03*
X1317621Y867401D03*
X1328721D03*
X1325021D03*
Y860993D03*
X1326871Y857789D03*
X1328720Y860993D03*
X1330571Y857789D03*
X1332420Y880219D03*
X1330571Y883423D03*
X1317621Y880219D03*
X1319471Y883423D03*
X1328720Y873810D03*
X1317621Y886627D03*
X1321321D03*
X1330571Y877014D03*
X1328722Y880219D03*
X1323171Y870606D03*
X1326871Y877014D03*
X1321321Y873810D03*
X1315771Y877014D03*
X1317621Y873810D03*
X1321321Y880219D03*
X1319471Y877014D03*
X1315771Y883423D03*
X1326871D03*
X1323171D03*
X1317621Y880219D03*
X1319471Y883423D03*
X1326871Y870606D03*
X1330571D03*
X1328720Y873810D03*
X1330571Y883423D03*
X1325020Y873810D03*
X1323171Y877014D03*
X1317620Y893036D03*
X1319470Y889832D03*
X1325020Y899445D03*
Y893036D03*
X1326871Y889832D03*
X1330571D03*
X1323171Y896240D03*
X1330571D03*
X1326871D03*
X1332420Y899445D03*
Y893036D03*
X1330571Y902649D03*
X1326871D03*
X1328720Y899445D03*
X1315771Y896240D03*
Y889832D03*
X1328720Y893036D03*
Y886627D03*
X1325021D03*
X1323171Y889832D03*
X1321321Y893036D03*
X1319470Y896240D03*
X1321321Y899445D03*
X1325020D03*
Y893036D03*
X1326871Y889832D03*
X1330571D03*
X1317620Y893036D03*
X1319470Y889832D03*
X1323171Y896240D03*
X1330571D03*
X1317621Y886627D03*
X1326871Y896240D03*
X1321321Y886627D03*
X1332420Y912262D03*
X1330571Y915466D03*
Y909057D03*
X1323171Y915466D03*
X1326871D03*
X1325020Y912262D03*
X1326871Y909057D03*
X1325020Y918670D03*
X1332420D03*
X1328720Y905853D03*
X1325020D03*
X1317621Y912262D03*
X1317620Y905853D03*
X1328720Y912262D03*
X1323171Y909057D03*
Y902649D03*
X1321321Y912262D03*
X1315771Y915466D03*
X1319471D03*
X1325020Y912262D03*
X1326871Y909057D03*
X1330571D03*
X1326871Y902649D03*
X1330571D03*
X1323171Y915466D03*
X1330571D03*
X1326871D03*
X1325021Y931488D03*
X1326871Y928283D03*
X1330571D03*
Y921875D03*
X1326871D03*
X1332420Y931488D03*
X1330571Y934691D03*
X1323171D03*
X1326871D03*
X1328720Y925079D03*
Y918670D03*
X1325020Y925079D03*
X1317620D03*
X1323171Y928283D03*
Y921875D03*
X1321321Y918670D03*
X1317621Y931488D03*
X1328720D03*
X1321321D03*
X1325021D03*
X1326871Y928283D03*
X1330571D03*
Y921875D03*
X1326871D03*
X1325020Y918670D03*
X1332420Y937896D03*
X1330571Y941100D03*
Y947509D03*
X1326871Y941100D03*
X1325020Y937896D03*
X1326871Y947509D03*
X1325020Y950713D03*
X1332420D03*
X1323171Y941100D03*
X1325020Y944304D03*
X1323171Y947509D03*
X1317620Y944304D03*
X1328720D03*
Y937896D03*
X1315771Y934692D03*
X1321321Y937896D03*
X1319470Y934692D03*
X1326871Y941100D03*
X1325020Y937896D03*
X1330571Y941100D03*
X1323171Y934691D03*
X1330571D03*
X1326871D03*
Y947509D03*
X1330571D03*
X1326871Y960326D03*
X1325020Y957122D03*
X1330571Y960326D03*
X1326871Y966735D03*
X1330571D03*
X1326871Y953917D03*
X1330571D03*
X1323172D03*
X1332420Y957122D03*
X1321321D03*
X1323171Y966735D03*
X1325020Y963530D03*
X1323171Y960326D03*
X1321321Y950713D03*
X1315771Y953917D03*
Y966735D03*
X1319470Y953917D03*
X1319471Y966735D03*
X1319470Y960326D03*
X1317621Y950713D03*
X1328720Y957122D03*
Y963530D03*
Y950713D03*
X1325020D03*
X1326871Y960326D03*
X1325020Y957122D03*
X1330571Y960326D03*
X1326871Y966735D03*
X1330571D03*
X1326871Y953917D03*
X1330571D03*
X1323172D03*
X1332420Y976347D03*
Y969939D03*
X1330571Y979552D03*
X1326871D03*
X1325020Y976347D03*
X1323171Y973143D03*
X1325020Y969939D03*
X1321321D03*
X1325020Y982756D03*
X1323171Y979552D03*
X1321321Y976347D03*
X1315771Y973143D03*
X1319471D03*
X1328720Y969939D03*
X1330570Y973143D03*
X1326871D03*
X1328720Y982756D03*
X1328721Y976347D03*
X1315771Y979552D03*
X1326871D03*
X1330571D03*
X1325020Y976347D03*
X1323171Y973143D03*
X1325020Y969939D03*
X1331003Y999684D03*
X1327303D03*
X1332853Y1002888D03*
Y1009297D03*
X1331003Y1012501D03*
X1323603Y1006093D03*
X1325453Y1002888D03*
X1327303Y1012501D03*
X1325453Y1009297D03*
X1318053D03*
Y1002888D03*
X1327304Y1006093D03*
X1331003D03*
X1329153Y1009297D03*
Y1002888D03*
X1323603Y999684D03*
X1321753Y1009297D03*
X1319903Y1006093D03*
X1321753Y1002888D03*
X1323603Y1012501D03*
Y1006093D03*
X1325453Y1002888D03*
X1327303Y999684D03*
X1331003D03*
X1327303Y1012501D03*
X1325453Y1009297D03*
X1331003Y1012501D03*
X1319903Y999684D03*
X1327303Y1018910D03*
X1331003D03*
X1327304Y1031727D03*
X1325453Y1028523D03*
X1331003Y1031727D03*
X1325453Y1022114D03*
X1323603Y1025318D03*
X1331004D03*
X1327304D03*
X1332853Y1028523D03*
Y1022114D03*
X1329153Y1028523D03*
Y1015705D03*
X1318053Y1022114D03*
Y1015705D03*
X1329153Y1022114D03*
X1325453Y1015705D03*
X1323603Y1018910D03*
X1321753Y1028523D03*
X1319903Y1018910D03*
X1321753Y1022114D03*
Y1015705D03*
X1319903Y1031727D03*
X1323603D03*
X1327304D03*
X1325453Y1028523D03*
X1331003Y1031727D03*
X1325453Y1022114D03*
X1327303Y1018910D03*
X1331003D03*
X1323603Y1025318D03*
X1331004D03*
X1327304D03*
X1332853Y1047749D03*
Y1041340D03*
X1331003Y1038136D03*
Y1044544D03*
X1325453Y1047749D03*
Y1041340D03*
X1327303Y1038136D03*
X1323603Y1044544D03*
X1327303D03*
X1329153Y1034931D03*
Y1047749D03*
X1318053Y1041340D03*
X1319903Y1038136D03*
X1329153Y1041340D03*
X1325453Y1034931D03*
X1323603Y1038136D03*
X1321753Y1041340D03*
X1319903Y1044544D03*
X1321753Y1047749D03*
X1325453D03*
Y1041340D03*
X1327303Y1038136D03*
X1331003D03*
X1323603Y1044544D03*
X1331003D03*
X1327303D03*
Y1050952D03*
X1331003D03*
X1325453Y1060565D03*
X1327303Y1057361D03*
X1331003D03*
X1323603Y1063770D03*
X1327303D03*
X1331003D03*
X1332853Y1060565D03*
X1329153D03*
Y1054157D03*
X1325453D03*
X1319903Y1057361D03*
Y1050952D03*
X1323603D03*
Y1057361D03*
X1321753Y1060565D03*
X1319903Y1063770D03*
X1325453Y1060565D03*
X1327303Y1057361D03*
X1331003D03*
X1323603Y1063770D03*
X1327303D03*
X1331003D03*
X1327303Y1050952D03*
X1331003D03*
X1332853Y1066974D03*
Y1079791D03*
X1331003Y1070178D03*
Y1076587D03*
X1325453Y1066974D03*
X1327304Y1070178D03*
X1325453Y1079791D03*
X1327303Y1076587D03*
X1329153Y1073383D03*
X1319903Y1076587D03*
Y1070178D03*
X1316204Y1076587D03*
X1329153Y1066974D03*
X1323603Y1076587D03*
Y1070178D03*
X1325454Y1073383D03*
X1321753Y1066974D03*
X1329153Y1079791D03*
X1321753D03*
X1318053D03*
X1331003Y1070178D03*
X1327304D03*
X1325453Y1066974D03*
Y1079791D03*
X1327303Y1076587D03*
X1331003D03*
Y1082995D03*
X1327303D03*
X1323603D03*
X1327303Y1089404D03*
X1325453Y1086200D03*
X1331003Y1089404D03*
X1332853Y1086200D03*
X1329153D03*
Y1092608D03*
X1325452Y1092609D03*
X1323603Y1089404D03*
X1321752Y1086200D03*
X1319902Y1082995D03*
X1319849Y1091513D03*
X1316202Y1082995D03*
X1316203Y1095813D03*
X1327303Y1089404D03*
X1325453Y1086200D03*
X1331003Y1089404D03*
X1323603Y1082995D03*
X1331003D03*
X1327303D03*
X1331003Y1102221D03*
X1329153Y1105426D03*
X1329154Y1111834D03*
X1318054D03*
X1318053Y1105426D03*
X1327303Y1102221D03*
X1325454Y1111834D03*
X1321753D03*
X1327304Y1108630D03*
X1319904D03*
X1321753Y1105426D03*
X1323603Y1115039D03*
X1331003Y1108630D03*
X1329153Y1099017D03*
X1323603Y1108630D03*
X1316203D03*
Y1102221D03*
X1325453Y1099017D03*
X1323603Y1102221D03*
X1319903D03*
X1325453Y1105426D03*
X1329153D03*
X1325454Y1111834D03*
X1327303Y1102221D03*
X1321753Y1111834D03*
X1318054D03*
X1318053Y1105426D03*
X1327304Y1108630D03*
X1329154Y1111834D03*
X1331003Y1102221D03*
X1319904Y1108630D03*
X1321753Y1105426D03*
X1318054Y1118243D03*
X1331003Y1127856D03*
X1329153Y1124651D03*
X1323603Y1121447D03*
X1319903Y1127856D03*
X1321753Y1124651D03*
X1323603Y1127856D03*
X1319903Y1121447D03*
X1332854Y1124651D03*
X1318053Y1131060D03*
X1316203Y1115039D03*
X1331003D03*
X1327303Y1121447D03*
Y1115039D03*
X1325453Y1124651D03*
X1325454Y1118243D03*
X1321753D03*
X1319903Y1115039D03*
X1318053Y1124651D03*
X1329153D03*
X1331003Y1127856D03*
X1327304D03*
X1329153Y1118243D03*
X1331003Y1121447D03*
X1323603D03*
X1319903Y1127856D03*
X1316203D03*
X1318054Y1118243D03*
X1321753Y1124651D03*
X1323603Y1127856D03*
X1319903Y1121447D03*
X1316203D03*
X1323603Y1115039D03*
X1332854Y1137469D03*
X1327303Y1134264D03*
X1325452Y1137469D03*
X1329152D03*
X1329153Y1131060D03*
X1321752Y1137469D03*
X1321753Y1131060D03*
X1325453D03*
X1319903Y1134264D03*
X1325452Y1137469D03*
X1327303Y1134264D03*
X1331003D03*
X1323603D03*
X1318053Y1131060D03*
X1322972Y1578182D03*
X1327232D03*
X1322972Y1590094D03*
X1327232D03*
X1316212Y1614292D03*
Y1602380D03*
X1328272D03*
Y1614292D03*
X1320472Y1602380D03*
Y1614292D03*
X1323819Y1675383D03*
Y1679920D03*
X1315945Y1679320D03*
X1323819Y1684454D03*
Y1689556D03*
Y1694093D03*
Y1698627D03*
X1315945Y1688391D03*
Y1693493D03*
Y1698030D03*
Y1683857D03*
X1323819Y1703729D03*
Y1708266D03*
Y1712800D03*
X1315945Y1707666D03*
Y1712203D03*
Y1702564D03*
X1323819Y1726974D03*
Y1722440D03*
Y1717903D03*
X1315945Y1730911D03*
Y1726377D03*
Y1721840D03*
Y1716737D03*
X1349351Y170398D03*
X1339727Y161149D03*
X1341992Y156897D03*
X1344103Y155288D03*
X1342936Y159301D03*
X1335472Y161149D03*
X1346137Y168549D03*
X1342907Y166699D03*
X1332268D03*
X1346137Y164849D03*
X1339727D03*
X1335472Y168549D03*
X1332268Y162999D03*
X1339727Y168549D03*
X1335472Y164849D03*
X1346140Y161149D03*
X1342937Y162999D03*
X1335472Y157449D03*
X1346140D03*
X1339727D03*
X1346137Y175949D03*
Y179649D03*
X1342937Y177799D03*
X1349351Y174098D03*
Y177798D03*
Y185198D03*
Y181498D03*
X1339568Y176028D03*
X1339727Y179649D03*
X1342937Y181499D03*
Y185199D03*
X1346137Y172249D03*
X1335472D03*
X1332268Y170399D03*
X1334252Y176574D03*
X1339727Y183349D03*
X1346137Y175949D03*
X1342937Y177799D03*
X1346137Y183349D03*
Y179649D03*
X1339727Y190749D03*
X1342937Y188899D03*
X1334252Y195474D03*
X1346137Y194449D03*
Y190749D03*
X1337901Y196035D03*
X1339727Y187049D03*
X1337345Y201831D03*
X1339727Y201849D03*
X1337402Y198624D03*
X1342937Y192599D03*
X1346137Y187049D03*
X1346147Y201849D03*
Y198149D03*
X1336527Y214799D03*
X1339727Y216649D03*
X1346147Y212949D03*
Y216649D03*
X1336527Y218499D03*
X1342937D03*
Y214799D03*
X1346147Y209248D03*
X1337102Y206675D03*
X1332262Y218499D03*
Y214799D03*
Y211099D03*
X1339686Y205478D03*
X1332262Y207399D03*
X1339727Y209249D03*
Y220349D03*
X1336527Y222199D03*
X1346147Y220349D03*
X1332285Y226210D03*
X1342937Y222199D03*
X1332267D03*
X1349069Y844971D03*
X1345369D03*
X1347221Y841467D03*
X1334269Y844971D03*
X1336120Y848176D03*
X1341669Y844971D03*
X1343520Y848176D03*
X1337969Y844971D03*
X1339821Y841467D03*
X1339820Y854584D03*
X1347220D03*
X1343521Y841467D03*
X1336121D03*
X1345371Y851380D03*
X1341671D03*
X1337971D03*
X1334271D03*
X1347220Y848176D03*
X1339820D03*
X1332420D03*
X1332421Y841467D03*
X1337969Y844971D03*
X1339821Y841467D03*
X1345369Y844971D03*
X1347221Y841467D03*
X1334269Y844971D03*
X1336120Y848176D03*
X1341669Y844971D03*
X1343520Y848176D03*
X1334271Y857789D03*
X1336120Y860993D03*
X1337971Y857789D03*
X1341671D03*
X1345371D03*
X1343520Y860993D03*
X1347220Y867401D03*
X1339820D03*
X1349071Y857789D03*
Y870606D03*
X1345371D03*
X1334271D03*
X1341671D03*
X1337971D03*
X1345371Y864197D03*
X1343521Y854584D03*
X1341671Y864197D03*
X1337971D03*
X1336121Y854584D03*
X1334271Y864197D03*
X1343521Y867401D03*
X1336121D03*
X1347220D03*
X1332420D03*
X1339820D03*
Y860993D03*
X1347220D03*
X1332420D03*
Y854584D03*
X1334271Y857789D03*
X1337971D03*
X1341671D03*
X1345371D03*
X1336120Y860993D03*
X1339820Y854584D03*
X1343520Y860993D03*
X1347220Y854584D03*
X1349071Y883423D03*
X1347220Y880219D03*
X1345371Y883423D03*
X1334271D03*
X1336120Y873810D03*
X1339820Y880219D03*
X1341671Y883423D03*
X1337971D03*
X1343520Y873810D03*
X1336120Y886627D03*
X1343520D03*
X1345371Y877014D03*
X1343521Y880219D03*
X1341671Y877014D03*
X1337971D03*
X1336121Y880219D03*
X1334271Y877014D03*
Y870606D03*
X1337971D03*
X1341671D03*
X1336120Y873810D03*
X1343520D03*
X1345371Y870606D03*
X1332420Y880219D03*
X1334271Y883423D03*
X1339820Y880219D03*
X1341671Y883423D03*
X1347220Y880219D03*
X1337971Y883423D03*
X1345371D03*
X1339820Y873810D03*
X1332420D03*
X1347220D03*
X1334271Y896240D03*
X1339820Y899445D03*
X1343520D03*
X1347220Y893036D03*
X1349071Y896240D03*
X1345371Y902649D03*
X1337971D03*
X1332420Y886627D03*
X1345371Y896240D03*
Y889832D03*
X1341671Y896240D03*
Y889832D03*
X1337970Y896240D03*
X1337971Y889832D03*
X1336121Y893036D03*
X1334270Y889832D03*
X1336121Y899445D03*
X1347220D03*
X1332420D03*
Y893036D03*
X1334271Y896240D03*
X1339820Y899445D03*
X1343520D03*
X1347220Y893036D03*
X1339821D03*
X1336120Y886627D03*
X1343520D03*
X1347220D03*
X1339820D03*
X1349071Y915466D03*
X1345371Y909057D03*
X1347220Y905853D03*
X1334271Y915466D03*
X1336120Y905853D03*
X1343520D03*
X1339820D03*
Y912262D03*
X1337971Y909057D03*
X1343520Y912262D03*
X1339820Y918670D03*
X1343520D03*
X1332420Y905853D03*
X1341671Y909057D03*
Y902649D03*
X1336120Y912262D03*
X1334270Y909057D03*
X1334271Y902649D03*
X1347221Y912262D03*
X1345371Y915466D03*
X1341671D03*
X1337970D03*
X1332420Y912262D03*
X1334271Y915466D03*
X1339820Y912262D03*
X1337971Y909057D03*
X1343520Y912262D03*
X1345371Y909057D03*
X1337971Y902649D03*
X1345371D03*
X1336120Y905853D03*
X1343520D03*
X1339820D03*
X1347220D03*
X1336120Y925079D03*
X1339820Y931488D03*
X1337971Y928283D03*
X1343520Y931488D03*
X1345371Y928283D03*
X1337971Y921875D03*
X1345371D03*
X1343520Y925079D03*
X1339820D03*
X1347220D03*
X1349071Y934691D03*
X1334271D03*
X1332421Y925079D03*
X1341671Y928283D03*
Y921875D03*
X1336121Y918670D03*
X1334270Y928283D03*
X1334271Y921875D03*
X1347220Y918670D03*
X1336120Y931488D03*
X1347221D03*
X1332420D03*
X1339820D03*
X1332420Y918670D03*
X1337971Y928283D03*
X1343520Y931488D03*
X1345371Y928283D03*
X1337971Y921875D03*
X1339820Y918670D03*
X1345371Y921875D03*
X1343520Y918670D03*
X1336120Y925079D03*
X1343520D03*
X1339820D03*
X1347220D03*
Y944304D03*
X1345371Y941100D03*
Y947509D03*
X1336120Y944304D03*
X1343520D03*
X1339820D03*
X1337971Y941100D03*
X1339820Y937896D03*
X1343520D03*
X1337971Y947509D03*
X1339820Y950713D03*
X1343520D03*
X1341671Y947509D03*
Y941100D03*
X1334270Y947509D03*
X1334271Y941100D03*
X1332421Y944304D03*
X1345371Y934691D03*
X1341671D03*
X1337970D03*
X1336121Y937896D03*
X1347220D03*
X1332420D03*
X1334271Y934691D03*
X1337971Y941100D03*
X1339820Y937896D03*
X1345371Y941100D03*
X1343520Y937896D03*
X1337971Y947509D03*
X1345371D03*
X1343520Y944304D03*
X1336120D03*
X1347220D03*
X1339820D03*
X1336120Y963530D03*
X1334271Y953917D03*
X1343520Y957122D03*
X1347220Y963530D03*
X1337971Y966735D03*
X1345371D03*
X1337971Y960326D03*
X1339820Y957122D03*
X1345371Y960326D03*
X1349071Y953917D03*
X1337971D03*
X1345371D03*
X1341671D03*
Y960326D03*
X1347220Y957122D03*
X1343520Y963530D03*
X1339821D03*
X1341670Y966735D03*
X1347221Y950713D03*
X1334271Y960326D03*
X1336121Y957122D03*
X1332421Y963530D03*
X1334270Y966735D03*
X1336120Y950713D03*
X1332420D03*
Y957122D03*
X1334271Y953917D03*
X1337971Y966735D03*
X1345371D03*
X1336120Y963530D03*
X1339820Y950713D03*
X1343520D03*
X1337971Y960326D03*
X1339820Y957122D03*
X1345371Y960326D03*
X1343520Y957122D03*
X1347220Y963530D03*
X1349071Y973143D03*
X1347220Y982756D03*
X1345371Y979552D03*
X1336120Y982756D03*
X1334271Y973143D03*
X1343520Y982756D03*
X1339820D03*
X1343520Y976347D03*
X1337971Y979552D03*
X1339820Y976347D03*
Y969939D03*
X1343520D03*
X1347221D03*
X1337970Y973143D03*
X1347220Y976347D03*
X1345371Y973143D03*
X1341671Y979552D03*
Y973143D03*
X1336120Y969939D03*
X1336121Y976347D03*
X1334271Y979552D03*
X1332421Y982756D03*
X1336120D03*
X1343520D03*
X1339820D03*
X1347220D03*
X1345371Y979552D03*
X1343520Y976347D03*
X1337971Y979552D03*
X1339820Y976347D03*
X1332420D03*
Y969939D03*
X1334271Y973143D03*
X1339820Y969939D03*
X1343520D03*
X1345804Y999684D03*
X1338404D03*
X1349504Y1006093D03*
X1347653Y1002888D03*
X1345804Y1012501D03*
X1334704Y1006093D03*
X1338404Y1012501D03*
X1340253Y1009297D03*
X1343953D03*
X1340253Y1002888D03*
X1336553Y1015705D03*
X1347653D03*
X1345804Y1006093D03*
X1342104Y999684D03*
Y1006093D03*
X1338403D03*
X1336553Y1009297D03*
X1336554Y1002888D03*
X1334704Y999684D03*
X1347654Y1009297D03*
X1342103Y1012501D03*
X1334703D03*
X1343953Y1002888D03*
X1334704Y1006093D03*
X1332853Y1002888D03*
Y1009297D03*
X1338404Y1012501D03*
X1345804D03*
X1340253Y1009297D03*
X1343953D03*
X1340253Y1002888D03*
X1338404Y999684D03*
X1347653Y1002888D03*
X1345804Y999684D03*
X1334704Y1025318D03*
X1338404Y1018910D03*
X1345804D03*
X1340253Y1022114D03*
X1343953D03*
X1338404Y1031727D03*
X1340253Y1028523D03*
X1345804Y1031727D03*
X1343953Y1028523D03*
X1349502Y1025318D03*
X1332854Y1015705D03*
X1345804Y1025318D03*
X1343953Y1015705D03*
X1342104Y1025318D03*
Y1018910D03*
X1340254Y1015705D03*
X1336553Y1028523D03*
X1338403Y1025318D03*
X1336554Y1022114D03*
X1334704Y1018910D03*
X1347653Y1028523D03*
Y1022114D03*
X1342104Y1031727D03*
X1334703D03*
X1332853Y1028523D03*
Y1022114D03*
X1338404Y1031727D03*
X1340253Y1028523D03*
X1345804Y1031727D03*
X1343953Y1028523D03*
X1334704Y1025318D03*
X1336553Y1015705D03*
X1347653D03*
X1340253Y1022114D03*
X1338404Y1018910D03*
X1343953Y1022114D03*
X1345804Y1018910D03*
X1349504Y1044544D03*
X1347653Y1034931D03*
X1345804Y1038136D03*
X1334704Y1044544D03*
X1336553Y1034931D03*
X1340253D03*
X1343953D03*
X1340253Y1047749D03*
X1343953D03*
X1340253Y1041340D03*
X1338404Y1038136D03*
X1343953Y1041340D03*
X1332854Y1034931D03*
X1345804Y1044544D03*
X1342104D03*
Y1038136D03*
X1338403Y1044544D03*
X1336554Y1041340D03*
X1334704Y1038136D03*
X1347653Y1041340D03*
X1336553Y1047749D03*
X1347653D03*
X1332853D03*
Y1041340D03*
X1340253D03*
X1338404Y1038136D03*
X1343953Y1041340D03*
X1345804Y1038136D03*
X1336553Y1034931D03*
X1347653D03*
X1340253D03*
X1334704Y1044544D03*
X1343953Y1034931D03*
X1340253Y1047749D03*
X1343953D03*
X1334704Y1063770D03*
X1338404Y1050952D03*
X1345804D03*
X1343953Y1054157D03*
X1340253Y1060565D03*
X1338404Y1057361D03*
X1343953Y1060565D03*
X1345804Y1057361D03*
X1336553Y1054157D03*
X1347653D03*
X1340253D03*
X1349504Y1063770D03*
X1332854Y1054157D03*
X1342104Y1057361D03*
Y1050952D03*
X1336554Y1060565D03*
X1334704Y1057361D03*
X1334703Y1050952D03*
X1347653Y1060565D03*
X1345804Y1063770D03*
X1342104D03*
X1338403D03*
X1332853Y1060565D03*
X1334704Y1063770D03*
X1340253Y1060565D03*
X1338404Y1057361D03*
X1343953Y1060565D03*
X1345804Y1057361D03*
X1338404Y1050952D03*
X1345804D03*
X1336553Y1054157D03*
X1347653D03*
X1340253D03*
X1343953D03*
X1345804Y1076587D03*
Y1070178D03*
X1347653Y1073383D03*
X1340253Y1066974D03*
X1343953D03*
Y1073383D03*
Y1079791D03*
X1338404Y1070178D03*
X1340253Y1079791D03*
X1338404Y1076587D03*
X1336553Y1073383D03*
X1340253D03*
X1332854D03*
X1342104Y1070178D03*
Y1076587D03*
X1336553Y1066974D03*
X1334703Y1070178D03*
X1334704Y1076587D03*
X1347654Y1066974D03*
X1336554Y1079791D03*
X1347653D03*
X1332853Y1066974D03*
X1343953Y1079791D03*
X1345804Y1076587D03*
X1338404Y1070178D03*
X1340253Y1066974D03*
X1345804Y1070178D03*
X1343953Y1066974D03*
X1332853Y1079791D03*
X1340253D03*
X1338404Y1076587D03*
X1336553Y1073383D03*
X1347653D03*
X1340253D03*
X1343953D03*
X1334704Y1082995D03*
X1338404Y1095813D03*
X1345804D03*
X1338404Y1089404D03*
X1340253Y1086200D03*
X1345804Y1089404D03*
X1343953Y1086200D03*
X1336553Y1092608D03*
X1343953D03*
X1340253D03*
X1347653D03*
X1349504Y1082995D03*
X1340253Y1099017D03*
X1343953D03*
X1345804Y1082995D03*
X1342104Y1089404D03*
Y1082995D03*
X1338403D03*
X1336553Y1086200D03*
X1334703Y1089404D03*
X1332854Y1092608D03*
X1347654Y1086200D03*
X1342104Y1095813D03*
X1334703D03*
X1332853Y1086200D03*
X1334704Y1082995D03*
X1338404Y1095813D03*
X1345804D03*
X1338404Y1089404D03*
X1340253Y1086200D03*
X1345804Y1089404D03*
X1343953Y1086200D03*
X1336553Y1092608D03*
X1343953D03*
X1340253D03*
X1347653D03*
X1345803Y1108630D03*
X1334703D03*
X1340254Y1105426D03*
X1336554Y1111834D03*
X1343954D03*
X1342103Y1108630D03*
X1338403D03*
X1334703Y1115039D03*
X1342103D03*
X1345803D03*
X1342104Y1102221D03*
X1338404D03*
X1336553Y1099017D03*
X1332853Y1105426D03*
Y1099017D03*
X1347654Y1105426D03*
Y1099017D03*
X1340254Y1111834D03*
X1332854D03*
X1347654D03*
X1340253Y1099017D03*
X1343953D03*
X1334704Y1102221D03*
X1345803D03*
X1343953Y1105426D03*
X1336554D03*
X1345803Y1108630D03*
X1340254Y1105426D03*
X1336554Y1111834D03*
X1334703Y1108630D03*
X1343954Y1111834D03*
X1342103Y1108630D03*
X1338403D03*
X1334703Y1121447D03*
X1345804Y1127856D03*
X1342104Y1121447D03*
X1338404Y1127856D03*
X1347653Y1124651D03*
X1343953D03*
X1340253D03*
X1336554D03*
X1349504Y1121447D03*
X1343953Y1118243D03*
X1340253D03*
X1338403Y1115039D03*
X1336553Y1118243D03*
X1332853D03*
X1347653D03*
X1342104Y1127856D03*
X1334703D03*
Y1121447D03*
X1336554Y1124651D03*
X1340253D03*
X1343953D03*
X1347653D03*
X1332854D03*
X1338404Y1127856D03*
X1342104Y1121447D03*
X1345804Y1127856D03*
Y1121447D03*
X1338403D03*
X1342103Y1115039D03*
X1345803D03*
X1334703D03*
X1349504Y1134264D03*
X1347654Y1137469D03*
X1345803Y1140973D03*
X1334703Y1134264D03*
X1342104D03*
X1343954Y1137469D03*
X1340254D03*
X1336554D03*
X1338403Y1140973D03*
X1343953Y1131060D03*
X1342103Y1140973D03*
X1340254Y1131060D03*
X1336554D03*
X1334703Y1140973D03*
X1332854Y1131060D03*
X1347653D03*
X1334703Y1134264D03*
X1338403Y1140973D03*
X1342104Y1134264D03*
X1345803Y1140973D03*
X1332854Y1137469D03*
X1336554D03*
X1340254D03*
X1343954D03*
X1347654D03*
X1338404Y1134264D03*
X1345804D03*
X1335032Y1578182D03*
X1347092D03*
X1339292D03*
X1335032Y1590094D03*
X1347092D03*
X1339292D03*
X1340332Y1602380D03*
Y1614292D03*
X1332532Y1602380D03*
Y1614292D03*
X1344592Y1602380D03*
Y1614292D03*
X1339567Y1675383D03*
Y1679920D03*
X1331693Y1679320D03*
X1347441D03*
X1339567Y1684454D03*
Y1689556D03*
Y1694093D03*
Y1698627D03*
X1331693Y1688391D03*
Y1693493D03*
Y1698030D03*
Y1683857D03*
X1347441Y1688391D03*
Y1693493D03*
Y1698030D03*
Y1683857D03*
X1339567Y1703729D03*
Y1708266D03*
Y1712800D03*
X1331693Y1707666D03*
Y1712203D03*
Y1702564D03*
X1347441Y1707666D03*
Y1712203D03*
Y1702564D03*
X1339567Y1726974D03*
Y1722440D03*
Y1717903D03*
X1331693Y1730911D03*
Y1726377D03*
Y1721840D03*
Y1716737D03*
X1347441Y1730911D03*
Y1726377D03*
Y1721840D03*
Y1716737D03*
X1352557Y168548D03*
X1355762Y166698D03*
X1352550Y157449D03*
X1349351Y159298D03*
X1355758D03*
X1355761Y162998D03*
X1358865Y166732D03*
Y158854D03*
Y162793D03*
X1349351Y166698D03*
X1352557Y164848D03*
X1355961Y155458D03*
X1352557Y168548D03*
X1355762Y166698D03*
X1349344Y162999D03*
X1348386Y156646D03*
X1352551Y161148D03*
X1352557Y172248D03*
X1355761Y174098D03*
Y185198D03*
Y181498D03*
X1352557Y183348D03*
Y175948D03*
X1358865Y170671D03*
Y174603D03*
Y182484D03*
Y178544D03*
X1355761Y170398D03*
Y177798D03*
X1352557Y179648D03*
Y172248D03*
X1349351Y177798D03*
Y170398D03*
Y174098D03*
X1352557Y175948D03*
X1349351Y181498D03*
X1355761Y185198D03*
X1349351D03*
X1355761Y174098D03*
Y181498D03*
X1352557Y183348D03*
X1352561Y198148D03*
X1355771Y196298D03*
X1355765Y199999D03*
Y203699D03*
X1358371Y188778D03*
X1358865Y195240D03*
Y199180D03*
X1349351Y196298D03*
X1352561Y194448D03*
X1352551Y190748D03*
X1349345Y188898D03*
X1355761Y192598D03*
X1349351D03*
X1352551Y187048D03*
X1355761Y188898D03*
X1352561Y198148D03*
X1355771Y196298D03*
X1355765Y199999D03*
X1349361Y199998D03*
X1352561Y201848D03*
X1355766Y214798D03*
X1349351Y218498D03*
X1352561Y216648D03*
X1355766Y218498D03*
X1358865Y207060D03*
Y203120D03*
Y213994D03*
Y217934D03*
X1352560Y205549D03*
X1355765Y207399D03*
X1349351Y214798D03*
X1352561Y212948D03*
X1349351Y211098D03*
X1355765Y203699D03*
X1352561Y220348D03*
X1355766Y222198D03*
X1349351D03*
X1365720Y848176D03*
X1363869Y844971D03*
X1362021Y841467D03*
X1352769Y844971D03*
X1350920Y848176D03*
X1356469Y844971D03*
X1360169D03*
X1354621Y841467D03*
X1358320Y848176D03*
X1354620Y854584D03*
X1362020D03*
X1358321Y841467D03*
X1350921D03*
X1360171Y851380D03*
X1356471D03*
X1352771D03*
X1349071D03*
X1363871D03*
X1362020Y848176D03*
X1354620D03*
X1363869Y844971D03*
X1352769D03*
X1356469D03*
X1360169D03*
X1362021Y841467D03*
X1349069Y844971D03*
X1350920Y848176D03*
X1354621Y841467D03*
X1358320Y848176D03*
X1350920Y860993D03*
X1352771Y857789D03*
X1356471D03*
X1360171D03*
X1363871D03*
X1358320Y860993D03*
X1362020Y867401D03*
X1354620D03*
X1365720Y860993D03*
X1363871Y870606D03*
X1352771D03*
X1360171D03*
X1356471D03*
X1360171Y864197D03*
X1358321Y854584D03*
X1356471Y864197D03*
X1352771D03*
X1350921Y854584D03*
X1349071Y864197D03*
X1363871D03*
X1358321Y867401D03*
X1350921D03*
X1354620D03*
X1362020D03*
Y860993D03*
X1354620D03*
X1349071Y857789D03*
X1354620Y854584D03*
X1356471Y857789D03*
X1360171D03*
X1363871D03*
X1350920Y860993D03*
X1352771Y857789D03*
X1358320Y860993D03*
X1362020Y854584D03*
X1365720Y873810D03*
X1362020Y880219D03*
X1363871Y883423D03*
X1352771D03*
X1350920Y873810D03*
X1354620Y880219D03*
X1360171Y883423D03*
X1356471D03*
X1358320Y873810D03*
X1350920Y886627D03*
X1358320D03*
X1365720D03*
X1360171Y877014D03*
X1358321Y880219D03*
X1356471Y877014D03*
X1352771D03*
X1350921Y880219D03*
X1349071Y877014D03*
X1363871D03*
Y870606D03*
X1349071D03*
X1356471D03*
X1350920Y873810D03*
X1352771Y870606D03*
X1358320Y873810D03*
X1360171Y870606D03*
X1349071Y883423D03*
X1354620Y880219D03*
X1356471Y883423D03*
X1362020Y880219D03*
X1363871Y883423D03*
X1352771D03*
X1360171D03*
X1354620Y873810D03*
X1362020D03*
X1350920Y899445D03*
Y893036D03*
X1352771Y896240D03*
X1358320Y899445D03*
Y893036D03*
X1362020D03*
X1356471Y896240D03*
X1360171D03*
X1365720Y899445D03*
X1363871Y902649D03*
X1352771D03*
X1356471D03*
X1360171Y889832D03*
X1356471D03*
X1354621Y893036D03*
X1352771Y889832D03*
X1349071D03*
X1363871Y896240D03*
Y889832D03*
X1362021Y899445D03*
X1354620D03*
X1350920D03*
X1358320D03*
Y893036D03*
X1350920D03*
X1362020D03*
X1349071Y896240D03*
X1356471D03*
X1352771D03*
X1360171D03*
X1350920Y886627D03*
X1358320D03*
X1354620D03*
X1362020D03*
X1365720Y912262D03*
Y905853D03*
X1363871Y909057D03*
X1362020Y905853D03*
X1350920Y912262D03*
X1352771Y909057D03*
Y915466D03*
X1356471D03*
X1360171D03*
X1358320Y912262D03*
X1356471Y909057D03*
X1350920Y918670D03*
X1358320D03*
X1365720D03*
X1362020Y912262D03*
X1360170Y909057D03*
X1360171Y902649D03*
X1358321Y905853D03*
X1354620Y912262D03*
Y905853D03*
X1350920D03*
X1349071Y909057D03*
X1349070Y902649D03*
X1363870Y915466D03*
X1352771Y902649D03*
X1356471D03*
X1350920Y912262D03*
X1352771Y909057D03*
X1358320Y912262D03*
X1356471Y909057D03*
X1363871D03*
Y902649D03*
X1349071Y915466D03*
X1362020Y905853D03*
X1356471Y915466D03*
X1352771D03*
X1360171D03*
X1350920Y931488D03*
X1352771Y928283D03*
Y921875D03*
X1356471Y928283D03*
Y921875D03*
X1358320Y931488D03*
X1363871Y921875D03*
Y928283D03*
X1362020Y925079D03*
X1365720Y931488D03*
Y925079D03*
X1352771Y934691D03*
X1356471D03*
X1360171D03*
X1362021Y918670D03*
X1360170Y928283D03*
X1360171Y921875D03*
X1358321Y925079D03*
X1354620D03*
Y918670D03*
X1350920Y925079D03*
X1349071Y928283D03*
X1349070Y921875D03*
X1362020Y931488D03*
X1354620D03*
X1350920D03*
X1352771Y928283D03*
X1358320Y931488D03*
X1356471Y928283D03*
X1363871Y921875D03*
X1352771D03*
X1350920Y918670D03*
X1356471Y921875D03*
X1358320Y918670D03*
X1363871Y928283D03*
X1362020Y925079D03*
X1365720Y937896D03*
Y944304D03*
X1363871Y947509D03*
Y941100D03*
X1362020Y944304D03*
X1352771Y947509D03*
Y941100D03*
X1350920Y937896D03*
X1356471Y941100D03*
X1358320Y937896D03*
X1356471Y947509D03*
X1350920Y950713D03*
X1358320D03*
X1365720D03*
X1360171Y941100D03*
X1358321Y944304D03*
X1354620D03*
X1360170Y947509D03*
X1350920Y944304D03*
X1349071Y947509D03*
X1349070Y941100D03*
X1362021Y937896D03*
X1354620D03*
X1363870Y934691D03*
X1356471Y941100D03*
X1358320Y937896D03*
X1352771Y947509D03*
X1356471D03*
X1352771Y941100D03*
X1350920Y937896D03*
X1349071Y934691D03*
X1356471D03*
X1352771D03*
X1360171D03*
X1363871Y947509D03*
Y941100D03*
X1362020Y944304D03*
X1352771Y960326D03*
X1350920Y957122D03*
X1352771Y953917D03*
Y966735D03*
X1356471Y960326D03*
X1358320Y957122D03*
X1356471Y953917D03*
X1360171D03*
X1356471Y966735D03*
X1363871Y960326D03*
Y966735D03*
X1362020Y963530D03*
X1365720Y957122D03*
Y963530D03*
X1363871Y953917D03*
X1360171Y960326D03*
X1362021Y957122D03*
X1354620D03*
X1358321Y963530D03*
X1354620D03*
X1360170Y966735D03*
X1354620Y950713D03*
X1362020D03*
X1349070Y960326D03*
X1350920Y963530D03*
X1349071Y966735D03*
X1352771Y960326D03*
X1350920Y957122D03*
X1356471Y960326D03*
X1358320Y957122D03*
X1350920Y950713D03*
X1358320D03*
X1349071Y953917D03*
X1356471D03*
X1352771D03*
X1360171D03*
X1363871Y960326D03*
Y966735D03*
X1356471D03*
X1352771D03*
X1362020Y963530D03*
X1365720Y982756D03*
X1365721Y976347D03*
X1365720Y969939D03*
X1362020Y982756D03*
X1363871Y979552D03*
X1350920Y969939D03*
X1352771Y979552D03*
X1350920Y976347D03*
X1358320Y969939D03*
X1356471Y979552D03*
X1358320Y976347D03*
X1360171Y973143D03*
X1362020Y969939D03*
X1354620D03*
X1363870Y973143D03*
X1362021Y976347D03*
X1360171Y979552D03*
X1358321Y982756D03*
X1356470Y973143D03*
X1354620Y982756D03*
X1354621Y976347D03*
X1350920Y982756D03*
X1349070Y979552D03*
X1352771Y973143D03*
X1362020Y982756D03*
X1363871Y979552D03*
X1352771D03*
X1356471D03*
X1350920Y976347D03*
X1358320D03*
X1349071Y973143D03*
X1350920Y969939D03*
X1358320D03*
X1360171Y973143D03*
X1364304Y999684D03*
X1353204D03*
X1356904D03*
X1351352Y996480D03*
X1366153Y1002888D03*
X1364304Y1012501D03*
X1366153Y1009297D03*
X1351353D03*
Y1002888D03*
X1353204Y1012501D03*
X1356904D03*
X1358753Y1009297D03*
X1356904Y1006093D03*
X1353204D03*
X1360604D03*
X1358753Y1002888D03*
X1362453Y1015705D03*
X1349503Y999684D03*
X1362453Y1009297D03*
X1362454Y1002888D03*
X1360604Y999684D03*
X1355053Y1009297D03*
Y1002888D03*
X1360603Y1012501D03*
X1349504D03*
Y1006093D03*
X1356904D03*
X1353204D03*
X1360604D03*
X1351353Y1002888D03*
X1353204Y999684D03*
X1358753Y1002888D03*
X1356904Y999684D03*
X1353204Y1012501D03*
X1351353Y1009297D03*
X1356904Y1012501D03*
X1358753Y1009297D03*
X1351353Y1028523D03*
Y1022114D03*
X1353204Y1018910D03*
X1356904D03*
X1353204Y1031727D03*
X1356904D03*
X1358753Y1028523D03*
Y1022114D03*
X1353204Y1025318D03*
X1360604D03*
X1356902D03*
X1364304Y1018910D03*
Y1031727D03*
X1366153Y1028523D03*
Y1022114D03*
X1362453Y1028523D03*
X1362454Y1022114D03*
X1360604Y1018910D03*
X1358754Y1015705D03*
X1355053Y1028523D03*
Y1022114D03*
Y1015705D03*
X1351353D03*
X1349503Y1018910D03*
X1360603Y1031727D03*
X1349504D03*
X1353204D03*
X1351353Y1028523D03*
X1356904Y1031727D03*
X1358753Y1028523D03*
X1351353Y1022114D03*
X1353204Y1018910D03*
X1358753Y1022114D03*
X1356904Y1018910D03*
X1353204Y1025318D03*
X1360604D03*
X1349502D03*
X1356902D03*
X1362453Y1015705D03*
X1366153Y1034931D03*
Y1041340D03*
X1364304Y1038136D03*
X1366153Y1047749D03*
X1362453Y1034931D03*
X1351353Y1047749D03*
Y1041340D03*
X1358753D03*
X1356904Y1038136D03*
Y1044544D03*
X1353204D03*
X1360604D03*
X1358753Y1047749D03*
X1353204Y1038136D03*
X1362454Y1041340D03*
X1360604Y1038136D03*
X1358754Y1034931D03*
X1355053Y1041340D03*
Y1034931D03*
X1351353D03*
X1349503Y1038136D03*
X1362453Y1047749D03*
X1355053D03*
X1351353D03*
X1358753D03*
X1351353Y1041340D03*
X1353204Y1038136D03*
X1358753Y1041340D03*
X1356904Y1038136D03*
X1349504Y1044544D03*
X1356904D03*
X1353204D03*
X1360604D03*
X1362453Y1034931D03*
X1351353Y1060565D03*
X1353204Y1050952D03*
X1356904D03*
X1353204Y1057361D03*
X1358753Y1060565D03*
X1356904Y1057361D03*
X1360604Y1063770D03*
X1353204D03*
X1356904D03*
X1362453Y1054157D03*
X1364304Y1050952D03*
X1366153Y1060565D03*
X1364304Y1057361D03*
X1366153Y1054157D03*
X1362454Y1060565D03*
X1360604Y1057361D03*
X1360603Y1050952D03*
X1358754Y1054157D03*
X1355053Y1060565D03*
Y1054157D03*
X1351353D03*
X1349503Y1057361D03*
X1349504Y1050952D03*
X1351353Y1060565D03*
X1353204Y1057361D03*
X1358753Y1060565D03*
X1356904Y1057361D03*
X1353204Y1050952D03*
X1356904D03*
X1349504Y1063770D03*
X1360604D03*
X1353204D03*
X1356904D03*
X1362453Y1054157D03*
X1366153Y1066974D03*
Y1079791D03*
X1364304Y1076587D03*
Y1070178D03*
X1366153Y1073383D03*
X1362453D03*
X1351353Y1066974D03*
Y1079791D03*
X1358753Y1066974D03*
X1356904Y1070178D03*
X1353204D03*
Y1076587D03*
X1358753Y1079791D03*
X1356904Y1076587D03*
X1362453Y1066974D03*
X1360604Y1076587D03*
X1360603Y1070178D03*
X1358754Y1073383D03*
X1355053D03*
Y1066974D03*
X1351353Y1073383D03*
X1349503Y1076587D03*
X1349504Y1070178D03*
X1362453Y1079791D03*
X1355053D03*
X1356904Y1070178D03*
X1358753Y1066974D03*
X1353204Y1070178D03*
X1351353Y1066974D03*
Y1079791D03*
X1353204Y1076587D03*
X1358753Y1079791D03*
X1356904Y1076587D03*
X1362453Y1073383D03*
X1351353Y1086200D03*
X1360604Y1082995D03*
X1353204D03*
X1356904D03*
Y1089404D03*
X1358753Y1086200D03*
X1353204Y1089404D03*
X1362453Y1092608D03*
X1364304Y1089404D03*
X1366153Y1086200D03*
X1364304Y1095813D03*
X1366153Y1092608D03*
Y1099017D03*
X1362453Y1086200D03*
X1360603Y1089404D03*
X1358753Y1092608D03*
X1355053D03*
Y1086200D03*
X1351353Y1092608D03*
X1349504Y1089404D03*
X1360604Y1095813D03*
X1349504D03*
X1353204Y1089404D03*
X1351353Y1086200D03*
X1356904Y1089404D03*
X1358753Y1086200D03*
X1349504Y1082995D03*
X1362453Y1092608D03*
X1360604Y1082995D03*
X1353204D03*
X1356904D03*
Y1095813D03*
X1362453Y1111834D03*
Y1105426D03*
X1351353Y1111834D03*
Y1105426D03*
X1356904Y1102221D03*
X1358753Y1105426D03*
Y1111834D03*
X1360604Y1108630D03*
X1355053Y1111834D03*
X1353204Y1108630D03*
X1355054Y1105426D03*
X1356904Y1115039D03*
X1362454Y1099017D03*
X1360604Y1102221D03*
X1356904Y1108630D03*
X1355053Y1099017D03*
X1353204Y1102221D03*
X1349503Y1108630D03*
Y1102221D03*
X1358753Y1099017D03*
X1362453Y1111834D03*
Y1105426D03*
X1358753D03*
X1351353Y1111834D03*
Y1105426D03*
X1358753Y1111834D03*
X1360604Y1108630D03*
X1355053Y1111834D03*
X1356904Y1102221D03*
X1353204Y1108630D03*
X1355054Y1105426D03*
X1351353Y1124651D03*
X1360604Y1127856D03*
X1356904Y1121447D03*
X1353204Y1127856D03*
X1362453Y1124651D03*
X1358753D03*
X1355053D03*
X1364304Y1121447D03*
X1366153Y1124651D03*
X1362453Y1118243D03*
X1360603Y1115039D03*
X1358753Y1118243D03*
X1355053D03*
X1353203Y1115039D03*
X1351353Y1118243D03*
X1349503Y1115039D03*
X1356903Y1127856D03*
X1349503D03*
X1351353Y1124651D03*
X1355053D03*
X1358753D03*
X1362453D03*
X1349504Y1121447D03*
X1353204Y1127856D03*
X1356904Y1121447D03*
X1360604Y1127856D03*
Y1121447D03*
X1353204D03*
X1356904Y1115039D03*
X1364304Y1134264D03*
X1366154Y1137469D03*
X1362454D03*
X1351354D03*
X1356904Y1134264D03*
X1358754Y1137469D03*
X1355054D03*
X1360603Y1140973D03*
X1353203D03*
X1362453Y1131060D03*
X1358753D03*
X1356903Y1140973D03*
X1355053Y1131060D03*
X1351353D03*
X1349503Y1140973D03*
X1349504Y1134264D03*
X1353203Y1140973D03*
X1356904Y1134264D03*
X1360603Y1140973D03*
X1351354Y1137469D03*
X1355054D03*
X1358754D03*
X1362454D03*
X1353204Y1134264D03*
X1360604D03*
X1351352Y1578182D03*
X1359152D03*
X1363412D03*
X1351352Y1590094D03*
X1359152D03*
X1363412D03*
X1352392Y1602380D03*
Y1614292D03*
X1356652Y1602380D03*
Y1614292D03*
X1363189Y1679320D03*
X1355315Y1675383D03*
Y1679920D03*
X1363189Y1688391D03*
Y1693493D03*
Y1698030D03*
Y1683857D03*
X1355315Y1684454D03*
Y1689556D03*
Y1694093D03*
Y1698627D03*
X1363189Y1707666D03*
Y1712203D03*
Y1702564D03*
X1355315Y1703729D03*
Y1708266D03*
Y1712800D03*
X1363189Y1730911D03*
Y1726377D03*
Y1721840D03*
Y1716737D03*
X1355315Y1726974D03*
Y1722440D03*
Y1717903D03*
X1380520Y848176D03*
X1382369Y844971D03*
X1378669D03*
X1367569D03*
X1369421Y841467D03*
X1373120Y848176D03*
X1376821Y841467D03*
X1371269Y844971D03*
X1374969D03*
X1369420Y854584D03*
X1376820D03*
X1373121Y841467D03*
X1365721D03*
X1378671Y851380D03*
X1374971D03*
X1371271D03*
X1367571D03*
X1376820Y848176D03*
X1369420D03*
X1367569Y844971D03*
X1369421Y841467D03*
X1373120Y848176D03*
X1376821Y841467D03*
X1365720Y848176D03*
X1371269Y844971D03*
X1374969D03*
X1378669D03*
X1367571Y857789D03*
X1369420Y867401D03*
X1373120Y860993D03*
X1374971Y857789D03*
X1371271D03*
X1378671D03*
X1376820Y867401D03*
X1380520Y860993D03*
X1382371Y857789D03*
Y870606D03*
X1378671D03*
X1367571D03*
X1374971D03*
X1371271D03*
X1378671Y864197D03*
X1374971D03*
X1373121Y854584D03*
X1371271Y864197D03*
X1367571D03*
X1365721Y854584D03*
X1373121Y867401D03*
X1365721D03*
X1376820D03*
X1369420D03*
X1376820Y860993D03*
X1369420D03*
X1365720D03*
X1367571Y857789D03*
X1373120Y860993D03*
X1374971Y857789D03*
X1369420Y854584D03*
X1371271Y857789D03*
X1376820Y854584D03*
X1378671Y857789D03*
X1382371Y883423D03*
X1380520Y873810D03*
X1378671Y883423D03*
X1369420Y880219D03*
X1367571Y883423D03*
X1376820Y880219D03*
X1374971Y883423D03*
X1371271D03*
X1373120Y873810D03*
Y886627D03*
X1380520D03*
X1378671Y877014D03*
X1374971D03*
X1373121Y880219D03*
X1371271Y877014D03*
X1367571D03*
X1365721Y880219D03*
X1367571Y870606D03*
X1371271D03*
X1378671D03*
X1365720Y873810D03*
X1373120D03*
X1374971Y870606D03*
X1369420Y880219D03*
X1371271Y883423D03*
X1376820Y880219D03*
X1378671Y883423D03*
X1367571D03*
X1374971D03*
X1369420Y873810D03*
X1376820D03*
X1369420Y899445D03*
X1371271Y902649D03*
X1378671Y889832D03*
X1374971D03*
X1371271Y896240D03*
Y889832D03*
X1367570Y896240D03*
X1367571Y889832D03*
X1365721Y893036D03*
X1373120Y899445D03*
X1378671Y896240D03*
X1376820Y899445D03*
X1365720D03*
X1369420D03*
X1369421Y893036D03*
X1373120Y886627D03*
X1365720D03*
X1374971Y896240D03*
X1376820Y893036D03*
X1369420Y886627D03*
X1376820D03*
X1369420Y912262D03*
Y905853D03*
X1371271Y909057D03*
X1373120Y905853D03*
X1369420Y918670D03*
X1374971Y909057D03*
X1374970Y902649D03*
X1373121Y912262D03*
X1367571Y909057D03*
Y902649D03*
X1371271Y915466D03*
X1367571D03*
X1376820Y905853D03*
X1378671Y915466D03*
Y909057D03*
X1365720Y912262D03*
X1369420D03*
X1371271Y909057D03*
Y902649D03*
X1369420Y905853D03*
X1365720D03*
X1373120D03*
X1376820Y912262D03*
X1378671Y902649D03*
X1369420Y931488D03*
Y925079D03*
X1371271Y928283D03*
Y921875D03*
X1373120Y925079D03*
X1376820Y931488D03*
X1378671Y928283D03*
X1376820Y925079D03*
X1374971Y928283D03*
X1374970Y921875D03*
X1373120Y918670D03*
X1367571Y928283D03*
Y921875D03*
X1373120Y931488D03*
X1369420D03*
X1371271Y928283D03*
X1365720Y918670D03*
X1371271Y921875D03*
X1369420Y918670D03*
X1365720Y931488D03*
X1369420Y925079D03*
X1365720D03*
X1373120D03*
X1369420Y937896D03*
Y944304D03*
X1371271Y947509D03*
Y941100D03*
X1373120Y944304D03*
X1369420Y950713D03*
X1374971Y934691D03*
X1378671D03*
X1376820Y937896D03*
X1374970Y941100D03*
X1373120Y937896D03*
X1371271Y934691D03*
X1367571Y941100D03*
Y934691D03*
X1374971Y947509D03*
X1367571D03*
X1371271D03*
X1365720Y937896D03*
X1371271Y941100D03*
X1369420Y937896D03*
Y944304D03*
X1365720D03*
X1373120D03*
X1378671Y947509D03*
X1369420Y957122D03*
Y963530D03*
X1371271Y960326D03*
Y966735D03*
X1373120Y963530D03*
X1376820Y957122D03*
X1374970Y960326D03*
X1373120Y957122D03*
X1373121Y950713D03*
X1371271Y953917D03*
X1367571Y960326D03*
Y953917D03*
X1376820Y963530D03*
X1374971Y966735D03*
X1367571D03*
X1365720Y957122D03*
X1371271Y960326D03*
X1369420Y957122D03*
X1371271Y966735D03*
X1365720Y950713D03*
X1369420D03*
X1373120Y963530D03*
X1369420D03*
X1365720D03*
X1378671Y953917D03*
X1374971D03*
X1376822Y950713D03*
X1378671Y979552D03*
Y973143D03*
X1369420Y982756D03*
Y976347D03*
Y969939D03*
X1374971Y973143D03*
X1376820Y976347D03*
X1373120Y982756D03*
X1371271Y979552D03*
X1376820Y982756D03*
Y969939D03*
X1374970Y979552D03*
X1373120Y976347D03*
X1373121Y969939D03*
X1371271Y973143D03*
X1367571Y979552D03*
Y973143D03*
X1374971D03*
X1376820Y976347D03*
X1378671Y979552D03*
Y973143D03*
X1369420Y982756D03*
X1365720D03*
X1373120D03*
X1369420Y976347D03*
X1371271Y979552D03*
X1365721Y976347D03*
X1365720Y969939D03*
X1369420D03*
X1371704Y999684D03*
X1369853Y1002888D03*
X1371704Y1012501D03*
X1369853Y1009297D03*
X1373553Y1015705D03*
X1364303Y1006093D03*
X1377253Y1002888D03*
X1373554Y1009297D03*
X1373553Y1002888D03*
X1371704Y1006093D03*
X1368004D03*
Y999684D03*
X1375404Y1012501D03*
X1368003D03*
X1375404Y1006093D03*
X1379104D03*
X1366153Y1002888D03*
X1364304Y999684D03*
X1369853Y1002888D03*
X1371704Y999684D03*
X1375404D03*
X1379104D03*
X1364304Y1012501D03*
X1371704D03*
X1366153Y1009297D03*
X1369853D03*
X1377253D03*
X1379104Y1012501D03*
X1371704Y1018910D03*
Y1031727D03*
X1369853Y1028523D03*
Y1022114D03*
X1379104Y1031727D03*
X1364303Y1025318D03*
X1375403Y1018910D03*
X1373553Y1028523D03*
Y1022114D03*
X1371704Y1025318D03*
X1369853Y1015705D03*
X1368004Y1025318D03*
Y1018910D03*
X1366154Y1015705D03*
X1375404Y1031727D03*
X1368004D03*
X1373553Y1015705D03*
X1364304Y1031727D03*
X1366153Y1028523D03*
X1371704Y1031727D03*
X1369853Y1028523D03*
X1366153Y1022114D03*
X1364304Y1018910D03*
X1369853Y1022114D03*
X1371704Y1018910D03*
X1375404Y1025318D03*
X1377253Y1022114D03*
X1379102Y1018910D03*
X1379104Y1025318D03*
X1377253Y1015705D03*
X1369853Y1034931D03*
X1373553D03*
X1369853Y1041340D03*
X1371704Y1038136D03*
X1369853Y1047749D03*
X1364303Y1044544D03*
X1375403Y1038136D03*
X1373553Y1041340D03*
X1371704Y1044544D03*
X1368004D03*
Y1038136D03*
X1373553Y1047749D03*
X1366153Y1041340D03*
X1364304Y1038136D03*
X1369853Y1041340D03*
X1371704Y1038136D03*
X1366153Y1047749D03*
X1369853D03*
Y1034931D03*
X1366153D03*
X1373553D03*
X1375404Y1044544D03*
X1377253Y1041340D03*
X1379104Y1044544D03*
Y1038136D03*
X1373553Y1054157D03*
X1371704Y1050952D03*
X1369853Y1060565D03*
X1371704Y1057361D03*
X1369853Y1054157D03*
X1375403Y1057361D03*
X1375404Y1050952D03*
X1373553Y1060565D03*
X1368004Y1057361D03*
Y1050952D03*
X1364303Y1063770D03*
X1371704D03*
X1368004D03*
X1366153Y1060565D03*
X1364304Y1057361D03*
X1369853Y1060565D03*
X1371704Y1057361D03*
X1364304Y1050952D03*
X1371704D03*
X1369853Y1054157D03*
X1366153D03*
X1373553D03*
X1379104Y1057361D03*
Y1063770D03*
X1375404D03*
X1377253Y1054157D03*
X1379104Y1050952D03*
X1369853Y1066974D03*
Y1079791D03*
X1371704Y1076587D03*
Y1070178D03*
X1369853Y1073383D03*
X1373553D03*
X1379104Y1076587D03*
Y1070178D03*
X1377253Y1073383D03*
X1375403Y1076587D03*
X1375404Y1070178D03*
X1373554Y1066974D03*
X1368004Y1076587D03*
Y1070178D03*
X1377253Y1079791D03*
X1373553D03*
X1366153D03*
X1364304Y1076587D03*
X1369853Y1079791D03*
X1371704Y1076587D03*
X1364304Y1070178D03*
X1366153Y1066974D03*
X1371704Y1070178D03*
X1369853Y1066974D03*
Y1073383D03*
X1366153D03*
X1373553D03*
X1379104Y1082995D03*
X1371704Y1095813D03*
Y1089404D03*
X1369853Y1086200D03*
Y1092608D03*
X1373553D03*
X1379103Y1089404D03*
X1380953Y1086200D03*
Y1099017D03*
X1377253D03*
X1369853D03*
X1364303Y1082995D03*
X1377254Y1092608D03*
X1377253Y1086200D03*
X1375404Y1089404D03*
X1373554Y1086200D03*
X1371704Y1082995D03*
X1368004Y1089404D03*
Y1082995D03*
X1379104Y1095813D03*
X1375403D03*
X1368004D03*
X1371704D03*
X1364304Y1089404D03*
X1366153Y1086200D03*
X1371704Y1089404D03*
X1369853Y1086200D03*
X1364304Y1095813D03*
X1369853Y1092608D03*
X1366153D03*
X1373553D03*
X1375404Y1082995D03*
X1379104D03*
X1379103Y1089404D03*
X1379104Y1102221D03*
Y1108630D03*
X1368004D03*
X1369853Y1111834D03*
X1373553Y1105426D03*
X1371704Y1108630D03*
X1377253Y1111834D03*
X1375404Y1108630D03*
X1368004Y1115039D03*
X1375404D03*
X1379104D03*
X1364304Y1108630D03*
Y1102221D03*
X1377253Y1105426D03*
X1375404Y1102221D03*
X1373554Y1099017D03*
X1371704Y1102221D03*
X1366153Y1105426D03*
X1373553Y1111834D03*
X1366153D03*
X1369853Y1099017D03*
X1366153D03*
X1368004Y1102221D03*
X1369853Y1105426D03*
Y1111834D03*
X1368004Y1108630D03*
X1377253Y1099017D03*
X1379104Y1108630D03*
X1373553Y1105426D03*
X1371704Y1108630D03*
X1379104Y1102221D03*
X1377253Y1111834D03*
X1375404Y1108630D03*
X1368004Y1127856D03*
X1379104Y1121447D03*
X1375404Y1127856D03*
X1371704Y1121447D03*
X1377253Y1124651D03*
X1373553D03*
X1369853D03*
X1380953D03*
X1364303Y1115039D03*
X1377253Y1118243D03*
X1373553D03*
X1371703Y1115039D03*
X1369853Y1118243D03*
X1366153D03*
X1364303Y1127856D03*
X1379103D03*
X1371703D03*
X1366153Y1124651D03*
X1371704Y1121447D03*
X1373553Y1124651D03*
X1377253D03*
X1368004Y1127856D03*
X1369853Y1124651D03*
X1375404Y1127856D03*
X1379104Y1121447D03*
X1364304D03*
X1368004D03*
X1375404Y1115039D03*
X1368004D03*
X1379104D03*
X1375404Y1121447D03*
X1380954Y1137469D03*
X1379104Y1134264D03*
X1368003Y1140973D03*
X1371704Y1134264D03*
X1377254Y1137469D03*
X1373554D03*
X1369854D03*
X1375403Y1140973D03*
X1364303D03*
X1379103D03*
X1377253Y1131060D03*
X1373553D03*
X1371703Y1140973D03*
X1369853Y1131060D03*
X1366153D03*
X1368003Y1140973D03*
X1371704Y1134264D03*
X1375403Y1140973D03*
X1379104Y1134264D03*
X1364304D03*
X1366154Y1137469D03*
X1369854D03*
X1373554D03*
X1377254D03*
X1368004Y1134264D03*
X1375404D03*
X1374847Y1153069D03*
X1371212Y1578088D03*
X1375472Y1578182D03*
X1371212Y1590094D03*
X1375472D03*
X1364452Y1602380D03*
Y1614292D03*
X1376512Y1602286D03*
Y1614292D03*
X1368712Y1602380D03*
Y1614292D03*
X1397169Y844971D03*
X1395320Y848176D03*
X1386069Y844971D03*
X1384221Y841467D03*
X1389769Y844971D03*
X1393469D03*
X1387920Y848176D03*
X1391621Y841467D03*
X1384220Y854584D03*
X1391620D03*
X1380521Y841467D03*
X1395321D03*
X1387921D03*
X1393471Y851380D03*
X1389771D03*
X1386071D03*
X1382371D03*
X1391620Y848176D03*
X1384220D03*
X1380520D03*
X1386069Y844971D03*
X1389769D03*
X1393469D03*
X1382369D03*
X1384221Y841467D03*
X1387920Y848176D03*
X1391621Y841467D03*
X1395320Y848176D03*
X1386071Y857789D03*
X1384220Y867401D03*
X1387920Y860993D03*
X1389771Y857789D03*
X1395320Y860993D03*
X1393471Y857789D03*
X1391620Y867401D03*
X1397171Y857789D03*
Y870606D03*
X1389771D03*
X1393471D03*
X1380521Y854584D03*
X1395321D03*
X1393471Y864197D03*
X1389771D03*
X1387921Y854584D03*
X1386071Y864197D03*
X1382371D03*
X1380521Y867401D03*
X1395321D03*
X1387921D03*
X1384220D03*
X1391620D03*
X1384220Y860993D03*
X1391620D03*
X1380520D03*
X1382371Y857789D03*
X1387920Y860993D03*
X1389771Y857789D03*
X1395320Y860993D03*
X1384220Y854584D03*
X1386071Y857789D03*
X1391620Y854584D03*
X1393471Y857789D03*
X1397171Y883423D03*
X1395320Y873810D03*
X1384220Y880219D03*
X1386071Y883423D03*
X1393471D03*
X1389771D03*
X1391620Y880219D03*
X1387920Y873810D03*
Y886627D03*
X1395320D03*
X1380521Y880219D03*
X1395321D03*
X1393471Y877014D03*
X1389771D03*
X1387921Y880219D03*
X1386071Y877014D03*
Y870606D03*
X1382371Y877014D03*
X1380520Y873810D03*
X1382371Y870606D03*
X1384220Y880219D03*
X1386071Y883423D03*
X1382371D03*
X1395320Y873810D03*
X1393471Y870606D03*
X1387920Y873810D03*
X1389771Y870606D03*
X1393471Y883423D03*
X1391620Y880219D03*
X1389771Y883423D03*
X1391620Y873810D03*
X1384220D03*
X1386071Y896240D03*
X1389771D03*
X1393471D03*
X1387920Y899445D03*
X1391620Y893036D03*
X1395320Y899445D03*
X1397171Y896240D03*
X1386071D03*
X1389771D03*
X1393471D03*
X1387920Y899445D03*
X1391620Y893036D03*
X1395320Y899445D03*
X1395321Y893036D03*
X1393471Y889832D03*
X1389771D03*
X1387921Y893036D03*
X1386071Y889832D03*
X1384221Y893036D03*
X1382371Y889832D03*
X1380520Y886627D03*
X1387920D03*
X1395320D03*
X1380520Y893036D03*
X1382371Y896240D03*
X1384220Y886627D03*
X1391620D03*
Y899445D03*
X1384221Y899446D03*
X1386071Y902649D03*
X1380520Y912262D03*
Y905853D03*
X1395320Y912262D03*
X1395321Y905853D03*
X1393471Y902649D03*
X1389771D03*
X1386071Y909057D03*
Y915466D03*
X1393471Y909057D03*
X1382371D03*
X1389771D03*
Y915466D03*
X1382371D03*
X1387920Y905853D03*
X1384220D03*
Y912262D03*
X1382371Y902649D03*
X1391620Y905853D03*
X1387920Y912262D03*
X1391620D03*
X1393471Y915466D03*
X1380520Y918670D03*
X1395187Y926265D03*
X1395320Y918670D03*
X1386071Y921875D03*
X1381189Y930811D03*
X1382371Y921875D03*
X1382809Y927986D03*
X1385070Y928468D03*
X1393471Y921875D03*
X1391550Y925219D03*
X1387921Y918670D03*
X1381189Y938045D03*
X1381287Y946239D03*
Y948539D03*
X1381189Y935745D03*
X1390234Y942097D03*
X1386030Y942163D03*
X1383730D03*
X1381430D03*
X1392534Y942097D03*
X1394834D03*
X1381264Y965896D03*
Y963596D03*
X1393826Y956619D03*
X1387826D03*
X1391326D03*
X1385526D03*
X1390506Y971139D03*
X1392896D03*
X1381003Y981269D03*
Y978969D03*
X1380926Y971099D03*
X1383226D03*
X1387826D03*
X1385526D03*
X1396346D03*
X1381003Y986421D03*
X1381243Y992971D03*
Y995271D03*
X1381003Y988721D03*
X1393716Y985579D03*
X1391326D03*
X1396286Y985549D03*
X1388506Y985609D03*
X1386206D03*
X1381369Y1007156D03*
X1381373Y1004848D03*
X1391326Y1014539D03*
X1393716D03*
Y1000059D03*
X1391326D03*
X1385526Y1014539D03*
X1387826D03*
X1383226D03*
X1386226Y1000079D03*
X1396356Y1000039D03*
X1388526Y1000079D03*
X1396546Y1014469D03*
X1381128Y1022427D03*
X1381140Y1026821D03*
X1388102Y1028854D03*
X1390602D03*
X1393102D03*
X1395602D03*
X1384466Y1034270D03*
Y1031970D03*
X1393904Y1044544D03*
X1384653Y1041340D03*
X1380953Y1047749D03*
X1388353D03*
X1380953Y1041340D03*
X1388353D03*
X1392053D03*
X1395753D03*
X1392053Y1047749D03*
X1382804Y1044544D03*
X1386504D03*
X1390204D03*
X1382804Y1050952D03*
X1380953Y1060565D03*
X1393904Y1050952D03*
X1392053Y1060565D03*
Y1054157D03*
X1388353Y1060565D03*
X1386504Y1050952D03*
X1384653Y1054157D03*
X1382804Y1057361D03*
X1386504D03*
X1395753Y1054157D03*
X1384653Y1060565D03*
X1386504Y1063770D03*
X1388353Y1054157D03*
X1390204Y1057361D03*
Y1063770D03*
X1395753Y1060565D03*
X1384653Y1079791D03*
X1395753D03*
X1384653Y1073383D03*
X1382804Y1070178D03*
X1380953Y1073383D03*
Y1066974D03*
X1395753Y1073383D03*
X1392053Y1066974D03*
X1386504Y1076587D03*
Y1070178D03*
X1382803Y1076587D03*
X1380953Y1079791D03*
X1388353D03*
X1392053D03*
X1384653Y1066974D03*
X1392053Y1073383D03*
X1390204Y1070178D03*
X1395753Y1066974D03*
X1384653Y1079791D03*
X1382804Y1082995D03*
Y1089404D03*
X1384653Y1092608D03*
X1386504Y1082995D03*
X1390204D03*
X1388353Y1086200D03*
X1390204Y1089404D03*
X1395753Y1086200D03*
Y1092608D03*
X1386504Y1089404D03*
X1397604D03*
X1384653Y1099017D03*
X1393903Y1089404D03*
Y1082995D03*
X1392053Y1092608D03*
X1392054Y1086200D03*
X1388353Y1092608D03*
X1384653Y1086200D03*
X1386504Y1095813D03*
X1382804D03*
X1380953Y1092608D03*
X1393904Y1095813D03*
X1388353Y1086200D03*
X1386504Y1082995D03*
X1390204Y1089404D03*
X1382804D03*
X1390204Y1082995D03*
X1382804D03*
X1395753Y1086200D03*
Y1092608D03*
X1380953Y1086200D03*
X1386504Y1089404D03*
X1384653Y1092608D03*
X1395753Y1105426D03*
Y1111834D03*
X1384653Y1105426D03*
Y1111834D03*
X1390204Y1102221D03*
X1393904Y1108630D03*
X1392053Y1111834D03*
X1388353D03*
X1392053Y1105426D03*
X1388353D03*
X1386504Y1108630D03*
X1390204Y1115039D03*
X1380954Y1105426D03*
X1393904Y1102221D03*
X1392054Y1099017D03*
X1390204Y1108630D03*
X1388353Y1099017D03*
X1386504Y1102221D03*
X1382803Y1108630D03*
Y1102221D03*
X1380954Y1111834D03*
X1380953Y1099017D03*
X1395753Y1105426D03*
X1393904Y1108630D03*
X1390204Y1102221D03*
X1392053Y1111834D03*
X1388353D03*
X1384653Y1105426D03*
Y1099017D03*
X1392053Y1105426D03*
X1395753Y1111834D03*
X1388353Y1105426D03*
X1384653Y1111834D03*
X1386504Y1108630D03*
X1382804Y1127856D03*
X1384653Y1124651D03*
X1386504Y1121447D03*
X1380953Y1118243D03*
X1393903Y1115039D03*
X1392053Y1118243D03*
X1390203Y1121447D03*
X1388353Y1124651D03*
Y1118243D03*
X1386503Y1115039D03*
X1384653Y1118243D03*
X1382803Y1115039D03*
X1386503Y1127856D03*
X1380953Y1124651D03*
X1384653D03*
X1382804Y1127856D03*
X1386504Y1121447D03*
X1392054Y1124651D03*
X1393903Y1121447D03*
Y1127856D03*
X1395754Y1118243D03*
Y1124651D03*
X1390204Y1115039D03*
X1382803Y1121447D03*
X1390204Y1127856D03*
X1384654Y1137469D03*
X1382803Y1140973D03*
X1386504Y1134264D03*
X1380953Y1131060D03*
X1390204Y1134264D03*
X1388354Y1131060D03*
X1386503Y1140973D03*
X1384653Y1131060D03*
X1382803Y1140973D03*
X1386504Y1134264D03*
X1380954Y1137469D03*
X1384654D03*
X1382804Y1134264D03*
X1390203Y1140973D03*
X1392054Y1131060D03*
Y1137469D03*
X1393903Y1134264D03*
Y1140973D03*
X1395754Y1131060D03*
Y1137469D03*
X1388354D03*
X1383272Y1578182D03*
Y1590094D03*
X1380772Y1602380D03*
Y1614292D03*
X1388572D03*
Y1602380D03*
X1413820Y848176D03*
X1411969Y844971D03*
X1399021Y841467D03*
X1402720Y848176D03*
X1400869Y844971D03*
X1406420Y848176D03*
X1404569Y844971D03*
X1410120Y848176D03*
X1399020Y854584D03*
X1406420D03*
X1413821D03*
X1408269Y844971D03*
X1402721Y841467D03*
X1397171Y851380D03*
X1408271D03*
X1404571D03*
X1400871D03*
X1411971D03*
X1399020Y848176D03*
X1397169Y844971D03*
X1399021Y841467D03*
X1402720Y848176D03*
X1406420D03*
X1411969Y844971D03*
X1400869D03*
X1404569D03*
X1410120Y848176D03*
X1402720Y860993D03*
X1400871Y857789D03*
X1399020Y867401D03*
X1404571Y857789D03*
X1410121Y860993D03*
X1411971Y857789D03*
X1408271D03*
X1406420Y867401D03*
X1413820D03*
X1411971Y870606D03*
X1400871D03*
X1404571D03*
X1408271D03*
X1397171Y864197D03*
X1408271D03*
X1404571D03*
X1402721Y854584D03*
X1400871Y864197D03*
X1410121Y854584D03*
X1411971Y864197D03*
X1410121Y867401D03*
X1402721D03*
X1406420D03*
X1399020D03*
X1406420Y860993D03*
X1399020D03*
X1397171Y857789D03*
X1402720Y860993D03*
X1404571Y857789D03*
X1410121Y860993D03*
X1411971Y857789D03*
X1399020Y854584D03*
X1400871Y857789D03*
X1406420Y854584D03*
X1408271Y857789D03*
X1413820Y880219D03*
X1411971Y883423D03*
X1399020Y880219D03*
X1400871Y883423D03*
X1402720Y873810D03*
X1408271Y883423D03*
X1404571D03*
X1406420Y880219D03*
X1410121Y873810D03*
X1402720Y886627D03*
X1410120D03*
X1397171Y877014D03*
X1410121Y880219D03*
X1408271Y877014D03*
X1404571D03*
X1402721Y880219D03*
X1400871Y877014D03*
X1411971D03*
X1408271Y870606D03*
X1402720Y873810D03*
X1400871Y870606D03*
X1410121Y873810D03*
X1404571Y870606D03*
X1397171D03*
X1411971D03*
X1408271Y883423D03*
X1406420Y880219D03*
X1400871Y883423D03*
X1399020Y880219D03*
X1404571Y883423D03*
X1397171D03*
X1411971D03*
X1399020Y873810D03*
X1402720Y899445D03*
X1399020Y893036D03*
X1400871Y896240D03*
X1404571D03*
X1410120Y899445D03*
X1406420Y893036D03*
X1408271Y896240D03*
X1411971D03*
X1413820Y893036D03*
X1397171Y896240D03*
X1402720Y899445D03*
X1404571Y896240D03*
X1410120Y899445D03*
X1399020Y893036D03*
X1400871Y896240D03*
X1406420Y893036D03*
X1408271Y896240D03*
X1411971D03*
X1397171Y889832D03*
X1410121Y893036D03*
X1408271Y889832D03*
X1404571D03*
X1402721Y893036D03*
X1400871Y889832D03*
X1411971D03*
X1410120Y886627D03*
X1402720D03*
X1406420D03*
X1399020D03*
X1406420Y899445D03*
X1399020D03*
Y912262D03*
X1400871Y915466D03*
X1402720Y912262D03*
X1400871Y902649D03*
X1397171D03*
X1408271D03*
X1404571Y909057D03*
Y902649D03*
X1411971D03*
X1404571Y915466D03*
X1406420Y912262D03*
X1408271Y915466D03*
X1397171Y909057D03*
X1411971D03*
Y915466D03*
X1408270Y909057D03*
X1410120Y905853D03*
X1400870Y909057D03*
X1402720Y905853D03*
X1397171Y915466D03*
X1410121Y912262D03*
X1406420Y918670D03*
X1410121Y925079D03*
Y931488D03*
X1404571Y921875D03*
X1408271D03*
X1410121Y918670D03*
X1411971Y921875D03*
X1401528Y927155D03*
X1399028D03*
X1401817Y929464D03*
X1399317D03*
X1400871Y921875D03*
X1399020Y918670D03*
X1397171Y921875D03*
X1402720Y918670D03*
X1408271Y928283D03*
X1403016Y949498D03*
Y947198D03*
X1406420Y937896D03*
X1404016Y936469D03*
X1410120Y937896D03*
X1410121Y944304D03*
X1406421D03*
X1408271Y941100D03*
X1411971D03*
X1404016Y944229D03*
Y941929D03*
X1408270Y947509D03*
X1411971D03*
X1408271Y934691D03*
X1403046Y963634D03*
Y965934D03*
X1410121Y957122D03*
Y950713D03*
Y963530D03*
X1406421Y950713D03*
Y957122D03*
X1408270Y953917D03*
Y960326D03*
X1411971Y953917D03*
Y960326D03*
X1404016Y954072D03*
Y956372D03*
X1401326Y956619D03*
X1398826D03*
X1406421Y963530D03*
X1408270Y966735D03*
X1411971D03*
X1403046Y978035D03*
Y980335D03*
X1410121Y976347D03*
Y969939D03*
Y982756D03*
X1406421Y969939D03*
X1406409Y976347D03*
X1408270Y973143D03*
X1411971D03*
X1404016Y971266D03*
Y968966D03*
X1398826Y971099D03*
X1406421Y982756D03*
X1408270Y979552D03*
X1411971D03*
X1404016Y983110D03*
X1403046Y992421D03*
Y994721D03*
X1404016Y985410D03*
X1398826Y985579D03*
X1404016Y997520D03*
X1403046Y1009174D03*
Y1006874D03*
X1410553Y1009297D03*
Y1002888D03*
X1412404Y999684D03*
Y1006093D03*
Y1012501D03*
X1406853Y1002888D03*
Y1009297D03*
X1408703Y999684D03*
Y1006093D03*
Y1012501D03*
X1404016Y1012151D03*
Y999820D03*
X1398826Y1000059D03*
X1404016Y1014451D03*
X1399156Y1014469D03*
X1403046Y1021962D03*
Y1019662D03*
X1410553Y1028523D03*
Y1022114D03*
Y1015705D03*
X1398102Y1028854D03*
X1406853Y1028523D03*
X1412404Y1018910D03*
X1406853Y1015705D03*
Y1022114D03*
X1408703Y1018910D03*
X1412404Y1025318D03*
X1408703D03*
X1404016Y1026703D03*
X1412404Y1031727D03*
X1408703D03*
X1404016Y1029003D03*
Y1031303D03*
X1405004Y1044544D03*
X1410553Y1034931D03*
X1406854Y1047749D03*
X1399453D03*
X1403153D03*
X1399454Y1041340D03*
X1401304Y1044544D03*
X1412403Y1038136D03*
Y1044544D03*
X1406853Y1034931D03*
Y1041340D03*
X1408703Y1038136D03*
Y1044544D03*
X1410554Y1041340D03*
X1404016Y1033603D03*
X1399426Y1036883D03*
Y1034583D03*
Y1032283D03*
X1410554Y1047749D03*
X1397604Y1044544D03*
X1403153Y1054157D03*
X1406853D03*
X1408703Y1050952D03*
X1401304Y1057361D03*
X1410553Y1060565D03*
Y1054157D03*
X1397604Y1063770D03*
X1405003Y1057361D03*
X1412404Y1050952D03*
Y1057361D03*
Y1063770D03*
X1397604Y1057361D03*
X1401304Y1050952D03*
X1397604D03*
X1399453Y1060565D03*
X1403153D03*
X1405003Y1063770D03*
X1406853Y1060565D03*
X1405003Y1076587D03*
X1406853Y1079791D03*
X1397604Y1076587D03*
X1408703D03*
X1406853Y1073383D03*
X1403153D03*
Y1066974D03*
X1401304Y1076587D03*
X1399453Y1066974D03*
X1410553Y1073383D03*
Y1066974D03*
X1403154Y1079791D03*
X1410553D03*
X1408702Y1070178D03*
X1399453Y1079791D03*
X1412404Y1070178D03*
Y1076587D03*
X1397604Y1070178D03*
X1401304D03*
X1406853Y1066974D03*
X1405003Y1076587D03*
X1406853Y1079791D03*
X1401304Y1082995D03*
X1399453Y1086200D03*
Y1092608D03*
X1401304Y1095813D03*
X1405003Y1089404D03*
X1406853Y1092608D03*
X1403154Y1086200D03*
X1406852D03*
X1403153Y1092608D03*
X1408703Y1089404D03*
Y1082995D03*
X1405003D03*
X1401304Y1089404D03*
X1397604Y1082995D03*
X1410553Y1092608D03*
Y1086200D03*
X1408703Y1095813D03*
X1405003D03*
X1397604D03*
X1412404Y1082995D03*
Y1089404D03*
X1412403Y1095813D03*
X1401304Y1082995D03*
X1405003Y1089404D03*
X1399453Y1086200D03*
X1406853Y1092608D03*
X1399453D03*
X1397604Y1089404D03*
X1403154Y1086200D03*
X1406852D03*
X1403153Y1092608D03*
X1401304Y1095813D03*
X1403153Y1099017D03*
X1401303Y1102221D03*
X1399453Y1105426D03*
X1397604Y1108630D03*
X1410553Y1105426D03*
X1399453Y1111834D03*
X1410553D03*
X1397604Y1102221D03*
X1399453Y1099017D03*
X1412404Y1102221D03*
Y1108630D03*
X1401304D03*
X1403154Y1105426D03*
Y1111834D03*
X1405003Y1102221D03*
Y1108630D03*
X1406853Y1099017D03*
Y1105426D03*
Y1111834D03*
X1408703Y1102221D03*
Y1108630D03*
X1410554Y1099017D03*
X1399453Y1124651D03*
Y1118243D03*
X1397604Y1115039D03*
X1410553Y1124651D03*
Y1118243D03*
X1412404Y1115039D03*
Y1121447D03*
Y1127856D03*
X1397603Y1121447D03*
Y1127856D03*
X1401304Y1115039D03*
Y1121447D03*
Y1127856D03*
X1403154Y1118243D03*
Y1124651D03*
X1405003Y1115039D03*
Y1121447D03*
Y1127856D03*
X1406853Y1118243D03*
Y1124651D03*
X1408703Y1115039D03*
Y1121447D03*
Y1127856D03*
X1399454Y1137469D03*
X1399453Y1131060D03*
X1410554Y1137769D03*
X1410553Y1131060D03*
X1412403Y1134264D03*
X1397603D03*
Y1140973D03*
X1401304Y1134264D03*
X1401303Y1140973D03*
X1403154Y1131060D03*
Y1137569D03*
X1405003Y1134264D03*
Y1140973D03*
X1406853Y1131060D03*
Y1137769D03*
X1408703Y1134264D03*
X1421220Y854584D03*
X1428620D03*
Y848176D03*
X1415669Y844971D03*
X1421220Y848176D03*
X1417520D03*
X1426771Y851380D03*
X1423070D03*
X1419370D03*
X1415671D03*
X1413820Y848176D03*
X1417520Y860993D03*
X1419371Y857789D03*
X1424921Y860993D03*
X1426771Y857789D03*
X1423071D03*
X1428620Y867401D03*
X1421220D03*
X1430471Y857789D03*
Y870606D03*
X1426771D03*
X1419371D03*
X1415671D03*
X1423071D03*
X1413822Y860993D03*
X1426771Y864197D03*
X1424921Y854584D03*
X1423071Y864197D03*
X1419371D03*
X1417521Y854584D03*
X1415671Y864197D03*
Y857789D03*
X1424921Y867401D03*
X1417521D03*
X1428620D03*
X1421220D03*
X1413820D03*
X1421220Y860993D03*
X1428621D03*
X1424921D03*
X1421220Y854584D03*
X1417520Y860993D03*
X1428620Y854584D03*
X1426771Y857789D03*
X1423071D03*
X1419371D03*
X1413821Y854584D03*
X1430471Y883423D03*
X1426771D03*
X1428621Y880219D03*
X1419371Y883423D03*
X1415671D03*
X1417520Y873810D03*
X1423071Y883423D03*
X1421220Y880219D03*
X1424921Y873810D03*
X1417520Y886627D03*
X1424920D03*
X1426771Y877014D03*
X1424921Y880219D03*
X1423071Y877014D03*
X1419371D03*
X1417521Y880219D03*
X1415671Y877014D03*
X1424921Y873810D03*
X1423071Y870606D03*
X1417520Y873810D03*
X1415671Y870606D03*
X1426771D03*
X1419371D03*
X1428621Y880219D03*
X1423071Y883423D03*
X1421220Y880219D03*
X1415671Y883423D03*
X1413820Y880219D03*
X1426771Y883423D03*
X1419371D03*
X1413821Y873810D03*
X1428621D03*
X1421220D03*
X1419371Y896240D03*
X1417520Y899445D03*
X1421220D03*
X1424920D03*
X1426772Y896240D03*
X1421220Y893036D03*
X1423071Y896240D03*
X1428621Y893036D03*
X1430471Y896240D03*
X1413820Y893036D03*
X1421220Y899445D03*
X1419371Y896240D03*
X1424920Y899445D03*
X1426772Y896240D03*
X1417520Y899445D03*
X1421220Y893036D03*
X1423071Y896240D03*
X1428621Y893036D03*
X1413820Y886627D03*
X1426771Y889832D03*
X1424921Y893036D03*
X1423071Y889832D03*
X1419371D03*
X1417521Y893036D03*
X1415671Y896240D03*
Y889832D03*
X1413821Y899445D03*
X1424920Y886627D03*
X1417520D03*
X1428620Y899445D03*
Y886627D03*
X1421220D03*
X1413820Y912262D03*
X1413821Y905853D03*
X1426771Y902649D03*
X1423071Y909057D03*
Y902649D03*
X1419371D03*
X1415670D03*
X1423071Y915466D03*
X1419371Y909057D03*
X1415671Y915466D03*
X1421221Y905853D03*
X1417521D03*
X1426772Y909057D03*
X1428621Y905853D03*
X1424922Y912262D03*
X1417522D03*
X1419371Y915466D03*
X1426771D03*
X1428620Y912262D03*
X1415671Y921875D03*
X1423071Y928283D03*
X1417520Y925079D03*
Y931488D03*
X1413820Y918670D03*
X1423071Y921875D03*
X1417520Y918670D03*
X1426771Y921875D03*
X1421220Y918670D03*
X1419371Y921875D03*
X1428620Y918670D03*
X1413820Y931488D03*
X1421220D03*
Y925079D03*
X1415671Y928283D03*
X1413820Y925079D03*
X1426771Y928283D03*
X1424920Y937896D03*
X1421220D03*
X1417520D03*
X1413820D03*
X1423070Y941100D03*
X1423071Y947509D03*
X1413821Y944304D03*
X1415671Y941100D03*
X1417521Y944304D03*
X1419371Y941100D03*
X1421220Y944304D03*
X1424921D03*
X1426771Y941100D03*
X1415670Y947509D03*
X1419370D03*
X1426771D03*
X1423071Y934691D03*
X1415671D03*
X1423071Y960326D03*
Y953917D03*
Y966735D03*
X1413821Y950713D03*
Y957122D03*
X1415670Y953917D03*
Y960326D03*
X1417521Y950713D03*
Y957122D03*
X1419370Y953917D03*
Y960326D03*
X1421220Y950713D03*
Y957122D03*
X1424921Y950713D03*
Y957122D03*
X1426771Y953917D03*
Y960326D03*
X1413821Y963530D03*
X1415670Y966735D03*
X1417521Y963530D03*
X1419370Y966735D03*
X1421220Y963530D03*
X1424921D03*
X1426771Y966735D03*
X1423071Y979552D03*
Y973143D03*
X1413821Y969939D03*
Y976347D03*
X1415670Y973143D03*
X1417521Y969939D03*
Y976347D03*
X1419370Y973143D03*
X1421220Y969939D03*
Y976347D03*
X1424921Y969939D03*
Y976347D03*
X1426771Y973143D03*
X1413821Y982756D03*
X1415670Y979552D03*
X1417521Y982756D03*
X1419370Y979552D03*
X1421220Y982756D03*
X1424921D03*
X1426771Y979552D03*
X1423503Y1006093D03*
Y999684D03*
Y1012501D03*
X1414254Y1002888D03*
Y1009297D03*
X1416103Y999684D03*
Y1006093D03*
Y1012501D03*
X1417954Y1002888D03*
Y1009297D03*
X1419803Y999684D03*
Y1006093D03*
Y1012501D03*
X1421653Y1002888D03*
Y1009297D03*
X1425354Y1002888D03*
Y1009297D03*
X1427203Y999684D03*
Y1006093D03*
Y1012501D03*
X1423503Y1025318D03*
Y1018910D03*
Y1031727D03*
X1421653Y1028523D03*
X1414254D03*
X1417954D03*
X1425354D03*
X1414254Y1015705D03*
Y1022114D03*
X1416103Y1018910D03*
X1417954Y1015705D03*
Y1022114D03*
X1419803Y1018910D03*
X1421653Y1015705D03*
Y1022114D03*
X1425354Y1015705D03*
Y1022114D03*
X1427203Y1018910D03*
X1416103Y1025318D03*
X1419803D03*
X1427203D03*
X1416103Y1031727D03*
X1419803D03*
X1427203D03*
X1429053Y1041340D03*
X1427203Y1044544D03*
X1423503Y1038136D03*
X1425353Y1047749D03*
X1429053D03*
X1414254Y1034931D03*
Y1041340D03*
X1416103Y1038136D03*
Y1044544D03*
X1417954Y1034931D03*
Y1041340D03*
X1419803Y1038136D03*
Y1044544D03*
X1421653Y1034931D03*
Y1041340D03*
X1423503Y1044544D03*
X1425354Y1034931D03*
X1425353Y1041340D03*
X1427203Y1038136D03*
X1421653Y1047749D03*
X1414254D03*
X1417954D03*
X1429053Y1060565D03*
X1423503Y1057361D03*
Y1050952D03*
Y1063770D03*
X1414254Y1054157D03*
X1416103Y1050952D03*
X1417954Y1054157D03*
X1419803Y1050952D03*
X1421653Y1054157D03*
X1414254Y1060565D03*
X1416103Y1057361D03*
X1417954Y1060565D03*
X1419803Y1057361D03*
X1421653Y1060565D03*
X1416103Y1063770D03*
X1419803D03*
X1427203D03*
X1429053Y1054157D03*
X1427203Y1050952D03*
X1427204Y1057361D03*
X1425353Y1073383D03*
X1423503Y1076587D03*
Y1070178D03*
X1429053Y1079791D03*
X1425353D03*
X1429053Y1073383D03*
X1414254Y1066974D03*
Y1073383D03*
X1416103Y1070178D03*
Y1076587D03*
X1417954Y1066974D03*
Y1073383D03*
X1419803Y1070178D03*
Y1076587D03*
X1421653Y1066974D03*
Y1073383D03*
X1414254Y1079791D03*
X1417954D03*
X1421653D03*
X1429053Y1066974D03*
X1425353D03*
X1429053Y1092608D03*
X1427204Y1089404D03*
X1425354Y1086200D03*
X1423503Y1082995D03*
X1427203Y1095812D03*
X1429053Y1086200D03*
X1416103Y1082995D03*
X1419803D03*
X1414254Y1086200D03*
Y1092608D03*
X1416103Y1089404D03*
Y1095813D03*
X1417954Y1086200D03*
Y1092608D03*
X1419803Y1089404D03*
Y1095813D03*
X1421653Y1086200D03*
Y1092608D03*
X1423503Y1089404D03*
Y1095813D03*
X1425353Y1092608D03*
X1427202Y1082995D03*
X1429053Y1099017D03*
X1423503Y1108630D03*
Y1102221D03*
X1414254Y1099017D03*
Y1105426D03*
Y1111834D03*
X1416103Y1102221D03*
Y1108630D03*
X1417954Y1099017D03*
Y1105426D03*
Y1111834D03*
X1419803Y1102221D03*
Y1108630D03*
X1421653Y1099017D03*
Y1105426D03*
Y1111834D03*
X1425354Y1099017D03*
Y1105426D03*
Y1111834D03*
X1427203Y1102221D03*
Y1108630D03*
X1429054Y1105426D03*
Y1111834D03*
X1423503Y1121447D03*
Y1115039D03*
Y1127856D03*
X1414254Y1118243D03*
Y1124651D03*
X1416103Y1115039D03*
Y1121447D03*
Y1127856D03*
X1417954Y1118243D03*
Y1124651D03*
X1419803Y1115039D03*
Y1121447D03*
Y1127856D03*
X1421653Y1118243D03*
Y1124651D03*
X1425354Y1118243D03*
Y1124651D03*
X1427203Y1115039D03*
Y1121447D03*
Y1127856D03*
X1429054Y1118243D03*
Y1124651D03*
X1423503Y1134264D03*
X1414254Y1131060D03*
Y1137769D03*
X1416103Y1134264D03*
X1417954Y1131060D03*
Y1137769D03*
X1419803Y1134264D03*
X1421653Y1131060D03*
Y1137769D03*
X1425354Y1131060D03*
Y1137769D03*
X1427203Y1134264D03*
X1429054Y1131060D03*
Y1137769D03*
X1436020Y854584D03*
X1443420D03*
X1437871Y851380D03*
X1434171D03*
X1430470D03*
X1432321Y841467D03*
X1439721D03*
X1445271Y851380D03*
X1441571D03*
X1443420Y848176D03*
X1436020D03*
X1432320Y860993D03*
X1434171Y857789D03*
X1436020Y867401D03*
X1445271Y857789D03*
X1439720Y860993D03*
X1437871Y857789D03*
X1441571D03*
X1443420Y867401D03*
X1447120Y860993D03*
X1445271Y870606D03*
X1434171D03*
X1441571D03*
X1437871D03*
X1439721Y854584D03*
X1432321D03*
X1437871Y864197D03*
X1434171D03*
X1430471D03*
X1445271D03*
X1441571D03*
X1432321Y867401D03*
X1439721D03*
X1443420D03*
X1436020D03*
X1443420Y860993D03*
X1436020D03*
X1445271Y857789D03*
X1439720Y860993D03*
X1437871Y857789D03*
X1432320Y860993D03*
X1430471Y857789D03*
X1443420Y854584D03*
X1441571Y857789D03*
X1436020Y854584D03*
X1434171Y857789D03*
X1445271Y883423D03*
X1443420Y880219D03*
X1434171Y883423D03*
X1436020Y880219D03*
X1432320Y873810D03*
X1441571Y883423D03*
X1437871D03*
X1439720Y873810D03*
X1432320Y886627D03*
X1439720D03*
X1447120D03*
X1437871Y877014D03*
X1434171D03*
X1432321Y880219D03*
X1430471Y877014D03*
X1445271D03*
X1441571D03*
X1439721Y880219D03*
X1445271Y870606D03*
X1439720Y873810D03*
X1437871Y870606D03*
X1432320Y873810D03*
X1430471Y870606D03*
X1441571D03*
X1434171D03*
X1445271Y883423D03*
X1443420Y880219D03*
X1437871Y883423D03*
X1436020Y880219D03*
X1430471Y883423D03*
X1441571D03*
X1434171D03*
X1436020Y873810D03*
X1443420D03*
X1436020Y893036D03*
X1432320Y899445D03*
X1434171Y896240D03*
X1437871D03*
X1441571D03*
X1439720Y899445D03*
X1443420Y893036D03*
X1430471Y896240D03*
X1436020Y893036D03*
X1437871Y896240D03*
X1441571D03*
X1432320Y899445D03*
X1434171Y896240D03*
X1439720Y899445D03*
X1443420Y893036D03*
X1437871Y889832D03*
X1434171D03*
X1432321Y893036D03*
X1430471Y889832D03*
X1445271Y896240D03*
X1439721Y893036D03*
X1445271Y889832D03*
X1441571D03*
X1439720Y886627D03*
X1432320D03*
X1436020Y899445D03*
X1443420D03*
X1436020Y886627D03*
X1443420D03*
X1437871Y902649D03*
X1434171D03*
X1432320Y912262D03*
Y905853D03*
X1430471Y902649D03*
X1441571D03*
Y909057D03*
Y915466D03*
X1445271Y902649D03*
X1434171Y909057D03*
X1437871Y915466D03*
X1445271D03*
X1434171D03*
X1439720Y912262D03*
X1436020D03*
Y905853D03*
X1439720D03*
X1445271Y909057D03*
X1430244Y931358D03*
Y933658D03*
X1437871Y921875D03*
X1432320Y918670D03*
X1430471Y921875D03*
X1443420Y918670D03*
X1439777Y928348D03*
X1437477D03*
X1435177D03*
X1444377D03*
X1442077D03*
X1445271Y921875D03*
X1439720Y918670D03*
X1434171Y921875D03*
X1438402Y942151D03*
X1440702D03*
X1443002D03*
X1430564Y949138D03*
X1445392Y942195D03*
X1429726Y944537D03*
Y939937D03*
Y942237D03*
X1440015Y956539D03*
X1430564Y951438D03*
X1442413Y956539D03*
X1430534Y963828D03*
Y966128D03*
X1429544Y959298D03*
Y956998D03*
X1437565Y956619D03*
X1434545D03*
X1445045D03*
X1440015Y971139D03*
X1442413Y971099D03*
X1430404Y981208D03*
Y978908D03*
X1429544Y970798D03*
Y973098D03*
X1437565Y971139D03*
X1434545Y971099D03*
X1440015Y985579D03*
X1430604Y995298D03*
Y992998D03*
X1442413Y985579D03*
X1429544Y986898D03*
Y984598D03*
X1437565Y985579D03*
X1434545D03*
X1445045D03*
X1429544Y998398D03*
X1440015Y1014539D03*
Y1000059D03*
X1430584Y1009408D03*
Y1007108D03*
X1442413Y1014539D03*
Y1000059D03*
X1429544Y1012198D03*
Y1000698D03*
X1437565Y1000079D03*
X1434545D03*
X1445045D03*
X1429544Y1014498D03*
X1437436Y1014509D03*
X1434545Y1014539D03*
X1445036Y1014549D03*
X1430575Y1022185D03*
Y1019885D03*
X1439321Y1028854D03*
X1436821D03*
X1434321D03*
X1441821D03*
X1434083Y1031908D03*
X1443541Y1036914D03*
X1436453Y1041340D03*
X1442003Y1044544D03*
X1432753Y1047749D03*
X1440153D03*
X1443853Y1041340D03*
X1430904Y1044544D03*
Y1038136D03*
X1434083Y1034408D03*
X1434813Y1037069D03*
X1439413D03*
X1437113D03*
X1438304Y1044544D03*
X1434604D03*
X1432753Y1060565D03*
X1438303Y1057361D03*
X1432753Y1054157D03*
X1442004Y1057361D03*
X1438304Y1050952D03*
X1434604Y1063770D03*
X1442004D03*
X1438303D03*
X1442002Y1050952D03*
X1436454Y1054157D03*
X1434604Y1057361D03*
X1443854Y1054157D03*
Y1060565D03*
X1430903Y1063770D03*
X1440154Y1060565D03*
X1434603Y1050952D03*
X1432753Y1073383D03*
X1430903Y1076587D03*
X1430904Y1070178D03*
X1443853Y1073383D03*
Y1066974D03*
X1438304Y1070178D03*
X1432754Y1079791D03*
X1443853D03*
X1434602Y1070178D03*
X1440153Y1066974D03*
X1440154Y1079791D03*
X1436454D03*
X1438304Y1076587D03*
X1432753Y1066974D03*
X1442004Y1076587D03*
X1440153Y1073383D03*
X1434604Y1076587D03*
X1434603Y1082995D03*
X1432753Y1086200D03*
X1436453Y1092608D03*
X1443854Y1086200D03*
X1440153D03*
X1443854Y1092608D03*
X1438304Y1082995D03*
X1442004D03*
X1438303Y1095812D03*
X1434603D03*
X1442003Y1089403D03*
X1432754Y1092607D03*
X1430903Y1089403D03*
X1436454Y1086199D03*
X1430902Y1082995D03*
X1442003Y1095812D03*
X1440154Y1092607D03*
X1430903Y1095812D03*
X1434603Y1089403D03*
X1438303D03*
X1436454Y1105426D03*
X1434604Y1102221D03*
X1432753Y1099017D03*
X1442003Y1108630D03*
Y1102221D03*
X1440154Y1105426D03*
Y1099017D03*
X1438304Y1108630D03*
X1440154Y1111834D03*
X1443853Y1105426D03*
Y1111834D03*
X1438304Y1102221D03*
X1443853Y1099017D03*
X1430903Y1102221D03*
Y1108630D03*
X1432754Y1105426D03*
X1432753Y1111834D03*
X1434603Y1108630D03*
X1436454Y1111834D03*
Y1099016D03*
X1447553Y1124651D03*
X1445704Y1121447D03*
X1434604D03*
Y1115039D03*
X1443854Y1124651D03*
X1443853Y1118243D03*
X1442004Y1121447D03*
Y1115039D03*
X1434604Y1127856D03*
X1430903Y1115039D03*
Y1121447D03*
Y1127856D03*
X1432753Y1118243D03*
Y1124651D03*
X1436454Y1118243D03*
Y1124651D03*
X1438303Y1115039D03*
Y1121447D03*
Y1127856D03*
X1440153Y1118243D03*
X1440154Y1124651D03*
X1442003Y1127856D03*
X1434604Y1134264D03*
X1443854Y1131060D03*
Y1137469D03*
X1430903Y1134264D03*
Y1140973D03*
X1432753Y1131060D03*
X1432754Y1137469D03*
X1434603Y1140973D03*
X1436454Y1131060D03*
Y1137469D03*
X1438303Y1134264D03*
Y1140973D03*
X1440154Y1131060D03*
Y1137469D03*
X1442003Y1134264D03*
Y1140973D03*
X1450820Y854584D03*
X1458220D03*
X1454521Y841467D03*
X1447121D03*
X1460071Y851380D03*
X1452671D03*
X1456371D03*
X1448971D03*
X1450820Y848176D03*
X1458220D03*
X1452671Y857789D03*
X1448971D03*
X1450820Y867401D03*
X1460071Y857789D03*
X1454520Y860993D03*
X1456371Y857789D03*
X1458220Y867401D03*
X1461920Y860993D03*
X1463771Y857789D03*
Y870606D03*
X1460071D03*
X1452671D03*
X1456371D03*
X1460071Y864197D03*
X1456371D03*
X1454521Y854584D03*
X1452671Y864197D03*
X1447121Y854584D03*
X1448971Y864197D03*
X1454521Y867401D03*
X1447121D03*
X1450820D03*
X1458220D03*
X1450820Y860993D03*
X1458220D03*
X1460071Y857789D03*
X1454520Y860993D03*
X1452671Y857789D03*
X1447120Y860993D03*
X1458220Y854584D03*
X1456371Y857789D03*
X1450820Y854584D03*
X1448971Y857789D03*
X1461920Y873810D03*
X1463771Y883423D03*
X1460071D03*
X1450820Y880219D03*
X1448971Y883423D03*
X1452671D03*
X1454520Y873810D03*
X1458220Y880219D03*
X1456371Y883423D03*
X1454520Y886627D03*
X1461920D03*
X1460071Y877014D03*
X1456371D03*
X1454521Y880219D03*
X1452671Y877014D03*
X1448971D03*
X1448970Y870606D03*
X1447121Y880219D03*
Y873810D03*
X1456371Y870606D03*
X1452671D03*
X1454520Y873810D03*
X1460071Y870606D03*
X1450820Y880219D03*
X1452671Y883423D03*
X1458220Y880219D03*
X1460071Y883423D03*
X1448971D03*
X1456371D03*
X1458220Y873810D03*
X1450820D03*
X1458220Y893036D03*
X1460071Y896240D03*
X1461920Y899445D03*
Y893036D03*
X1463771Y896240D03*
Y902649D03*
X1456370Y896240D03*
X1456371Y889832D03*
X1454521Y893036D03*
X1447121D03*
X1460071Y889832D03*
X1452671D03*
X1448971D03*
X1458220Y899445D03*
X1450820D03*
Y893036D03*
X1448971Y896240D03*
X1458220Y893036D03*
X1460071Y896240D03*
X1447120Y886627D03*
X1454520D03*
Y899445D03*
X1458220Y886627D03*
X1450820D03*
X1461920Y912262D03*
X1463771Y909057D03*
Y915466D03*
X1460071D03*
X1461920Y918670D03*
X1456371Y902649D03*
X1460071Y909057D03*
X1458221Y912262D03*
X1450820D03*
Y905853D03*
X1460070Y902649D03*
X1460071Y915466D03*
X1456371D03*
X1447122Y912262D03*
X1452671Y915466D03*
X1448971Y902649D03*
X1456370Y909057D03*
X1458220Y905853D03*
X1452671Y902649D03*
X1447120Y905853D03*
X1448971Y909057D03*
X1452671D03*
X1461920Y931488D03*
X1463771Y928283D03*
Y921875D03*
Y934691D03*
X1460071D03*
X1456371Y928283D03*
X1454522Y931488D03*
X1454520Y925079D03*
X1458220D03*
X1452426Y930125D03*
X1460071Y928283D03*
X1458220Y918670D03*
X1456371Y921875D03*
X1460070D03*
X1452670D03*
X1450820Y918670D03*
X1458220Y931488D03*
X1448971Y921875D03*
X1447120Y918670D03*
X1446677Y928348D03*
X1461920Y937896D03*
X1463771Y947509D03*
Y941100D03*
X1461920Y950713D03*
X1454520Y937896D03*
X1456371Y941100D03*
X1452426Y934725D03*
X1454520Y944304D03*
X1452321Y945354D03*
Y947654D03*
X1460070Y941100D03*
X1458221Y944304D03*
X1458220Y937896D03*
X1456371Y934691D03*
X1460070Y947509D03*
X1460071Y934691D03*
X1456371Y947509D03*
X1449992Y942195D03*
X1447692D03*
X1460071Y953917D03*
X1461920Y957122D03*
X1463771Y966735D03*
Y960326D03*
Y953917D03*
X1452426Y962325D03*
Y960025D03*
Y964625D03*
X1460070Y960326D03*
X1458220Y957122D03*
X1458221Y950713D03*
X1460071Y966735D03*
X1454520Y963530D03*
X1456371Y966735D03*
X1458220Y963529D03*
X1460071Y953917D03*
X1456371D03*
X1454520Y957122D03*
Y950713D03*
X1447545Y956619D03*
X1461920Y976347D03*
Y969939D03*
X1463771Y979552D03*
Y973143D03*
X1460071D03*
X1452426Y966925D03*
X1452333Y977669D03*
X1452476Y980736D03*
X1458221Y969939D03*
X1460070Y979552D03*
X1458220Y976347D03*
X1460071Y973143D03*
X1450045Y971099D03*
X1445445D03*
X1447745D03*
X1452426Y973825D03*
Y971525D03*
X1456371Y979552D03*
X1454520Y982756D03*
X1456371Y973143D03*
X1454520Y976347D03*
X1452426Y996825D03*
Y994525D03*
Y989925D03*
Y987625D03*
X1447545Y985579D03*
X1462353Y1002888D03*
Y1009297D03*
X1460504Y1006093D03*
X1452436Y1010499D03*
X1452426Y1006025D03*
Y1003725D03*
Y1012925D03*
X1460503Y999684D03*
X1458654Y1009297D03*
X1458653Y1002888D03*
X1460504Y1012501D03*
X1456804Y999684D03*
X1454953Y1002888D03*
Y1009297D03*
X1456804Y1012501D03*
X1460504Y1006093D03*
X1447545Y1000079D03*
X1447345Y1014539D03*
X1460504Y1025318D03*
X1462353Y1028523D03*
Y1022114D03*
X1452416Y1022635D03*
X1452426Y1017525D03*
X1458653Y1028523D03*
Y1022114D03*
X1460503Y1018910D03*
Y1031727D03*
X1460504Y1025318D03*
X1456804Y1031727D03*
X1454953Y1028523D03*
Y1022114D03*
X1456803Y1018910D03*
X1454953Y1015705D03*
X1446934Y1028889D03*
X1452466Y1031794D03*
Y1029494D03*
Y1027194D03*
X1456804Y1025318D03*
X1458653Y1015705D03*
X1462353Y1047749D03*
Y1041340D03*
X1460504Y1044544D03*
X1447424Y1036526D03*
X1449649Y1035928D03*
X1458653Y1041340D03*
X1458654Y1034931D03*
X1451253Y1041340D03*
X1460503Y1038136D03*
X1458653Y1047749D03*
X1447553D03*
X1460504Y1044544D03*
X1445704D03*
X1456804Y1038136D03*
X1454953Y1041340D03*
X1456804Y1044544D03*
X1449404D03*
X1454953Y1047749D03*
X1453104Y1044544D03*
X1460504Y1063770D03*
X1462353Y1060565D03*
X1460503Y1057361D03*
X1458653Y1060565D03*
X1456804Y1050952D03*
X1451253Y1060565D03*
X1447553Y1054157D03*
X1460504Y1050952D03*
Y1063770D03*
X1456804D03*
X1458653Y1054157D03*
X1454954D03*
X1453104Y1057361D03*
Y1063770D03*
X1454954Y1060565D03*
X1456803Y1057361D03*
X1453103Y1050952D03*
X1445703Y1057361D03*
X1445704Y1063770D03*
X1447554Y1060565D03*
X1449403Y1057361D03*
X1449404Y1063770D03*
X1451254Y1054157D03*
X1445703Y1050952D03*
X1449404D03*
X1462353Y1066974D03*
Y1079791D03*
X1460503Y1076587D03*
X1451253Y1066974D03*
X1449404Y1070178D03*
X1460504D03*
X1458654Y1066974D03*
X1454953Y1073383D03*
X1458653Y1079791D03*
X1454954D03*
X1451253D03*
X1454953Y1066974D03*
X1445702Y1070178D03*
X1456804Y1076587D03*
Y1070178D03*
X1447553Y1073383D03*
X1449404Y1076587D03*
X1445704D03*
X1447553Y1079791D03*
X1451253Y1073383D03*
X1460504Y1082995D03*
X1462353Y1086200D03*
X1445703Y1089404D03*
X1458654Y1086200D03*
X1456804Y1082995D03*
X1453104Y1089404D03*
X1449404Y1082995D03*
X1460504Y1089404D03*
X1445704Y1095813D03*
X1460504D03*
X1456803D03*
X1460504Y1082995D03*
X1445704D03*
X1456804Y1089404D03*
X1449404Y1095813D03*
X1454954Y1092607D03*
X1451254D03*
X1449403Y1089403D03*
X1447554Y1086199D03*
X1453103Y1082994D03*
X1458654Y1092607D03*
X1453103Y1095812D03*
X1447554Y1092607D03*
X1451254Y1086199D03*
X1454954D03*
X1445704Y1102221D03*
X1458653Y1105426D03*
X1456804Y1108630D03*
X1454953Y1099017D03*
X1449404Y1108630D03*
X1453104Y1102221D03*
X1451254Y1099017D03*
X1447553D03*
X1458653Y1111834D03*
X1460504Y1108630D03*
X1451253Y1111834D03*
X1447553D03*
X1454953Y1105426D03*
X1445704Y1108630D03*
X1449404Y1102221D03*
X1458653Y1099017D03*
X1454953Y1111834D03*
X1453104Y1108630D03*
X1447553Y1105426D03*
X1451253D03*
X1460504Y1102221D03*
X1456804D03*
X1451253Y1124651D03*
X1449404Y1127856D03*
X1458653Y1124651D03*
X1454953D03*
X1460504Y1121447D03*
X1456804Y1127856D03*
X1453104Y1121447D03*
X1462353Y1124651D03*
X1445703Y1115039D03*
X1458653Y1118243D03*
X1456803Y1115039D03*
X1454953Y1118243D03*
X1453103Y1115039D03*
X1451253Y1118243D03*
X1447553D03*
X1445704Y1127856D03*
X1460503D03*
X1453103D03*
X1460504Y1115039D03*
X1449404D03*
X1460504Y1121447D03*
X1456804Y1127856D03*
X1453104Y1121447D03*
X1449404Y1127856D03*
X1445704Y1121447D03*
X1458653Y1124651D03*
X1454953D03*
X1451253D03*
X1447553D03*
X1456804Y1121447D03*
X1449404D03*
X1462354Y1137469D03*
X1460504Y1134264D03*
X1451254Y1137469D03*
X1449403Y1140973D03*
X1453104Y1134264D03*
X1458654Y1137469D03*
X1454954D03*
X1456803Y1140973D03*
X1445703D03*
X1458653Y1131060D03*
X1454953D03*
X1453103Y1140973D03*
X1451253Y1131060D03*
X1447554Y1137469D03*
Y1131060D03*
X1449403Y1134264D03*
X1460503Y1140973D03*
X1460504Y1134264D03*
X1458654Y1137469D03*
X1453104Y1134264D03*
X1451254Y1137469D03*
X1456803Y1140973D03*
X1454954Y1137469D03*
X1449403Y1140973D03*
X1456804Y1134264D03*
X1445703D03*
X1460095Y1578182D03*
Y1590094D03*
X1465620Y854584D03*
X1473020D03*
X1469321Y841467D03*
X1461921D03*
X1476721D03*
X1474871Y851380D03*
X1471171D03*
X1467471D03*
X1463771D03*
X1465620Y848176D03*
X1473020D03*
X1476720Y860993D03*
X1467471Y857789D03*
X1469320Y860993D03*
X1465620Y867401D03*
X1474871Y857789D03*
X1471171D03*
X1473020Y867401D03*
X1478571Y857789D03*
Y870606D03*
X1467471D03*
X1471171D03*
X1474871D03*
X1461921Y854584D03*
X1474871Y864197D03*
X1471171D03*
X1469321Y854584D03*
X1467471Y864197D03*
X1463771D03*
X1476721Y854584D03*
X1461921Y867401D03*
X1476721D03*
X1469321D03*
X1465620D03*
X1473020D03*
X1465620Y860993D03*
X1473020D03*
X1467471Y857789D03*
X1461920Y860993D03*
X1476720D03*
X1474871Y857789D03*
X1471171D03*
X1465620Y854584D03*
X1463771Y857789D03*
X1473020Y854584D03*
X1469320Y860993D03*
X1478571Y883423D03*
X1476720Y873810D03*
X1469320D03*
X1465620Y880219D03*
X1467471Y883423D03*
X1473020Y880219D03*
X1471171Y883423D03*
X1474871D03*
X1476720Y886627D03*
X1469320D03*
X1461921Y880219D03*
X1471171Y877014D03*
X1476721Y880219D03*
X1474871Y877014D03*
X1469321Y880219D03*
X1467471Y877014D03*
X1463771D03*
Y870606D03*
X1471171D03*
X1461920Y873810D03*
X1467471Y870606D03*
X1469320Y873810D03*
X1474871Y870606D03*
X1476720Y873810D03*
X1465620Y880219D03*
X1467471Y883423D03*
X1473020Y880219D03*
X1474871Y883423D03*
X1463771D03*
X1471171D03*
X1473020Y873810D03*
X1465620D03*
X1476720Y899445D03*
X1469320D03*
Y893036D03*
X1467471Y896240D03*
X1473020Y893036D03*
X1471171Y896240D03*
X1467471Y902649D03*
X1474871D03*
Y889832D03*
X1465621Y893036D03*
X1476721D03*
X1474871Y896240D03*
X1471171Y889832D03*
X1467471D03*
X1463771D03*
X1473021Y899445D03*
X1465620D03*
X1476720D03*
X1461920D03*
X1469320D03*
Y893036D03*
X1473020D03*
X1461920D03*
X1467471Y896240D03*
X1463771D03*
X1471171D03*
X1461920Y886627D03*
X1469320D03*
X1476720D03*
X1473020D03*
X1465620D03*
X1476720Y912262D03*
Y905853D03*
X1469320Y912262D03*
X1467471Y909057D03*
Y915466D03*
X1474871Y909057D03*
X1473020Y905853D03*
X1471171Y915466D03*
X1476720Y918670D03*
X1469320D03*
X1461920Y905853D03*
X1473020Y912262D03*
X1471171Y909057D03*
X1465620Y912262D03*
Y905853D03*
X1471171Y902649D03*
X1469321Y905853D03*
X1474870Y915466D03*
X1461920Y912262D03*
X1463771Y909057D03*
X1469320Y912262D03*
X1467471Y909057D03*
X1476720Y912262D03*
X1474871Y909057D03*
Y902649D03*
X1463771D03*
X1467471D03*
X1463771Y915466D03*
X1476720Y905853D03*
X1471171Y915466D03*
X1473020Y905853D03*
X1467471Y915466D03*
X1476720Y931488D03*
Y925079D03*
X1467471Y921875D03*
Y928283D03*
X1469320Y931488D03*
X1474871Y921875D03*
Y928283D03*
X1473020Y925079D03*
X1467471Y934691D03*
X1471171D03*
X1461920Y925079D03*
X1471170Y928283D03*
X1469321Y925079D03*
X1465620D03*
Y918670D03*
X1473021D03*
X1471171Y921875D03*
X1473020Y931488D03*
X1465620D03*
X1476720D03*
X1474871Y921875D03*
X1476720Y918670D03*
X1474871Y928283D03*
X1473020Y925079D03*
X1476720D03*
X1467471Y921875D03*
X1469320Y918670D03*
X1461920Y931488D03*
X1467471Y928283D03*
X1469320Y931488D03*
X1463771Y928283D03*
Y921875D03*
X1461920Y918670D03*
X1476720Y937896D03*
Y944304D03*
X1467471Y947509D03*
Y941100D03*
X1469320Y937896D03*
X1474871Y941100D03*
X1473020Y944304D03*
X1474871Y947509D03*
X1469320Y950713D03*
X1476720D03*
X1461920Y944304D03*
X1474871Y934691D03*
X1473021Y937896D03*
X1471171Y941100D03*
X1469321Y944304D03*
X1465620D03*
Y937896D03*
X1471170Y947509D03*
X1474871D03*
Y941100D03*
X1476720Y937896D03*
X1473020Y944304D03*
X1476720D03*
X1463771Y947509D03*
X1467471D03*
X1463771Y941100D03*
X1461920Y937896D03*
X1467471Y941100D03*
X1469320Y937896D03*
X1463771Y934691D03*
X1471171D03*
X1467471D03*
Y966735D03*
Y960326D03*
X1469320Y957122D03*
X1467471Y953917D03*
X1474871Y960326D03*
X1476720Y957122D03*
X1474871Y966735D03*
X1473020Y963530D03*
X1471171Y953917D03*
X1474871D03*
X1473021Y957122D03*
X1471171Y960326D03*
X1465620Y957122D03*
Y950713D03*
X1473020D03*
X1461920Y963530D03*
X1476721D03*
X1471170Y966735D03*
X1469321Y963530D03*
X1465620D03*
X1476720Y950713D03*
X1463771Y966735D03*
X1467471D03*
X1474871D03*
X1473020Y963530D03*
X1461920Y950713D03*
X1469320D03*
X1467471Y960326D03*
X1469320Y957122D03*
X1463771Y960326D03*
X1461920Y957122D03*
X1476720D03*
X1474871Y960326D03*
X1471171Y953917D03*
X1463771D03*
X1467471D03*
X1476720Y982756D03*
Y976347D03*
Y969939D03*
X1467471Y979552D03*
X1469320Y976347D03*
X1467471Y973143D03*
X1469320Y969939D03*
X1473020Y982756D03*
X1474871Y979552D03*
X1471171Y973143D03*
X1473021Y976347D03*
X1473020Y969939D03*
X1465620Y976347D03*
Y969939D03*
X1474870Y973143D03*
X1471171Y979552D03*
X1461920Y982756D03*
X1469321D03*
X1465620D03*
X1463771Y979552D03*
X1461920Y976347D03*
X1467471Y979552D03*
X1469320Y976347D03*
X1476720Y982756D03*
X1473020D03*
X1474871Y979552D03*
X1476720Y976347D03*
X1471171Y973143D03*
X1463771D03*
X1467471D03*
X1461920Y969939D03*
X1469320D03*
X1476720D03*
X1464204Y999684D03*
X1467904D03*
X1475304D03*
X1477153Y1002888D03*
Y1009297D03*
X1467903Y1012501D03*
X1464204D03*
X1475304D03*
X1471604Y1006093D03*
X1469753Y1002888D03*
Y1009297D03*
X1473453Y1015705D03*
X1475303Y1006093D03*
X1473453Y1009297D03*
X1473454Y1002888D03*
X1471604Y999684D03*
X1466053Y1009297D03*
X1466054Y1002888D03*
X1467903Y1006093D03*
X1464204D03*
X1471603Y1012501D03*
X1477153Y1002888D03*
X1475304Y999684D03*
Y1012501D03*
X1477153Y1009297D03*
X1471604Y1006093D03*
X1462353Y1002888D03*
X1469753D03*
X1464204Y999684D03*
X1467904D03*
X1467903Y1012501D03*
X1469753Y1009297D03*
X1464204Y1012501D03*
X1462353Y1009297D03*
X1464204Y1018910D03*
X1467904D03*
X1464204Y1031727D03*
X1467904D03*
X1464204Y1025318D03*
X1467904D03*
X1475304Y1018910D03*
Y1031727D03*
X1477153Y1028523D03*
Y1022114D03*
X1469753Y1028523D03*
Y1022114D03*
X1471604Y1025318D03*
X1462353Y1015705D03*
X1473453Y1028523D03*
X1466053D03*
Y1022114D03*
Y1015705D03*
X1477154D03*
X1475303Y1025318D03*
X1473453Y1022114D03*
X1471604Y1018910D03*
X1469754Y1015705D03*
X1471603Y1031727D03*
X1473453Y1015705D03*
X1475304Y1031727D03*
X1477153Y1028523D03*
Y1022114D03*
X1475304Y1018910D03*
X1464204Y1031727D03*
X1462353Y1028523D03*
X1467904Y1031727D03*
X1469753Y1028523D03*
X1462353Y1022114D03*
X1464204Y1018910D03*
X1469753Y1022114D03*
X1467904Y1018910D03*
X1464204Y1025318D03*
X1471604D03*
X1467904D03*
X1477153Y1034931D03*
Y1041340D03*
Y1047749D03*
X1464204Y1038136D03*
X1467904D03*
X1464204Y1044544D03*
X1467904D03*
X1473453Y1034931D03*
X1475304Y1038136D03*
X1469753Y1047749D03*
Y1041340D03*
X1471604Y1044544D03*
X1462353Y1034931D03*
X1473454Y1041340D03*
X1466053D03*
Y1034931D03*
X1475303Y1044544D03*
X1471604Y1038136D03*
X1469754Y1034931D03*
X1466053Y1047749D03*
X1473453D03*
X1477153Y1041340D03*
X1475304Y1038136D03*
X1477153Y1047749D03*
Y1034931D03*
X1473453D03*
X1462353Y1047749D03*
X1469753D03*
X1462353Y1041340D03*
X1464204Y1038136D03*
X1469753Y1041340D03*
X1467904Y1038136D03*
X1464204Y1044544D03*
X1471604D03*
X1467904D03*
X1464204Y1050952D03*
X1467904D03*
X1464204Y1057361D03*
X1467904D03*
X1464204Y1063770D03*
X1467904D03*
X1475304Y1050952D03*
X1477153Y1060565D03*
X1475304Y1057361D03*
X1477153Y1054157D03*
X1473453D03*
X1469753Y1060565D03*
X1471604Y1063770D03*
X1462353Y1054157D03*
X1473453Y1060565D03*
X1471604Y1057361D03*
X1466053Y1060565D03*
Y1054157D03*
X1471603Y1050952D03*
X1469753Y1054157D03*
X1475304Y1063770D03*
X1477153Y1060565D03*
X1475304Y1057361D03*
Y1050952D03*
X1477153Y1054157D03*
X1473453D03*
X1462353Y1060565D03*
X1464204Y1057361D03*
X1469753Y1060565D03*
X1467904Y1057361D03*
X1464204Y1050952D03*
X1467904D03*
X1464204Y1063770D03*
X1471604D03*
X1467904D03*
X1477153Y1066974D03*
Y1079791D03*
Y1073383D03*
X1464204Y1076587D03*
X1467904D03*
X1464204Y1070178D03*
X1467904D03*
X1469753Y1066974D03*
X1475304Y1070178D03*
Y1076587D03*
X1473453Y1073383D03*
X1469753Y1079791D03*
X1462353Y1073383D03*
X1471604Y1076587D03*
X1469754Y1073383D03*
X1466053Y1066974D03*
X1473453D03*
X1471603Y1070178D03*
X1466053Y1073383D03*
X1473454Y1079791D03*
X1466053D03*
X1475304Y1070178D03*
X1477153Y1066974D03*
Y1079791D03*
X1475304Y1076587D03*
X1473453Y1073383D03*
X1477153D03*
X1462353Y1079791D03*
X1464204Y1076587D03*
X1469753Y1079791D03*
X1467904Y1076587D03*
X1464204Y1070178D03*
X1462353Y1066974D03*
X1467904Y1070178D03*
X1469753Y1066974D03*
X1464204Y1082995D03*
X1467904D03*
Y1089404D03*
X1464204D03*
X1471604Y1082995D03*
X1475304Y1089404D03*
X1477153Y1086200D03*
X1473453Y1092608D03*
X1477153D03*
X1469753Y1086200D03*
X1462353Y1092608D03*
X1475303Y1082995D03*
X1473453Y1086200D03*
X1469754Y1092608D03*
X1466053D03*
Y1086200D03*
X1471603Y1089404D03*
X1475304Y1095813D03*
X1471604D03*
X1467904D03*
Y1089404D03*
X1469753Y1086200D03*
X1475304Y1089404D03*
X1477153Y1086200D03*
X1464204Y1089404D03*
X1462353Y1086200D03*
X1473453Y1092608D03*
X1471604Y1082995D03*
X1477153Y1092608D03*
X1464204Y1082995D03*
X1467904D03*
X1464204Y1095813D03*
X1462353Y1105426D03*
X1462354Y1099017D03*
X1475303Y1108630D03*
Y1102221D03*
X1473454Y1105426D03*
X1469753D03*
X1467904Y1102221D03*
X1464203D03*
X1473454Y1111834D03*
X1466053D03*
Y1099017D03*
X1471604Y1102221D03*
X1477153Y1099017D03*
X1469753D03*
X1473453D03*
X1471604Y1108630D03*
X1466053Y1105426D03*
X1462353Y1111834D03*
X1469753D03*
X1467904Y1108630D03*
X1464204D03*
X1477154Y1105426D03*
Y1111833D03*
X1466053Y1124651D03*
X1464204Y1127856D03*
X1467904Y1121447D03*
X1477153Y1124651D03*
X1473453D03*
X1469753D03*
X1475304Y1121447D03*
X1471604Y1127856D03*
X1479004D03*
X1462353Y1118243D03*
X1477153D03*
X1475303Y1115039D03*
X1473453Y1118243D03*
X1471604Y1121447D03*
X1469754Y1118243D03*
X1466053D03*
X1475303Y1127856D03*
X1467903D03*
X1467904Y1115039D03*
X1471604D03*
X1464204Y1127856D03*
X1475304Y1121447D03*
X1471604Y1127856D03*
X1467904Y1121447D03*
X1466053Y1124651D03*
X1462353D03*
X1477153D03*
X1473453D03*
X1469753D03*
X1464204Y1115039D03*
Y1121447D03*
X1479003Y1140973D03*
X1477154Y1137469D03*
X1467904Y1134264D03*
X1466054Y1137469D03*
X1464203Y1140973D03*
X1475304Y1134264D03*
X1469754Y1137469D03*
X1473454D03*
X1471603Y1140973D03*
X1462353Y1131060D03*
X1477153D03*
X1475303Y1140973D03*
X1473453Y1131060D03*
X1469753D03*
X1466053D03*
X1467903Y1140973D03*
X1469754Y1137469D03*
X1464203Y1140973D03*
X1477154Y1137469D03*
X1471603Y1140973D03*
X1467904Y1134264D03*
X1466054Y1137469D03*
X1462354D03*
X1475304Y1134264D03*
X1473454Y1137469D03*
X1471604Y1134264D03*
X1464204D03*
X1472155Y1578182D03*
X1467895D03*
X1472155Y1590094D03*
X1467895D03*
X1477455Y1602380D03*
Y1614292D03*
X1473195D03*
Y1602380D03*
X1465395D03*
Y1614292D03*
X1480420Y854584D03*
X1487820D03*
X1495220D03*
X1491521Y841467D03*
X1484121D03*
X1478571Y851380D03*
X1482271D03*
X1489671D03*
X1485971D03*
X1493371D03*
X1487820Y848176D03*
X1480420D03*
X1484120Y860993D03*
X1482271Y857789D03*
X1485971D03*
X1480420Y867401D03*
X1491520Y860993D03*
X1489671Y857789D03*
X1493371D03*
X1487820Y867401D03*
X1495220D03*
X1493371Y870606D03*
X1482271D03*
X1485971D03*
X1489671D03*
X1478571Y864197D03*
X1491521Y854584D03*
X1489671Y864197D03*
X1485971D03*
X1482271D03*
X1493371D03*
X1491521Y867401D03*
X1484121D03*
Y854584D03*
X1487820Y867401D03*
X1480420D03*
X1487820Y860993D03*
X1480420D03*
X1491520D03*
X1489671Y857789D03*
X1484120Y860993D03*
X1482271Y857789D03*
X1493371D03*
X1487820Y854584D03*
X1485971Y857789D03*
X1480420Y854584D03*
X1478571Y857789D03*
X1495220Y880219D03*
X1493371Y883423D03*
X1484120Y873810D03*
X1480420Y880219D03*
X1485971Y883423D03*
X1482271D03*
X1491520Y873810D03*
X1487820Y880219D03*
X1489671Y883423D03*
X1484120Y886627D03*
X1491520D03*
X1478571Y877014D03*
X1491521Y880219D03*
X1485971Y877014D03*
X1484121Y880219D03*
X1489671Y877014D03*
X1482271D03*
X1493371D03*
Y870606D03*
X1478571D03*
X1485971D03*
X1489671D03*
X1491520Y873810D03*
X1482271Y870606D03*
X1484120Y873810D03*
X1487820Y880219D03*
X1489671Y883423D03*
X1480420Y880219D03*
X1482271Y883423D03*
X1485971D03*
X1493371D03*
X1478571D03*
X1487820Y873810D03*
X1480420D03*
X1484120Y893036D03*
X1485971Y896240D03*
X1480420Y899445D03*
X1487820D03*
Y893036D03*
X1493371Y896240D03*
X1489671D03*
X1495220Y899445D03*
Y893036D03*
X1493371Y902649D03*
X1482271D03*
X1489671D03*
X1478570Y896240D03*
X1478571Y889832D03*
X1491521Y893036D03*
X1482271Y889832D03*
X1489671D03*
X1485971D03*
X1482270Y896240D03*
X1480421Y893036D03*
X1493371Y889832D03*
X1491520Y899445D03*
X1484120D03*
X1487820D03*
Y893036D03*
X1484120D03*
X1485971Y896240D03*
X1493371D03*
X1489671D03*
X1480420Y899445D03*
X1491520Y886627D03*
X1484120D03*
X1480420D03*
X1487820D03*
X1495220Y912262D03*
X1493371Y909057D03*
Y915466D03*
X1485971D03*
X1480420Y912262D03*
X1482271Y909057D03*
X1484120Y905853D03*
X1480420D03*
X1487820Y912262D03*
X1489671Y909057D03*
Y915466D03*
X1480420Y918670D03*
X1487820D03*
X1495220D03*
X1478571Y909057D03*
Y902649D03*
X1491520Y912262D03*
X1487820Y905853D03*
X1485971Y909057D03*
X1484121Y912262D03*
X1491520Y905853D03*
X1485970Y902649D03*
X1478571Y915466D03*
X1482271D03*
X1489671Y902649D03*
X1493371D03*
X1487820Y912262D03*
X1489671Y909057D03*
X1493371D03*
X1489671Y915466D03*
X1485971D03*
X1493371D03*
X1480420Y912262D03*
X1482271Y909057D03*
Y902649D03*
X1484120Y905853D03*
X1480420D03*
X1482271Y928283D03*
Y921875D03*
X1480420Y931488D03*
Y925079D03*
X1484120D03*
X1487820Y931488D03*
X1489671Y928283D03*
X1493371D03*
X1489671Y921875D03*
X1493371D03*
X1495220Y931488D03*
X1493371Y934691D03*
X1485971D03*
X1489671D03*
X1478571Y928283D03*
Y921875D03*
X1491520Y925079D03*
Y918670D03*
X1487820Y925079D03*
X1485971Y928283D03*
X1485970Y921875D03*
X1484120Y918670D03*
X1491520Y931488D03*
X1484121D03*
X1487820D03*
X1489671Y928283D03*
X1493371D03*
X1482271D03*
Y921875D03*
X1480420Y918670D03*
X1489671Y921875D03*
X1487820Y918670D03*
X1493371Y921875D03*
X1480420Y931488D03*
Y925079D03*
X1484120D03*
X1495220Y937896D03*
X1493371Y941100D03*
Y947509D03*
X1480420Y937896D03*
X1487820D03*
X1482271Y941100D03*
X1484120Y944304D03*
X1480420D03*
X1482271Y947509D03*
X1489671Y941100D03*
Y947509D03*
X1480420Y950713D03*
X1487820D03*
X1495220D03*
X1478571Y941100D03*
Y934691D03*
X1491520Y944304D03*
Y937896D03*
X1487820Y944304D03*
X1485970Y941100D03*
X1484120Y937896D03*
X1482271Y934691D03*
X1478571Y947509D03*
X1485971D03*
X1489671Y941100D03*
X1487820Y937896D03*
X1493371Y941100D03*
X1489671Y934691D03*
X1485971D03*
X1493371D03*
X1489671Y947509D03*
X1493371D03*
X1482271D03*
Y941100D03*
X1480420Y937896D03*
X1484120Y944304D03*
X1480420D03*
X1482271Y960326D03*
X1485971Y953917D03*
X1480420Y957122D03*
X1482271Y966735D03*
X1484120Y963530D03*
X1487820Y957122D03*
X1489671Y953917D03*
X1493371D03*
X1489671Y960326D03*
X1493371D03*
Y966735D03*
X1489671D03*
X1495220Y957122D03*
X1478571Y960326D03*
Y953917D03*
X1491520Y957122D03*
Y950713D03*
X1485970Y960326D03*
X1484120Y957122D03*
X1482271Y953917D03*
X1484121Y950713D03*
X1478570Y966735D03*
X1491520Y963530D03*
X1485971Y966735D03*
X1487820Y963530D03*
X1480420D03*
X1487820Y950713D03*
X1489671Y960326D03*
X1487820Y957122D03*
X1493371Y960326D03*
Y966735D03*
X1489671D03*
X1480420Y950713D03*
X1489671Y953917D03*
X1493371D03*
X1485971D03*
X1482271Y966735D03*
X1480420Y957122D03*
X1482271Y960326D03*
X1484120Y963530D03*
X1495220Y976347D03*
Y969939D03*
X1493371Y979552D03*
X1484120Y982756D03*
X1480420D03*
Y976347D03*
X1482271Y979552D03*
X1485971Y973143D03*
X1480420Y969939D03*
X1487820Y976347D03*
Y969939D03*
X1489671Y979552D03*
X1478571D03*
Y973143D03*
X1491521Y976347D03*
X1491520Y969939D03*
X1484120Y976347D03*
X1484121Y969939D03*
X1489671Y973143D03*
X1485970Y979552D03*
X1482271Y973143D03*
X1493370D03*
X1491520Y982756D03*
X1487820D03*
X1484120D03*
X1480420D03*
Y976347D03*
X1482271Y979552D03*
X1489671D03*
X1493371D03*
X1487820Y976347D03*
X1485971Y973143D03*
X1487820Y969939D03*
X1480420D03*
X1493803Y999684D03*
X1482703D03*
X1490104D03*
X1495655Y1002888D03*
X1495653Y1009297D03*
X1493804Y1006093D03*
Y1012501D03*
X1480853Y1002888D03*
X1482704Y1012501D03*
X1480853Y1009297D03*
X1488253Y1002888D03*
X1490104Y1006093D03*
X1486404D03*
X1490104Y1012501D03*
X1488253Y1009297D03*
X1484553Y1015705D03*
X1479004Y999684D03*
X1486403D03*
X1484553Y1002888D03*
X1482704Y1006093D03*
X1479003Y1012501D03*
X1486404D03*
X1491953Y1009297D03*
Y1002888D03*
X1484554Y1009297D03*
X1479004Y1006093D03*
X1493804D03*
X1490104D03*
X1486404D03*
X1493804Y1012501D03*
X1480853Y1002888D03*
X1482703Y999684D03*
X1490104Y1012501D03*
X1488253Y1009297D03*
X1482704Y1012501D03*
X1480853Y1009297D03*
X1493803Y999684D03*
X1488253Y1002888D03*
X1490104Y999684D03*
X1482704Y1018910D03*
Y1031727D03*
X1480853Y1028523D03*
Y1022114D03*
X1490104Y1018910D03*
X1493804D03*
X1490104Y1031727D03*
X1488253Y1028523D03*
X1493804Y1031727D03*
X1488253Y1022114D03*
X1490104Y1025318D03*
X1486404D03*
X1493804D03*
X1495653Y1028523D03*
Y1022114D03*
X1479004Y1025318D03*
Y1018910D03*
X1491953Y1028523D03*
Y1022114D03*
X1484553Y1028523D03*
X1486403Y1018910D03*
X1484553Y1022114D03*
X1482704Y1025318D03*
X1480853Y1015705D03*
X1479004Y1031727D03*
X1486404D03*
X1488253Y1015705D03*
X1491953D03*
X1490104Y1031727D03*
X1488253Y1028523D03*
X1493804Y1031727D03*
X1488253Y1022114D03*
X1490104Y1018910D03*
X1493804D03*
X1490104Y1025318D03*
X1486404D03*
X1493804D03*
X1484553Y1015705D03*
X1482704Y1031727D03*
X1480853Y1028523D03*
Y1022114D03*
X1482704Y1018910D03*
X1495653Y1047749D03*
Y1041340D03*
X1493804Y1044544D03*
Y1038136D03*
X1484553Y1034931D03*
X1480853D03*
Y1041340D03*
X1482704Y1038136D03*
X1480853Y1047749D03*
X1486404Y1044544D03*
X1490104D03*
X1488253Y1047749D03*
Y1041340D03*
X1490104Y1038136D03*
X1479004Y1044544D03*
Y1038136D03*
X1491953Y1034931D03*
Y1041340D03*
X1488253Y1034931D03*
X1486403Y1038136D03*
X1484553Y1041340D03*
X1482704Y1044544D03*
X1491953Y1047749D03*
X1484553D03*
X1480853Y1041340D03*
X1482704Y1038136D03*
X1488253Y1047749D03*
Y1041340D03*
X1490104Y1038136D03*
X1493804D03*
X1480853Y1047749D03*
X1486404Y1044544D03*
X1484553Y1034931D03*
X1490104Y1044544D03*
X1493804D03*
X1480853Y1034931D03*
X1482704Y1050952D03*
X1480853Y1060565D03*
X1482704Y1057361D03*
X1484553Y1054157D03*
X1480853D03*
X1490104Y1050952D03*
X1493804D03*
X1488253Y1060565D03*
X1490104Y1057361D03*
X1493804D03*
X1486404Y1063770D03*
X1490104D03*
X1493804D03*
X1495653Y1060565D03*
X1479004Y1057361D03*
Y1050952D03*
X1491953Y1054157D03*
X1486404Y1057361D03*
X1484553Y1060565D03*
X1488253Y1054157D03*
X1486404Y1050952D03*
X1491953Y1060565D03*
X1479004Y1063770D03*
X1482704D03*
X1488253Y1060565D03*
X1490104Y1057361D03*
X1493804D03*
X1486404Y1063770D03*
X1490104D03*
X1493804D03*
X1490104Y1050952D03*
X1493804D03*
X1480853Y1060565D03*
X1482704Y1057361D03*
Y1050952D03*
X1484553Y1054157D03*
X1480853D03*
X1495653Y1066974D03*
Y1079791D03*
X1493804Y1076587D03*
Y1070178D03*
X1480853Y1066974D03*
X1482704Y1070178D03*
X1484553Y1073383D03*
X1480853D03*
Y1079791D03*
X1482704Y1076587D03*
X1488253Y1066974D03*
Y1079791D03*
X1490104Y1076587D03*
Y1070178D03*
X1479004Y1076587D03*
Y1070178D03*
X1486404Y1076587D03*
Y1070178D03*
X1488253Y1073383D03*
X1484553Y1066974D03*
X1491953Y1073383D03*
Y1066974D03*
X1484553Y1079791D03*
X1491953D03*
X1493804Y1070178D03*
X1490104D03*
X1488253Y1066974D03*
X1480853Y1079791D03*
X1482704Y1076587D03*
Y1070178D03*
X1480853Y1066974D03*
X1488253Y1079791D03*
X1490104Y1076587D03*
X1493804D03*
X1484553Y1073383D03*
X1480853D03*
X1482703Y1095813D03*
X1482704Y1089404D03*
X1480853Y1086200D03*
X1484553Y1092608D03*
X1480853D03*
X1490104Y1082995D03*
X1486404D03*
X1493804D03*
X1490104Y1089404D03*
X1488253Y1086200D03*
X1493804Y1089404D03*
X1486404Y1095813D03*
X1495653Y1086200D03*
X1491953Y1099017D03*
X1479004Y1089404D03*
Y1082995D03*
X1488254Y1092608D03*
X1486404Y1089404D03*
X1484554Y1086200D03*
X1482704Y1082995D03*
X1491954Y1092608D03*
X1491953Y1086200D03*
X1479004Y1095813D03*
X1490103D03*
X1493804D03*
X1490104Y1089404D03*
X1488253Y1086200D03*
X1493804Y1089404D03*
X1490104Y1082995D03*
X1486404D03*
X1493804D03*
X1486404Y1095813D03*
X1482703D03*
X1482704Y1089404D03*
X1480853Y1086200D03*
X1484553Y1092608D03*
X1480853D03*
X1493804Y1102221D03*
X1479004D03*
X1490104Y1108630D03*
Y1102221D03*
X1488254Y1099017D03*
X1484553D03*
X1482704Y1108630D03*
X1480853Y1099017D03*
X1491953Y1105426D03*
Y1111834D03*
X1493804Y1108630D03*
Y1102221D03*
X1491953Y1099017D03*
X1486404Y1102221D03*
X1479003Y1108629D03*
X1488254Y1105426D03*
X1484554Y1111833D03*
X1482703Y1102220D03*
X1480854Y1111833D03*
Y1105426D03*
X1486403Y1108630D03*
X1488254Y1111833D03*
X1484554Y1105426D03*
X1482704Y1121447D03*
X1484553Y1124651D03*
X1480853D03*
X1491953D03*
X1488253D03*
X1493804Y1127856D03*
X1490104Y1121447D03*
X1486404Y1127856D03*
X1495653Y1124651D03*
X1490103Y1115039D03*
X1488253Y1118243D03*
X1484553D03*
X1480853D03*
X1486403Y1115039D03*
X1491953Y1118243D03*
X1490103Y1127856D03*
X1482703D03*
X1493804Y1115039D03*
Y1127856D03*
X1490104Y1121447D03*
X1486404Y1127856D03*
X1482704Y1121447D03*
X1479004Y1127856D03*
X1491953Y1124651D03*
X1488253D03*
X1484553D03*
X1480853D03*
X1479004Y1115039D03*
Y1121447D03*
X1493804D03*
X1486404D03*
X1482703Y1115038D03*
X1495654Y1137469D03*
X1491954D03*
X1493803Y1140973D03*
X1482704Y1134264D03*
X1484554Y1137469D03*
X1480854D03*
X1490104Y1134264D03*
X1488254Y1137469D03*
X1486403Y1140973D03*
X1490103D03*
X1488253Y1131060D03*
X1484553D03*
X1480853D03*
X1482703Y1140973D03*
X1491953Y1131060D03*
X1493803Y1140973D03*
X1490104Y1134264D03*
X1488254Y1137469D03*
X1482704Y1134264D03*
X1480854Y1137469D03*
X1491954D03*
X1486403Y1140973D03*
X1484554Y1137469D03*
X1479003Y1140973D03*
X1479004Y1134264D03*
X1493804D03*
X1486404D03*
X1492015Y1578182D03*
X1484215D03*
X1479955D03*
X1492015Y1590094D03*
X1484215D03*
X1479955D03*
X1489515Y1614292D03*
Y1602380D03*
X1485255D03*
Y1614292D03*
X1502620Y854584D03*
X1510021D03*
X1504471Y844671D03*
X1498921Y841467D03*
X1508171Y851380D03*
X1504471D03*
X1500771D03*
X1497071D03*
X1495220Y848176D03*
X1497071Y857789D03*
X1500771D03*
X1502621Y867401D03*
X1498920Y860993D03*
X1508171Y864197D03*
X1504471Y857789D03*
X1511871Y864197D03*
Y857789D03*
X1508171Y870606D03*
X1500771D03*
X1497071D03*
X1504471D03*
Y864197D03*
X1500771D03*
X1508170Y857789D03*
X1497071Y864197D03*
X1506321Y860993D03*
Y854584D03*
X1498921D03*
X1510021Y860993D03*
X1506320Y867401D03*
X1498921D03*
X1510021D03*
X1508171Y864197D03*
X1510021Y854584D03*
X1495220Y867401D03*
X1502621D03*
X1495220Y860993D03*
X1502621D03*
X1504471Y857789D03*
X1498920Y860993D03*
X1497071Y857789D03*
X1502620Y854584D03*
X1500771Y857789D03*
X1495220Y854584D03*
X1511871Y877014D03*
X1498920Y873810D03*
X1502621Y880219D03*
X1497071Y883423D03*
X1500771D03*
X1506321Y873810D03*
X1504471Y883423D03*
X1498920Y886627D03*
X1506321D03*
X1504471Y877014D03*
X1498921Y880219D03*
X1508171Y877014D03*
X1497071D03*
X1506321Y880219D03*
X1500771Y877014D03*
X1510021Y880219D03*
Y873810D03*
X1508170Y883423D03*
X1500771Y870606D03*
X1508171D03*
X1497071D03*
X1498920Y873810D03*
X1504471Y870606D03*
X1506321Y873810D03*
X1495220Y880219D03*
X1497071Y883423D03*
X1502621Y880219D03*
X1504471Y883423D03*
X1500771D03*
X1495220Y873810D03*
X1502621D03*
Y899445D03*
X1498920Y893036D03*
X1497071Y896240D03*
X1506320Y899445D03*
X1508171Y902649D03*
X1500771D03*
X1508171Y889832D03*
X1504471Y896240D03*
Y889832D03*
X1500771D03*
X1508171Y896240D03*
X1502621Y893036D03*
X1500771Y896240D03*
X1497071Y889832D03*
X1510021Y893036D03*
X1498921Y899445D03*
X1510021D03*
X1502621D03*
X1506320D03*
X1495220D03*
Y893036D03*
X1498920D03*
X1497071Y896240D03*
X1498920Y886627D03*
X1506321D03*
X1495220D03*
X1502621D03*
X1510021D03*
X1508171Y909057D03*
X1510021Y905853D03*
X1502621Y912262D03*
X1500771Y909057D03*
X1502621Y905853D03*
X1498920D03*
X1497071Y915466D03*
X1506321Y912262D03*
Y905853D03*
X1502621Y918670D03*
X1506321D03*
X1495221Y905853D03*
X1504471Y902649D03*
X1498920Y912262D03*
X1497070Y909057D03*
X1497071Y902649D03*
X1508171Y915466D03*
X1504471D03*
X1500770D03*
X1504471Y909057D03*
X1510021Y912262D03*
X1506321D03*
X1508171Y909057D03*
X1500771Y902649D03*
X1508171D03*
X1502621Y912262D03*
X1500771Y909057D03*
X1502621Y905853D03*
X1510021D03*
X1498920D03*
X1506321D03*
X1495220Y912262D03*
X1497071Y915466D03*
X1502621Y931488D03*
X1500771Y928283D03*
Y921875D03*
X1502621Y925079D03*
X1498920D03*
X1506321Y931488D03*
X1508171Y928283D03*
Y921875D03*
X1510021Y925079D03*
X1506321D03*
X1497071Y934691D03*
X1495221Y925079D03*
X1504471Y921875D03*
X1497070Y928283D03*
X1498921Y918670D03*
X1497071Y921875D03*
X1498920Y931488D03*
X1504471Y928283D03*
X1510021Y918670D03*
X1510020Y931488D03*
X1502621D03*
X1500771Y928283D03*
X1506321Y931488D03*
X1508171Y928283D03*
X1500771Y921875D03*
X1502621Y918670D03*
X1508171Y921875D03*
X1506321Y918670D03*
X1502621Y925079D03*
X1510021D03*
X1498920D03*
X1506321D03*
X1495220Y931488D03*
Y918670D03*
X1508171Y941100D03*
Y947509D03*
X1510021Y944304D03*
X1502621Y937896D03*
X1506321D03*
X1500771Y947509D03*
X1502621Y944304D03*
X1498920D03*
X1500771Y941100D03*
X1506320Y944304D03*
X1502621Y950713D03*
X1506320D03*
X1495221Y944304D03*
X1504471Y941100D03*
Y934691D03*
X1500770D03*
X1498921Y937896D03*
X1497071Y941100D03*
X1497070Y947509D03*
X1508171Y934691D03*
X1510021Y937896D03*
X1504471Y947509D03*
X1500771Y941100D03*
X1502621Y937896D03*
X1508171Y941100D03*
X1506321Y937896D03*
X1500771Y947509D03*
X1508171D03*
X1495220Y937896D03*
X1510021Y944304D03*
X1497071Y934691D03*
X1502621Y944304D03*
X1506320D03*
X1498920D03*
X1497071Y953917D03*
X1500771Y966735D03*
X1498920Y963530D03*
X1500771Y960326D03*
X1502621Y957122D03*
X1508171Y966735D03*
Y960326D03*
X1506320Y957122D03*
X1510021Y963530D03*
X1504471Y960326D03*
Y953917D03*
X1500771D03*
X1498921Y957122D03*
X1497071Y960326D03*
X1498920Y950713D03*
X1495221Y963530D03*
X1497070Y966735D03*
X1502621Y963530D03*
X1510021Y957122D03*
X1508171Y953917D03*
X1510021Y950713D03*
X1506320Y963530D03*
X1504471Y966735D03*
X1500771D03*
X1508171D03*
X1498920Y963530D03*
X1502621Y950713D03*
X1506320D03*
X1508171Y960326D03*
X1506320Y957122D03*
X1500771Y960326D03*
X1502621Y957122D03*
X1510021Y963530D03*
X1495220Y950713D03*
Y957122D03*
X1497071Y953917D03*
X1502621Y969939D03*
X1497071Y973143D03*
X1506321Y969939D03*
X1504471Y979552D03*
Y973143D03*
X1498921Y976347D03*
X1498920Y969939D03*
X1500770Y973143D03*
X1497071Y979552D03*
X1510021Y976347D03*
X1495221Y982756D03*
X1510043Y980606D03*
X1510021Y969939D03*
X1508171Y973143D03*
X1502621Y969939D03*
X1506321D03*
X1495220Y976347D03*
Y969939D03*
X1497071Y973143D03*
X1508603Y999684D03*
X1501204D03*
X1508603Y1012501D03*
X1497504Y1006093D03*
X1501204Y1012501D03*
X1506753Y1002888D03*
X1503053D03*
Y1009297D03*
X1506753D03*
X1499353Y1015705D03*
X1510453D03*
X1497503Y1012501D03*
Y999684D03*
X1504904Y1006093D03*
Y999684D03*
X1501203Y1006093D03*
X1499353Y1009297D03*
X1499354Y1002888D03*
X1510453Y1009297D03*
Y1002888D03*
X1508603Y1006093D03*
X1504903Y1012501D03*
X1497504Y1006093D03*
X1501204Y1012501D03*
X1508603D03*
X1503053Y1009297D03*
X1506753D03*
X1495653D03*
X1495655Y1002888D03*
X1506753D03*
X1508603Y999684D03*
X1503053Y1002888D03*
X1501204Y999684D03*
Y1018910D03*
Y1031727D03*
X1497504Y1025318D03*
X1508603Y1018910D03*
X1503053Y1028523D03*
X1508603Y1031727D03*
X1506753Y1028523D03*
Y1022114D03*
X1503053D03*
X1504904Y1025318D03*
X1499353Y1028523D03*
X1501203Y1025318D03*
X1504904Y1031727D03*
X1497503D03*
X1495654Y1015705D03*
X1497504Y1018910D03*
X1499353Y1022114D03*
X1503054Y1015705D03*
X1504904Y1018910D03*
X1506753Y1015705D03*
X1510453Y1028523D03*
X1510452Y1022114D03*
X1508603Y1025318D03*
X1499353Y1015705D03*
X1510453D03*
X1501204Y1031727D03*
X1503053Y1028523D03*
X1508603Y1031727D03*
X1506753Y1028523D03*
Y1022114D03*
X1508603Y1018910D03*
X1503053Y1022114D03*
X1501204Y1018910D03*
X1495653Y1028523D03*
Y1022114D03*
X1497504Y1025318D03*
X1510453Y1034931D03*
X1508603Y1038136D03*
X1499353Y1034931D03*
X1497504Y1044544D03*
X1501204Y1038136D03*
X1503053Y1034931D03*
X1506753D03*
X1503053Y1041340D03*
X1506753D03*
X1503053Y1047749D03*
X1506753D03*
X1504904Y1044544D03*
X1501203D03*
X1499354Y1041340D03*
X1497504Y1038136D03*
X1495654Y1034931D03*
X1508604Y1044544D03*
X1499353Y1047749D03*
X1504904Y1038136D03*
X1510453Y1041340D03*
Y1047749D03*
X1503053Y1041340D03*
X1501204Y1038136D03*
X1506753Y1041340D03*
X1508603Y1038136D03*
X1503053Y1047749D03*
X1506753D03*
X1503053Y1034931D03*
X1510453D03*
X1499353D03*
X1506753D03*
X1495653Y1047749D03*
Y1041340D03*
X1497504Y1044544D03*
X1501203Y1050952D03*
X1501204Y1057361D03*
X1499353Y1054157D03*
X1497504Y1063770D03*
X1508604Y1050953D03*
X1510453Y1054157D03*
X1503053D03*
X1506753D03*
X1503053Y1060565D03*
X1506753D03*
X1508604Y1057361D03*
X1504904D03*
Y1050952D03*
X1499354Y1060565D03*
X1497504Y1057361D03*
X1497503Y1050952D03*
X1495654Y1054157D03*
X1504904Y1063770D03*
X1501203D03*
X1510453Y1060565D03*
X1508604Y1063770D03*
X1495653Y1060565D03*
X1503053D03*
X1501204Y1057361D03*
X1506753Y1060565D03*
X1508604Y1057361D03*
X1501203Y1050952D03*
X1508604Y1050953D03*
X1499353Y1054157D03*
X1497504Y1063770D03*
X1510453Y1054157D03*
X1503053D03*
X1506753D03*
X1508604Y1076587D03*
Y1070178D03*
X1510453Y1073383D03*
X1501204Y1070178D03*
Y1076587D03*
X1499353Y1073383D03*
X1503053Y1066974D03*
X1506753D03*
Y1079791D03*
X1503053D03*
Y1073383D03*
X1506753D03*
X1504904Y1076587D03*
Y1070178D03*
X1497504Y1076587D03*
X1497503Y1070178D03*
X1495654Y1073383D03*
X1499353Y1066974D03*
X1499354Y1079791D03*
X1510453Y1066974D03*
Y1079791D03*
X1506753D03*
X1508604Y1076587D03*
X1501204Y1070178D03*
X1503053Y1066974D03*
X1508604Y1070178D03*
X1506753Y1066974D03*
X1503053Y1079791D03*
X1501204Y1076587D03*
X1499353Y1073383D03*
X1510453D03*
X1503053D03*
X1506753D03*
X1495653Y1066974D03*
Y1079791D03*
X1497504Y1082995D03*
Y1095813D03*
X1501204D03*
Y1089404D03*
X1499353Y1092608D03*
X1508603Y1095813D03*
X1503053Y1086200D03*
X1508604Y1089404D03*
X1506753Y1086200D03*
X1503053Y1092608D03*
X1510452D03*
X1506753D03*
Y1099017D03*
X1499353Y1086200D03*
X1497503Y1089404D03*
X1495653Y1092608D03*
X1504904Y1089404D03*
Y1082995D03*
X1501203D03*
X1508604Y1082996D03*
X1510453Y1086200D03*
X1504903Y1095813D03*
X1497504D03*
X1508603D03*
X1501204D03*
Y1089404D03*
X1503053Y1086200D03*
X1508604Y1089404D03*
X1506753Y1086200D03*
X1503053Y1092608D03*
X1510452D03*
X1499353D03*
X1506753D03*
X1495653Y1086200D03*
X1497504Y1082995D03*
X1503053Y1105426D03*
X1497503Y1102221D03*
X1495653Y1105426D03*
X1495654Y1099017D03*
X1508603Y1108630D03*
X1506754Y1111834D03*
X1499353D03*
X1503053Y1099017D03*
X1510453D03*
X1508602Y1102221D03*
X1497504Y1108630D03*
X1501204D03*
X1510453Y1111834D03*
X1499353Y1105426D03*
X1510453D03*
X1504904Y1108630D03*
X1495653Y1111834D03*
X1503053D03*
X1506753Y1099017D03*
Y1105426D03*
X1504904Y1102221D03*
X1501204D03*
X1499354Y1099017D03*
X1499353Y1124651D03*
X1501204Y1127856D03*
X1497504Y1121447D03*
X1503053Y1124651D03*
X1506753D03*
Y1118243D03*
X1504904Y1121447D03*
X1499353Y1118243D03*
X1497503Y1115039D03*
X1495653Y1118243D03*
X1508603Y1115039D03*
X1504904Y1127856D03*
X1497503D03*
X1501204Y1115039D03*
X1504904D03*
X1503053Y1124651D03*
X1497504Y1121447D03*
X1501204Y1127856D03*
X1499353Y1124651D03*
X1495653D03*
X1503053Y1118243D03*
X1510453D03*
X1501204Y1121447D03*
X1508603Y1121446D03*
X1510453Y1124650D03*
X1508603Y1127855D03*
X1508604Y1134264D03*
X1510454Y1137469D03*
X1497504Y1134264D03*
X1499354Y1137469D03*
X1501203Y1140973D03*
X1503054Y1137469D03*
X1506754D03*
X1506753Y1131060D03*
X1503053D03*
X1499353D03*
X1495653D03*
X1504904Y1134264D03*
X1497503Y1140973D03*
X1510453Y1131060D03*
X1508604Y1134264D03*
X1501203Y1140973D03*
X1499354Y1137469D03*
X1510454D03*
X1503054D03*
X1497504Y1134264D03*
X1495654Y1137469D03*
X1501204Y1134264D03*
X1508603Y1140973D03*
X1504903D03*
X1508335Y1578182D03*
X1496275D03*
X1504075D03*
X1508335Y1590094D03*
X1496275D03*
X1504075D03*
X1501575Y1614292D03*
Y1602380D03*
X1509375D03*
Y1614292D03*
X1497315Y1602380D03*
Y1614292D03*
X1505315Y1675383D03*
Y1679920D03*
Y1684454D03*
Y1689556D03*
Y1694093D03*
Y1698627D03*
Y1703729D03*
Y1708266D03*
Y1712800D03*
Y1726974D03*
Y1722440D03*
Y1717903D03*
X1519271Y851380D03*
X1515571D03*
X1517421Y854584D03*
X1511871Y844671D03*
X1513722Y848176D03*
X1511871Y851380D03*
X1519271D03*
X1515571D03*
X1519270Y864197D03*
X1519271Y857789D03*
X1515571D03*
X1517421Y860993D03*
X1522970Y864197D03*
X1515571Y870606D03*
X1519271D03*
X1521121Y860993D03*
Y854584D03*
X1515570Y864197D03*
X1513721Y854584D03*
Y860993D03*
X1521121Y867401D03*
X1517421D03*
X1513721D03*
X1511871Y864197D03*
X1519270D03*
X1522970D03*
X1511871Y857789D03*
X1519271D03*
X1515571D03*
X1517421Y860993D03*
Y854584D03*
X1515571Y883423D03*
X1513720Y880219D03*
X1519271Y883423D03*
X1513720Y873810D03*
X1515570Y877014D03*
X1519271D03*
X1521121Y880219D03*
Y873810D03*
X1522970Y877014D03*
X1511871Y870606D03*
X1522971D03*
X1517421Y873810D03*
X1511871Y883423D03*
X1517421Y880219D03*
X1522971Y883423D03*
X1515571D03*
X1513720Y880219D03*
X1519271Y883423D03*
X1521121Y880219D03*
X1513720Y873810D03*
X1515571Y870606D03*
X1521121Y873810D03*
X1519271Y870606D03*
X1515570Y877014D03*
X1522970D03*
X1511871D03*
X1519271D03*
X1511871Y889832D03*
X1513721Y893036D03*
X1517421Y886627D03*
X1521121D03*
X1513721D03*
X1526671Y889832D03*
X1513721Y899445D03*
X1524821Y912262D03*
X1511871Y909057D03*
Y902649D03*
X1513721Y912262D03*
X1515571Y909057D03*
X1524821Y905853D03*
X1513721D03*
X1519271Y909057D03*
X1511871Y928283D03*
Y921875D03*
X1519271Y928283D03*
X1515571D03*
X1513721Y918670D03*
X1524820Y925079D03*
X1513720D03*
X1524820Y931488D03*
X1513720D03*
X1511871Y941100D03*
X1513721Y937896D03*
X1524820Y944304D03*
X1513720D03*
X1511871Y947509D03*
X1525420Y949619D03*
X1519271Y947509D03*
X1515571D03*
X1525861Y962436D03*
X1511871Y960326D03*
X1513721Y957122D03*
Y950713D03*
X1511871Y966735D03*
X1524288Y965640D03*
X1513721Y963530D03*
X1515571Y979552D03*
X1513721Y982756D03*
X1511871Y973143D03*
X1517421Y969939D03*
X1515571Y973143D03*
X1519871Y984866D03*
X1516004Y1006092D03*
X1516003Y999684D03*
X1512303D03*
Y1006093D03*
X1519705Y1006092D03*
X1525396Y1000648D03*
X1512303Y1012501D03*
Y1025318D03*
X1516003Y1018910D03*
X1517854Y1015705D03*
X1525254D03*
X1521554D03*
X1514154D03*
X1512303Y1018910D03*
Y1031727D03*
X1525254Y1034931D03*
X1521554D03*
X1516004Y1044544D03*
X1516003Y1038136D03*
X1517853Y1034931D03*
X1514153D03*
X1512303Y1038136D03*
X1517853Y1054157D03*
X1514153D03*
X1512303Y1057361D03*
X1521553Y1054157D03*
X1514153Y1060565D03*
X1512303Y1050952D03*
X1525564Y1064850D03*
X1523404Y1070178D03*
X1514153Y1066974D03*
X1517853Y1073383D03*
X1521553Y1066974D03*
X1516003Y1076587D03*
X1512303D03*
X1512304Y1070178D03*
X1514153Y1073383D03*
X1523404Y1082996D03*
X1512304D03*
X1514153Y1092608D03*
X1512303Y1089404D03*
X1521553Y1092608D03*
X1523403Y1095813D03*
X1519703D03*
X1512303D03*
X1521554Y1105426D03*
X1517853D03*
X1516003Y1108630D03*
Y1102221D03*
X1512303D03*
X1517853Y1111834D03*
X1521553D03*
X1514153Y1105426D03*
X1512303Y1108630D03*
X1514153Y1111834D03*
X1519703Y1108630D03*
X1521553Y1124651D03*
Y1118243D03*
X1519704Y1115039D03*
X1516004D03*
X1514153Y1124651D03*
X1512303Y1115039D03*
X1517853Y1118243D03*
X1519703Y1121446D03*
X1516003Y1127855D03*
X1512303D03*
Y1121446D03*
X1516003D03*
X1517853Y1124650D03*
X1519703Y1127855D03*
X1517854Y1131560D03*
X1512304Y1134264D03*
X1514154Y1131059D03*
X1520395Y1578182D03*
X1516135D03*
X1520395Y1590094D03*
X1516135D03*
X1525695Y1614292D03*
Y1602380D03*
X1521435D03*
Y1614292D03*
X1513635D03*
Y1602380D03*
X1521063Y1675383D03*
Y1679920D03*
X1513189Y1679320D03*
X1521063Y1684454D03*
Y1689556D03*
Y1694093D03*
Y1698627D03*
X1513189Y1688391D03*
Y1693493D03*
Y1698030D03*
Y1683857D03*
X1521063Y1703729D03*
Y1708266D03*
Y1712800D03*
X1513189Y1707666D03*
Y1712203D03*
Y1702564D03*
X1521063Y1726974D03*
Y1722440D03*
Y1717903D03*
X1513189Y1730911D03*
Y1726377D03*
Y1721840D03*
Y1716737D03*
X1527571Y979057D03*
X1526843Y972608D03*
X1527103Y1031726D03*
X1540255Y1578182D03*
X1532455D03*
X1528195D03*
X1540255Y1590094D03*
X1532455D03*
X1528195D03*
X1537755Y1614292D03*
Y1602380D03*
X1533495D03*
Y1614292D03*
X1536811Y1675383D03*
Y1679920D03*
X1528937Y1679320D03*
X1536811Y1684454D03*
Y1689556D03*
Y1694093D03*
Y1698627D03*
X1528937Y1688391D03*
Y1693493D03*
Y1698030D03*
Y1683857D03*
X1536811Y1703729D03*
Y1708266D03*
Y1712800D03*
X1528937Y1707666D03*
Y1712203D03*
Y1702564D03*
X1536811Y1726974D03*
Y1722440D03*
Y1717903D03*
X1528937Y1730911D03*
Y1726377D03*
Y1721840D03*
Y1716737D03*
X1556575Y1578182D03*
X1544515D03*
X1552315D03*
X1556575Y1590094D03*
X1544515D03*
X1552315D03*
X1549815Y1614292D03*
Y1602380D03*
X1557615D03*
Y1614292D03*
X1545555Y1602380D03*
Y1614292D03*
X1552559Y1675383D03*
Y1679920D03*
X1544685Y1679320D03*
X1552559Y1684454D03*
Y1689556D03*
Y1694093D03*
Y1698627D03*
X1544685Y1688391D03*
Y1693493D03*
Y1698030D03*
Y1683857D03*
X1552559Y1703729D03*
Y1708266D03*
Y1712800D03*
X1544685Y1707666D03*
Y1712203D03*
Y1702564D03*
X1552559Y1726974D03*
Y1722440D03*
Y1717903D03*
X1544685Y1730911D03*
Y1726377D03*
Y1721840D03*
Y1716737D03*
X1568635Y1578182D03*
X1564375D03*
X1568635Y1590094D03*
X1564375D03*
X1573935Y1614292D03*
Y1602380D03*
X1569675Y1614292D03*
Y1602380D03*
X1561875Y1614292D03*
Y1602380D03*
X1560433Y1679320D03*
X1572244Y1675383D03*
Y1679920D03*
X1560433Y1688391D03*
Y1693493D03*
Y1698030D03*
Y1683857D03*
X1572244Y1684454D03*
Y1689556D03*
Y1694093D03*
Y1698627D03*
X1560433Y1707666D03*
Y1712203D03*
Y1702564D03*
X1572244Y1703729D03*
Y1708266D03*
Y1712800D03*
X1560433Y1730911D03*
Y1726377D03*
Y1721840D03*
Y1716737D03*
X1572244Y1726974D03*
Y1722440D03*
Y1717903D03*
X1588495Y1578182D03*
X1580695D03*
X1576435D03*
X1588495Y1590094D03*
X1580695D03*
X1576435D03*
X1585995Y1614292D03*
Y1602380D03*
X1581735D03*
Y1614292D03*
X1587992Y1675383D03*
Y1679920D03*
X1580118Y1679320D03*
X1587992Y1684454D03*
Y1689556D03*
Y1694093D03*
Y1698627D03*
X1580118Y1688391D03*
Y1693493D03*
Y1698030D03*
Y1683857D03*
X1587992Y1703729D03*
Y1708266D03*
Y1712800D03*
X1580118Y1707666D03*
Y1712203D03*
Y1702564D03*
X1587992Y1726974D03*
Y1722440D03*
Y1717903D03*
X1580118Y1730911D03*
Y1726377D03*
Y1721840D03*
Y1716737D03*
X1597041Y770144D03*
X1605741D03*
X1605800Y766478D03*
X1605741Y776837D03*
X1597041D03*
X1605741Y783530D03*
X1597041D03*
X1605741Y793570D03*
X1597041D03*
X1596988Y800263D03*
X1605741D03*
X1595774Y806955D03*
X1606934D03*
X1596218Y813648D03*
X1606735D03*
X1597041Y820341D03*
X1605741D03*
X1597041Y830381D03*
X1605741D03*
Y837074D03*
X1597041D03*
Y843766D03*
X1605741D03*
X1596147Y850459D03*
X1606896D03*
X1596200Y857152D03*
X1606623D03*
X1597041Y867192D03*
X1605741D03*
X1596941Y883924D03*
X1597041Y873885D03*
X1605741D03*
X1597041Y880577D03*
X1605741D03*
X1596941Y883924D03*
Y890617D03*
Y897310D03*
Y900656D03*
X1597041Y887270D03*
X1605741D03*
X1606898Y893963D03*
X1597041D03*
X1596941Y890617D03*
Y897310D03*
Y900656D03*
Y914042D03*
Y907349D03*
X1605741Y904003D03*
X1597041D03*
Y917389D03*
X1605741D03*
X1597041Y910696D03*
X1605741D03*
X1596941Y914042D03*
Y907349D03*
X1597041Y924081D03*
X1605741D03*
X1606541Y930697D03*
X1596047Y930774D03*
X1596106Y940814D03*
X1606919D03*
X1605741Y947507D03*
X1597041D03*
X1596941Y960892D03*
Y957546D03*
X1605741Y954200D03*
X1597041D03*
Y964239D03*
X1605741D03*
X1596941Y960892D03*
Y957546D03*
X1597041Y977625D03*
X1605741D03*
Y970932D03*
X1597041D03*
Y984318D03*
X1605741D03*
X1597041Y991011D03*
X1605741D03*
X1601922Y1000198D03*
X1599489Y999665D03*
X1597041Y1024475D03*
X1605741D03*
X1597041Y1017782D03*
X1605741D03*
X1597041Y1031168D03*
X1605741D03*
X1597041Y1037861D03*
X1605741D03*
X1597041Y1044554D03*
X1605741D03*
Y1051247D03*
X1597041D03*
Y1057940D03*
X1605741D03*
X1597041Y1061286D03*
Y1064633D03*
X1605741D03*
X1606541Y1071326D03*
X1596141D03*
X1597041Y1078018D03*
X1605741D03*
Y1094751D03*
X1597041D03*
Y1088058D03*
X1605741D03*
Y1101444D03*
X1597041D03*
Y1108137D03*
X1605741D03*
X1606541Y1114829D03*
X1596241D03*
X1596511Y1124969D03*
X1606505Y1124674D03*
X1605741Y1138255D03*
X1597041D03*
X1605741Y1144948D03*
X1597041D03*
Y1131562D03*
X1605741D03*
Y1151641D03*
X1597041D03*
X1596653Y1161680D03*
X1605975Y1161581D03*
X1596941Y1178412D03*
X1605741Y1168373D03*
X1597041D03*
X1605741Y1175066D03*
X1597041D03*
X1596941Y1185105D03*
Y1191798D03*
Y1195144D03*
X1605741Y1181759D03*
X1597041D03*
X1606765Y1188452D03*
X1597041D03*
X1596941Y1185105D03*
Y1178412D03*
Y1191798D03*
Y1201837D03*
Y1208530D03*
X1597041Y1198491D03*
X1605741D03*
Y1205184D03*
X1597041D03*
X1596941Y1208530D03*
Y1201837D03*
Y1195144D03*
X1597041Y1211877D03*
X1605741D03*
X1597041Y1218570D03*
X1605741D03*
X1597041Y1225263D03*
X1605741D03*
X1607064Y1235302D03*
X1596178D03*
X1605741Y1241995D03*
X1597041D03*
Y1248688D03*
X1605741D03*
X1606481Y1258649D03*
X1603788Y1273144D03*
X1601388D03*
X1607897Y1264445D03*
X1604815Y1578182D03*
X1592755D03*
X1600555D03*
X1604815Y1590094D03*
X1592755D03*
X1600555D03*
X1598055Y1614292D03*
Y1602380D03*
X1605855Y1614292D03*
Y1602380D03*
X1593795Y1614292D03*
Y1602380D03*
X1603740Y1675383D03*
Y1679920D03*
X1595866Y1679320D03*
X1603740Y1684454D03*
Y1689556D03*
Y1694093D03*
Y1698627D03*
X1595866Y1688391D03*
Y1693493D03*
Y1698030D03*
Y1683857D03*
X1603740Y1703729D03*
Y1708266D03*
Y1712800D03*
X1595866Y1707666D03*
Y1712203D03*
Y1702564D03*
X1603740Y1726974D03*
Y1722440D03*
Y1717903D03*
X1595866Y1730911D03*
Y1726377D03*
Y1721840D03*
Y1716737D03*
X1613183Y766798D03*
X1621883D03*
Y773491D03*
X1613183D03*
X1621883Y780184D03*
X1613183D03*
X1621883Y790223D03*
X1613183D03*
Y796916D03*
X1621883D03*
X1613183Y803609D03*
X1621883D03*
X1622916Y816995D03*
X1613183D03*
X1612363Y810302D03*
X1622986D03*
X1613183Y827034D03*
X1621883D03*
Y833727D03*
X1613183D03*
Y840420D03*
X1621883D03*
X1613183Y847113D03*
X1621943D03*
X1622060Y863845D03*
X1612408D03*
X1612474Y853955D03*
X1622961Y853806D03*
X1613083Y880577D03*
Y887270D03*
X1621883Y883924D03*
X1613183D03*
Y870538D03*
X1621883D03*
X1613183Y877231D03*
X1621883D03*
X1613083Y880577D03*
Y897310D03*
Y893963D03*
Y904003D03*
X1613183Y890617D03*
X1621883D03*
X1613183Y900656D03*
X1621883D03*
X1613083Y887270D03*
Y897310D03*
Y893963D03*
Y910696D03*
X1621883Y907349D03*
X1613183D03*
Y914042D03*
X1621883D03*
X1613083Y910696D03*
Y904003D03*
X1621883Y920735D03*
X1613183D03*
X1622535Y927526D03*
X1612168Y927428D03*
X1622845Y937467D03*
X1612312D03*
X1621883Y944160D03*
X1613183D03*
X1621883Y950853D03*
X1613183D03*
X1621883Y960892D03*
X1613183D03*
X1613083Y957546D03*
Y954200D03*
X1613183Y974278D03*
X1621883D03*
X1613183Y980971D03*
X1621883D03*
X1613183Y967585D03*
X1621883D03*
X1613183Y987664D03*
X1621883D03*
X1616609Y1000735D03*
X1616469Y1003135D03*
X1623539Y1000135D03*
X1620489Y1003135D03*
X1623589Y1002865D03*
X1620399Y1000325D03*
X1621883Y1017782D03*
X1613183D03*
Y1027822D03*
X1621883D03*
X1613183Y1034515D03*
X1621883D03*
X1613183Y1041207D03*
X1621883D03*
X1613183Y1047900D03*
X1621883D03*
Y1054593D03*
X1613183D03*
Y1061286D03*
X1621883D03*
Y1067979D03*
X1612983D03*
X1612283Y1074672D03*
X1622683D03*
X1621883Y1084711D03*
X1612383D03*
X1613183Y1091404D03*
X1621883D03*
Y1104790D03*
X1613183D03*
X1621883Y1098097D03*
X1613183D03*
X1621883Y1111483D03*
X1613183D03*
Y1128915D03*
X1621883Y1128215D03*
X1613183Y1121522D03*
X1621883D03*
Y1141601D03*
X1613183D03*
X1622726Y1135108D03*
X1611886Y1134908D03*
X1621883Y1158333D03*
X1613183D03*
X1621883Y1148294D03*
X1613183D03*
X1613083Y1175066D03*
X1621883Y1165026D03*
X1613183D03*
Y1171719D03*
X1621883D03*
X1613083Y1175066D03*
Y1181759D03*
Y1191798D03*
Y1188451D03*
X1621883Y1178412D03*
X1613183D03*
X1621883Y1185105D03*
X1613183D03*
X1613083Y1181759D03*
Y1191798D03*
Y1188451D03*
Y1198491D03*
Y1205184D03*
X1613183Y1195144D03*
X1621883D03*
Y1201837D03*
X1613183D03*
X1621883Y1208530D03*
X1613183D03*
X1613083Y1205184D03*
Y1198491D03*
X1621883Y1215223D03*
X1613183D03*
X1612147Y1221916D03*
X1622712D03*
X1612137Y1231862D03*
X1622681Y1231955D03*
X1621883Y1238648D03*
X1613183D03*
X1610150Y1257172D03*
X1621883Y1245341D03*
X1613183D03*
X1621983Y1258727D03*
X1613183Y1252034D03*
X1613027Y1248805D03*
X1609056Y1250602D03*
X1618888Y1273344D03*
X1616088D03*
X1613019Y1261235D03*
X1616875Y1578182D03*
X1612615D03*
X1616875Y1590094D03*
X1612615D03*
X1622175Y1614292D03*
Y1602380D03*
X1617915Y1614292D03*
Y1602380D03*
X1610115Y1614292D03*
Y1602380D03*
X1619488Y1675383D03*
Y1679920D03*
X1611614Y1679320D03*
X1619488Y1684454D03*
Y1689556D03*
Y1694093D03*
Y1698627D03*
X1611614Y1688391D03*
Y1693493D03*
Y1698030D03*
Y1683857D03*
X1619488Y1703729D03*
Y1708266D03*
Y1712800D03*
X1611614Y1707666D03*
Y1712203D03*
Y1702564D03*
X1619488Y1726974D03*
Y1722440D03*
Y1717903D03*
X1611614Y1730911D03*
Y1726377D03*
Y1721840D03*
Y1716737D03*
X1626741Y770144D03*
X1635441D03*
X1626741Y766798D03*
Y776837D03*
X1635441D03*
X1626741Y783530D03*
X1635441D03*
X1626741Y793570D03*
X1635441D03*
Y800263D03*
X1626741D03*
X1636341Y820341D03*
X1626741D03*
X1636574Y813648D03*
X1626741D03*
X1635441Y806955D03*
X1626741D03*
X1635441Y830381D03*
X1626741D03*
X1635441Y837074D03*
X1626741D03*
Y843766D03*
X1635441D03*
Y850459D03*
X1626741D03*
X1625705Y867192D03*
X1636441D03*
X1635441Y857152D03*
X1626741D03*
Y880577D03*
X1635441D03*
Y873885D03*
X1626741D03*
Y887270D03*
X1635441D03*
X1626741Y893963D03*
X1635441D03*
X1626741Y904003D03*
X1635441D03*
Y910696D03*
X1626741D03*
X1635441Y917389D03*
X1626741D03*
X1636316Y930774D03*
X1625803D03*
X1636646Y924081D03*
X1626741D03*
X1635441Y940814D03*
X1626741D03*
X1635441Y947507D03*
X1626741D03*
X1626641Y960892D03*
Y957546D03*
X1635441Y954200D03*
X1626741D03*
Y964239D03*
X1635441D03*
X1626641Y960892D03*
Y957546D03*
X1635441Y977625D03*
X1626741D03*
X1635441Y970932D03*
X1626741D03*
X1635441Y984318D03*
X1626741D03*
Y991011D03*
X1635441D03*
X1626249Y1002825D03*
X1635441Y1024475D03*
X1626741D03*
X1635441Y1017782D03*
X1626741D03*
X1635441Y1031168D03*
X1626741D03*
X1635441Y1037861D03*
X1626741D03*
X1635441Y1044554D03*
X1626741D03*
Y1057940D03*
X1635441D03*
Y1051247D03*
X1626741D03*
X1635441Y1064633D03*
X1626741D03*
X1635441Y1071326D03*
X1626741D03*
X1636241Y1078018D03*
X1625941D03*
Y1088058D03*
X1636241D03*
X1635441Y1094751D03*
X1626741D03*
Y1101444D03*
X1635441D03*
X1626741Y1108137D03*
X1635441D03*
X1626074Y1124640D03*
X1636341Y1124869D03*
X1635441Y1114829D03*
X1626741D03*
X1635441Y1144948D03*
X1626741D03*
X1635441Y1138255D03*
X1626741D03*
X1635441Y1130762D03*
X1626741D03*
Y1161680D03*
X1635441D03*
Y1151641D03*
X1626741D03*
Y1168373D03*
X1635441D03*
X1626741Y1175066D03*
X1635441D03*
X1626741Y1181759D03*
X1635441D03*
X1626741Y1188452D03*
X1635441D03*
X1626741Y1198491D03*
X1635441D03*
X1626741Y1205184D03*
X1635441D03*
Y1211877D03*
X1626741D03*
X1635441Y1218570D03*
X1626741D03*
X1636212Y1225263D03*
X1626055D03*
X1636376Y1235302D03*
X1625843D03*
X1635441Y1241995D03*
X1626741D03*
X1635688Y1257664D03*
X1626741Y1248688D03*
X1635441D03*
X1626741Y1258727D03*
X1629788Y1273344D03*
X1632588D03*
X1625729Y1266766D03*
X1636735Y1578088D03*
X1628935Y1578182D03*
X1624675D03*
X1636735Y1590094D03*
X1628935D03*
X1624675D03*
X1634235Y1614292D03*
Y1602380D03*
X1629975Y1614292D03*
Y1602380D03*
X1627362Y1679320D03*
Y1688391D03*
Y1693493D03*
Y1698030D03*
Y1683857D03*
Y1707666D03*
Y1712203D03*
Y1702564D03*
Y1730911D03*
Y1726377D03*
Y1721840D03*
Y1716737D03*
X1656441Y773491D03*
X1651583Y766798D03*
X1642883D03*
X1656441Y770144D03*
Y766798D03*
Y780184D03*
Y786877D03*
Y776837D03*
X1642883Y773491D03*
X1651583D03*
X1642883Y780184D03*
X1651583D03*
X1656441Y783530D03*
Y780184D03*
Y773491D03*
Y786877D03*
Y796916D03*
Y790223D03*
Y803609D03*
Y793570D03*
X1642883Y790223D03*
X1651583D03*
X1642883Y796916D03*
X1651583D03*
X1656441Y800263D03*
X1651583Y803609D03*
X1642883D03*
X1656441D03*
Y796916D03*
Y790223D03*
Y816995D03*
Y810302D03*
Y806955D03*
Y813648D03*
Y820341D03*
X1651583Y810302D03*
X1642883D03*
X1652545Y816995D03*
X1641945D03*
X1656441D03*
Y810302D03*
Y833727D03*
Y823688D03*
Y827034D03*
Y830381D03*
X1652767Y827034D03*
X1642018D03*
X1651583Y833727D03*
X1642883D03*
X1656441D03*
Y823688D03*
Y827034D03*
Y847113D03*
Y840420D03*
Y853806D03*
Y837074D03*
Y843766D03*
X1642883Y840420D03*
X1651583D03*
X1656441Y850459D03*
X1651583Y847113D03*
X1642883D03*
X1656441D03*
Y840420D03*
Y860499D03*
Y863845D03*
Y870538D03*
X1642058Y863845D03*
X1652742D03*
X1656441Y857152D03*
Y867192D03*
X1652559Y853806D03*
X1642032D03*
X1656441D03*
Y860499D03*
Y863845D03*
Y883924D03*
Y877231D03*
Y873885D03*
Y880577D03*
X1642883Y883924D03*
X1651583D03*
Y870538D03*
X1642883D03*
X1651583Y877231D03*
X1642883D03*
X1656441Y883924D03*
Y877231D03*
Y870538D03*
Y890617D03*
Y897310D03*
Y900656D03*
Y887270D03*
Y893963D03*
X1642883Y890617D03*
X1651583D03*
X1642883Y900656D03*
X1651583D03*
X1656441Y890617D03*
Y897310D03*
Y900656D03*
Y914042D03*
Y907349D03*
Y904003D03*
Y910696D03*
X1642883Y907349D03*
X1651583D03*
X1656441Y917389D03*
X1651583Y914042D03*
X1642883D03*
X1656441D03*
Y907349D03*
Y927428D03*
Y920735D03*
Y934121D03*
Y924081D03*
Y930774D03*
X1652630Y927428D03*
X1642038D03*
X1651583Y920735D03*
X1642883D03*
X1656441Y927428D03*
Y920735D03*
Y934121D03*
Y937467D03*
Y944160D03*
Y950853D03*
Y940814D03*
Y947507D03*
X1652501Y937467D03*
X1642065D03*
X1651583Y944160D03*
X1642883D03*
X1656441D03*
Y937467D03*
Y960892D03*
Y957546D03*
Y967585D03*
Y954200D03*
X1642883Y950853D03*
X1651583D03*
Y960892D03*
X1642883D03*
X1656441Y964239D03*
Y960892D03*
Y950853D03*
Y957546D03*
X1642783D03*
Y954200D03*
X1656441Y980971D03*
Y974278D03*
Y977625D03*
Y970932D03*
X1651583Y967585D03*
X1642883D03*
X1651583Y974278D03*
X1642883D03*
X1651583Y980971D03*
X1642883D03*
X1656441D03*
Y974278D03*
Y967585D03*
Y994357D03*
Y987664D03*
Y984318D03*
Y991011D03*
X1651583Y987664D03*
X1642883D03*
X1656441Y994357D03*
Y987664D03*
X1648205Y998632D03*
X1656141Y1027822D03*
X1656441Y1021129D03*
X1651583Y1017782D03*
X1642883D03*
X1656441D03*
Y1024475D03*
X1651583Y1027822D03*
X1642883D03*
X1656441Y1031168D03*
X1656141Y1027822D03*
X1656441Y1021129D03*
X1656141Y1034514D03*
Y1047900D03*
Y1041207D03*
X1656441Y1044554D03*
Y1037861D03*
X1651583Y1034515D03*
X1642883D03*
X1651583Y1041207D03*
X1642883D03*
X1651583Y1047900D03*
X1642883D03*
X1656141D03*
Y1041207D03*
Y1034514D03*
Y1054593D03*
X1642883Y1061286D03*
X1651583D03*
X1656441Y1051247D03*
Y1057940D03*
X1651583Y1054593D03*
X1642883D03*
X1656441Y1061286D03*
X1656141Y1054593D03*
X1656441Y1067979D03*
Y1074672D03*
Y1081365D03*
Y1064633D03*
Y1071326D03*
Y1078018D03*
X1652483Y1074672D03*
X1641983D03*
X1651583Y1067979D03*
X1642883D03*
X1656441Y1074672D03*
Y1067979D03*
Y1084711D03*
Y1091404D03*
Y1098097D03*
Y1088058D03*
Y1094751D03*
X1652383Y1084711D03*
X1642083D03*
X1651583Y1091404D03*
X1642883D03*
X1656441D03*
Y1081365D03*
Y1084711D03*
Y1111483D03*
Y1104790D03*
Y1101444D03*
Y1108137D03*
X1642883Y1098097D03*
X1651583D03*
X1642883Y1104790D03*
X1651583D03*
X1642883Y1111483D03*
X1651583D03*
X1656441Y1098097D03*
Y1111483D03*
Y1104790D03*
Y1118176D03*
Y1128215D03*
Y1121522D03*
Y1114829D03*
Y1124869D03*
X1642883Y1121522D03*
X1651583D03*
X1642883Y1128215D03*
X1651583D03*
X1656441D03*
Y1118176D03*
Y1121522D03*
Y1134908D03*
Y1141601D03*
Y1131562D03*
Y1138255D03*
X1642883Y1134908D03*
X1651583D03*
X1642883Y1141601D03*
X1651583D03*
X1656441Y1144948D03*
Y1141601D03*
Y1134908D03*
Y1148294D03*
Y1154987D03*
Y1158333D03*
Y1151641D03*
Y1161680D03*
X1652383Y1158333D03*
X1642083D03*
X1652794Y1148294D03*
X1641744D03*
X1656441D03*
Y1154987D03*
Y1158333D03*
Y1165026D03*
Y1171719D03*
Y1178412D03*
Y1168373D03*
Y1175066D03*
X1642883Y1171719D03*
X1651583D03*
Y1165026D03*
X1642883D03*
X1656441Y1171719D03*
Y1165026D03*
Y1185105D03*
Y1191798D03*
Y1195144D03*
Y1181759D03*
Y1188452D03*
X1651583Y1178412D03*
X1642883D03*
X1651583Y1185105D03*
X1642883D03*
X1656441D03*
Y1178412D03*
Y1191798D03*
Y1201837D03*
Y1208530D03*
Y1198491D03*
Y1205184D03*
X1642883Y1195144D03*
X1651583D03*
X1642883Y1201837D03*
X1651583D03*
X1642883Y1208530D03*
X1651583D03*
X1656441D03*
Y1201837D03*
Y1195144D03*
Y1215223D03*
Y1221916D03*
Y1228609D03*
Y1211877D03*
X1652590Y1221916D03*
X1641793D03*
X1656441Y1225263D03*
Y1218570D03*
X1651583Y1215223D03*
X1642883D03*
X1656441Y1221916D03*
Y1215223D03*
Y1231955D03*
Y1238648D03*
Y1245341D03*
Y1235302D03*
Y1241995D03*
X1652604Y1231955D03*
X1642054D03*
X1651583Y1238648D03*
X1642883D03*
X1656441D03*
Y1228609D03*
Y1231955D03*
Y1248688D03*
X1651583Y1245341D03*
X1642883D03*
X1656441D03*
X1642883Y1255381D03*
Y1258727D03*
Y1252034D03*
X1651679Y1248885D03*
X1653140Y1257862D03*
X1648588Y1273344D03*
X1645788D03*
X1656188Y1264964D03*
X1642788Y1264464D03*
X1642883Y1262074D03*
X1656170Y1260352D03*
X1640995Y1578182D03*
X1648795D03*
X1640995Y1590094D03*
X1648795D03*
X1646295Y1614292D03*
Y1602380D03*
X1654095Y1614292D03*
Y1602380D03*
X1642035Y1614292D03*
Y1602286D03*
X1672583Y770144D03*
X1665141D03*
X1672583Y766798D03*
Y770144D03*
Y776837D03*
Y783530D03*
Y786877D03*
X1665141Y776837D03*
Y783530D03*
X1672583Y773491D03*
Y780184D03*
Y776837D03*
Y786877D03*
Y783530D03*
Y800263D03*
Y793570D03*
X1665141D03*
Y800263D03*
X1672583Y790223D03*
Y796916D03*
Y803609D03*
Y800263D03*
Y793570D03*
Y813648D03*
Y806955D03*
Y820341D03*
X1665141Y806955D03*
Y813648D03*
X1666030Y820341D03*
X1672583Y810302D03*
Y816995D03*
Y813648D03*
Y806955D03*
Y820341D03*
Y830381D03*
Y823688D03*
Y837074D03*
X1665141Y830381D03*
X1672583Y827034D03*
Y833727D03*
Y830381D03*
Y823688D03*
Y850459D03*
Y843766D03*
X1665141Y837074D03*
Y843766D03*
X1672583Y840420D03*
X1665141Y850459D03*
X1672583Y847113D03*
Y850459D03*
Y843766D03*
Y837074D03*
Y867192D03*
Y860499D03*
Y857152D03*
X1666038D03*
X1665141Y867192D03*
X1672583Y853806D03*
Y863845D03*
Y867192D03*
Y860499D03*
Y857152D03*
Y873885D03*
Y880577D03*
Y887270D03*
X1665141Y873885D03*
Y880577D03*
X1672583Y870538D03*
Y877231D03*
Y883924D03*
Y873885D03*
Y880577D03*
Y897310D03*
Y893963D03*
Y904003D03*
X1665141Y887270D03*
Y893963D03*
X1672583Y890617D03*
Y900656D03*
Y887270D03*
Y897310D03*
Y893963D03*
Y917389D03*
Y910696D03*
X1665141Y904003D03*
Y910696D03*
Y917389D03*
X1672583Y907349D03*
Y914042D03*
Y917389D03*
Y910696D03*
Y904003D03*
Y924081D03*
Y934121D03*
Y930774D03*
X1665141Y924081D03*
X1666246Y930774D03*
X1672583Y920735D03*
Y927428D03*
Y924081D03*
Y934121D03*
Y930774D03*
Y947507D03*
Y940814D03*
X1665141D03*
Y947507D03*
X1672583Y937467D03*
Y944160D03*
Y947507D03*
Y940814D03*
Y964239D03*
X1665141Y954200D03*
Y964239D03*
X1672583Y950853D03*
Y960892D03*
Y964239D03*
Y957546D03*
Y954200D03*
Y977625D03*
Y970932D03*
Y984318D03*
X1665141Y977625D03*
Y970932D03*
X1672583Y967585D03*
Y974278D03*
Y980971D03*
Y977625D03*
Y970932D03*
Y991011D03*
X1665141Y984318D03*
Y991011D03*
X1672583Y987664D03*
Y991011D03*
Y984318D03*
Y994357D03*
Y1021129D03*
Y1024475D03*
Y1031168D03*
X1665141Y1017782D03*
Y1024475D03*
Y1031168D03*
X1672583Y1017782D03*
Y1027822D03*
Y1021129D03*
Y1024475D03*
Y1031168D03*
X1672283Y1044554D03*
Y1037861D03*
X1665141Y1044554D03*
Y1037861D03*
X1672583Y1034515D03*
Y1041207D03*
Y1047900D03*
X1672283Y1044554D03*
Y1037861D03*
X1672583Y1051247D03*
Y1064633D03*
X1665141Y1051247D03*
Y1057940D03*
X1672583Y1061286D03*
Y1054593D03*
Y1051247D03*
Y1071325D03*
Y1078018D03*
Y1081365D03*
X1665141Y1064633D03*
Y1071326D03*
Y1077118D03*
X1672583Y1067979D03*
Y1074672D03*
Y1071325D03*
Y1064633D03*
Y1078018D03*
Y1094751D03*
Y1088058D03*
X1665141D03*
Y1094751D03*
X1672583Y1084711D03*
Y1091404D03*
Y1094751D03*
Y1088058D03*
Y1081365D03*
Y1101444D03*
Y1108136D03*
Y1114829D03*
X1665141Y1101444D03*
Y1108137D03*
X1672583Y1098097D03*
Y1104790D03*
Y1111483D03*
Y1108136D03*
Y1101444D03*
Y1118176D03*
Y1124869D03*
Y1131562D03*
X1665141Y1114829D03*
Y1124869D03*
X1672583Y1121522D03*
Y1128215D03*
Y1124869D03*
Y1118176D03*
Y1114829D03*
Y1144947D03*
Y1138255D03*
X1665141Y1131562D03*
Y1138255D03*
Y1144948D03*
X1672583Y1134908D03*
Y1141601D03*
Y1144947D03*
Y1138255D03*
Y1131562D03*
Y1151640D03*
Y1161680D03*
Y1154987D03*
X1666141Y1151641D03*
X1665141Y1161680D03*
X1672583Y1148294D03*
Y1158333D03*
Y1161680D03*
Y1154987D03*
Y1151640D03*
Y1168373D03*
Y1175066D03*
X1665141Y1168373D03*
Y1175066D03*
X1672583Y1165026D03*
Y1171719D03*
Y1175066D03*
Y1168373D03*
Y1181758D03*
Y1191798D03*
Y1188451D03*
X1665141Y1181759D03*
Y1188452D03*
X1672583Y1178412D03*
Y1185105D03*
Y1181758D03*
Y1191798D03*
Y1188451D03*
Y1198491D03*
Y1205184D03*
Y1211877D03*
X1665141Y1198491D03*
Y1205184D03*
X1672583Y1195144D03*
Y1201837D03*
Y1208530D03*
Y1205184D03*
Y1198491D03*
Y1218569D03*
Y1225262D03*
Y1228609D03*
X1665141Y1211877D03*
X1665941Y1225263D03*
X1665141Y1218570D03*
X1672583Y1215223D03*
Y1221916D03*
Y1218569D03*
Y1211877D03*
Y1225262D03*
Y1235302D03*
Y1241995D03*
X1665141Y1235302D03*
Y1241995D03*
X1672583Y1231955D03*
Y1238648D03*
Y1241995D03*
Y1235302D03*
Y1228609D03*
X1665141Y1248688D03*
X1672583Y1245341D03*
X1665688Y1257964D03*
X1672583Y1255381D03*
Y1258727D03*
Y1248688D03*
X1659488Y1273344D03*
X1662288D03*
X1672188Y1263764D03*
X1681283Y766798D03*
X1686141Y770144D03*
X1686041Y766798D03*
X1681283Y773491D03*
Y780184D03*
X1686141Y776837D03*
Y783530D03*
X1681283Y790223D03*
Y796916D03*
Y803609D03*
X1686141Y793570D03*
Y800263D03*
X1681283Y810302D03*
Y816995D03*
X1686141Y806955D03*
Y813648D03*
Y820341D03*
X1681283Y827034D03*
Y833727D03*
X1686141Y830381D03*
X1681283Y840420D03*
X1686141Y837074D03*
Y843766D03*
Y850459D03*
X1681283Y847113D03*
X1686141Y857152D03*
Y867192D03*
X1681283Y853806D03*
Y863845D03*
X1686141Y873885D03*
Y880577D03*
X1681283Y870538D03*
Y877231D03*
Y883924D03*
X1686141Y887270D03*
Y893963D03*
X1681283Y890617D03*
Y900656D03*
X1686141Y904003D03*
Y910696D03*
Y917389D03*
X1681283Y907349D03*
Y914042D03*
X1686141Y924081D03*
Y930774D03*
X1681283Y920735D03*
Y927428D03*
X1686141Y940814D03*
Y947507D03*
X1681283Y937467D03*
Y944160D03*
X1686041Y960892D03*
Y957546D03*
X1686141Y967585D03*
Y954200D03*
Y964239D03*
X1681283Y950853D03*
Y960892D03*
X1686041D03*
Y957546D03*
X1686141Y970932D03*
Y977625D03*
X1681283Y967585D03*
Y974278D03*
Y980971D03*
X1686141Y967585D03*
Y984318D03*
Y991011D03*
X1681283Y987664D03*
X1686141Y1017782D03*
Y1024475D03*
Y1031168D03*
X1681283Y1017782D03*
Y1027822D03*
X1686141Y1037861D03*
Y1044554D03*
X1681283Y1034515D03*
Y1041207D03*
Y1047900D03*
X1686141Y1054593D03*
Y1051247D03*
Y1057940D03*
X1681283Y1061286D03*
Y1054593D03*
X1686141D03*
Y1064633D03*
Y1071326D03*
Y1078018D03*
X1681283Y1067979D03*
Y1074672D03*
X1686141Y1088058D03*
Y1094751D03*
X1681283Y1084711D03*
Y1091404D03*
X1686141Y1101444D03*
Y1108137D03*
X1681283Y1098097D03*
Y1104790D03*
Y1111483D03*
X1686141Y1114829D03*
Y1124869D03*
X1681283Y1121522D03*
Y1128215D03*
X1686141Y1131562D03*
Y1138255D03*
Y1144948D03*
X1681283Y1134908D03*
Y1141601D03*
X1686141Y1151641D03*
Y1161680D03*
X1681283Y1148294D03*
Y1158333D03*
X1686141Y1168373D03*
Y1175066D03*
X1681283Y1165026D03*
Y1171719D03*
X1686141Y1181759D03*
Y1188452D03*
X1681283Y1178412D03*
Y1185105D03*
X1686141Y1198491D03*
Y1205184D03*
X1681283Y1195144D03*
Y1201837D03*
Y1208530D03*
X1686141Y1211877D03*
Y1218570D03*
Y1225263D03*
X1681283Y1215223D03*
Y1221916D03*
Y1231955D03*
Y1238648D03*
X1686141Y1235302D03*
Y1241995D03*
X1681283Y1245341D03*
X1686141Y1248688D03*
Y1258727D03*
X1681179Y1252034D03*
X1675488Y1273344D03*
X1678288D03*
X1689188D03*
X1686119Y1264985D03*
X1681309Y1262074D03*
X1694841Y770144D03*
X1702283Y766798D03*
X1694841Y776837D03*
Y783530D03*
X1702283Y773491D03*
Y780184D03*
X1694841Y793570D03*
Y800263D03*
X1702283Y790223D03*
Y796916D03*
Y803609D03*
X1694841Y806955D03*
Y813648D03*
Y820341D03*
X1702283Y810302D03*
Y816995D03*
X1694841Y830381D03*
X1702283Y827034D03*
Y833727D03*
X1694841Y837074D03*
Y843766D03*
Y850459D03*
X1702283Y840420D03*
Y847113D03*
X1694841Y857152D03*
Y867192D03*
X1702283Y853806D03*
Y863845D03*
X1694841Y873885D03*
Y880577D03*
X1702283Y870538D03*
Y877231D03*
Y883924D03*
X1694841Y887270D03*
Y893963D03*
X1702283Y890617D03*
Y900656D03*
X1694841Y904003D03*
Y910696D03*
Y917389D03*
X1702283Y907349D03*
Y914042D03*
X1694841Y924081D03*
Y930774D03*
X1702283Y920735D03*
Y927428D03*
X1694841Y940814D03*
Y947507D03*
X1702283Y937467D03*
Y944160D03*
Y964239D03*
X1694841Y954200D03*
Y964239D03*
X1702283Y950853D03*
Y960892D03*
Y964239D03*
X1702183Y957546D03*
Y954200D03*
X1694841Y970932D03*
Y977625D03*
X1702283Y967585D03*
Y974278D03*
Y980971D03*
X1694841Y984318D03*
Y991011D03*
X1702283Y987664D03*
X1702183Y994357D03*
X1702283Y1021129D03*
Y1024475D03*
X1694841Y1017782D03*
Y1024475D03*
Y1031168D03*
X1702283Y1017782D03*
Y1027822D03*
Y1021129D03*
Y1024475D03*
X1694841Y1037861D03*
Y1044554D03*
X1702283Y1034515D03*
Y1041207D03*
Y1047900D03*
Y1051247D03*
X1694841D03*
Y1057940D03*
X1702283Y1054593D03*
Y1061286D03*
Y1051247D03*
Y1057940D03*
X1694841Y1064633D03*
Y1071326D03*
Y1078018D03*
X1702283Y1067979D03*
Y1074672D03*
X1694841Y1088058D03*
Y1094751D03*
X1702283Y1084711D03*
Y1091404D03*
X1694841Y1101444D03*
Y1108137D03*
X1702283Y1098097D03*
Y1104790D03*
Y1111483D03*
X1694841Y1114829D03*
Y1124869D03*
X1702283Y1121522D03*
Y1128215D03*
X1694841Y1131562D03*
Y1138255D03*
Y1144948D03*
X1702283Y1134908D03*
Y1141601D03*
X1694841Y1151641D03*
Y1161680D03*
X1702283Y1148294D03*
Y1158333D03*
X1694841Y1168373D03*
Y1175066D03*
X1702283Y1165026D03*
Y1171719D03*
X1694841Y1181759D03*
Y1188452D03*
X1702283Y1178412D03*
Y1185105D03*
X1694841Y1198491D03*
Y1205184D03*
X1702283Y1195144D03*
Y1201837D03*
Y1208530D03*
X1694841Y1211877D03*
Y1218570D03*
Y1225263D03*
X1702283Y1215223D03*
Y1221916D03*
X1694841Y1235302D03*
Y1241995D03*
X1702283Y1231955D03*
Y1238648D03*
X1694841Y1248688D03*
X1695188Y1257064D03*
X1702283Y1245341D03*
X1699852Y1245418D03*
X1702283Y1248688D03*
X1691988Y1273344D03*
X1705188D03*
X1702249Y1265420D03*
X1702283Y1262074D03*
X1715841Y773491D03*
X1710983Y766798D03*
X1715841Y770144D03*
Y766798D03*
Y780184D03*
Y786877D03*
X1710983Y773491D03*
Y780184D03*
X1715841Y783530D03*
Y776837D03*
Y780184D03*
Y773491D03*
Y786877D03*
Y796916D03*
Y790223D03*
Y803609D03*
X1710983Y790223D03*
Y796916D03*
Y803609D03*
X1715841Y793570D03*
Y800263D03*
Y803609D03*
Y796916D03*
Y790223D03*
Y816995D03*
Y810302D03*
X1710983D03*
Y816995D03*
X1715841Y806955D03*
Y813648D03*
Y820341D03*
Y816995D03*
Y810302D03*
Y833727D03*
Y823688D03*
Y827034D03*
X1710983D03*
Y833727D03*
X1715841Y830381D03*
Y833727D03*
Y823688D03*
Y827034D03*
Y847113D03*
Y840420D03*
Y853806D03*
X1710983Y840420D03*
Y847113D03*
X1715841Y837074D03*
Y843766D03*
Y850459D03*
Y847113D03*
Y840420D03*
Y860499D03*
Y863845D03*
Y870538D03*
X1710983Y853806D03*
Y863845D03*
X1715841Y857152D03*
Y867192D03*
Y853806D03*
Y860499D03*
Y863845D03*
Y883924D03*
Y877231D03*
X1710983Y870538D03*
Y877231D03*
Y883924D03*
X1715841Y873885D03*
Y880577D03*
Y883924D03*
Y877231D03*
Y870538D03*
Y897310D03*
Y900656D03*
Y890617D03*
X1710983D03*
Y900656D03*
X1715841Y893963D03*
Y887270D03*
Y890617D03*
Y897310D03*
Y900656D03*
Y914042D03*
Y907349D03*
X1710983D03*
Y914042D03*
X1715841Y904003D03*
Y910696D03*
Y917389D03*
Y914042D03*
Y907349D03*
Y927428D03*
Y920735D03*
Y934121D03*
X1710983Y920735D03*
Y927428D03*
X1715841Y924081D03*
Y930774D03*
Y927428D03*
Y920735D03*
Y934121D03*
Y944160D03*
Y937467D03*
Y950853D03*
X1710983Y937467D03*
Y944160D03*
X1715841Y940814D03*
Y947507D03*
Y944160D03*
Y937467D03*
Y960892D03*
Y957546D03*
Y967585D03*
X1710983Y950853D03*
Y960892D03*
X1715841Y954200D03*
Y964239D03*
Y960892D03*
Y950853D03*
Y957546D03*
Y980971D03*
Y974278D03*
X1710983Y967585D03*
Y974278D03*
Y980971D03*
X1715841Y970932D03*
Y977625D03*
Y980971D03*
Y974278D03*
Y967585D03*
Y994357D03*
Y987664D03*
X1710983D03*
X1715841Y984318D03*
Y991011D03*
Y994357D03*
Y987664D03*
Y1027822D03*
Y1021129D03*
X1710983Y1017782D03*
Y1027822D03*
X1715841Y1017782D03*
Y1024475D03*
Y1031168D03*
Y1027822D03*
Y1021129D03*
Y1034514D03*
Y1041207D03*
Y1047900D03*
X1710983Y1034515D03*
Y1041207D03*
Y1047900D03*
X1715841Y1037861D03*
Y1044554D03*
Y1047900D03*
Y1041207D03*
Y1034514D03*
Y1054593D03*
X1710983D03*
Y1061286D03*
X1715841Y1051247D03*
Y1057940D03*
Y1061286D03*
Y1054593D03*
Y1067979D03*
Y1074672D03*
Y1081365D03*
X1710983Y1067979D03*
Y1074672D03*
X1715841Y1071326D03*
Y1064633D03*
Y1078018D03*
Y1074672D03*
Y1067979D03*
Y1084711D03*
Y1091404D03*
Y1098097D03*
X1710983Y1084711D03*
Y1091404D03*
X1715841Y1088058D03*
Y1094751D03*
Y1091404D03*
Y1081365D03*
Y1084711D03*
Y1111483D03*
Y1104790D03*
X1710983Y1098097D03*
Y1104790D03*
Y1111483D03*
X1715841Y1101444D03*
Y1108137D03*
Y1098097D03*
Y1111483D03*
Y1104790D03*
Y1118176D03*
Y1128215D03*
Y1121522D03*
X1710983D03*
Y1128215D03*
X1715841Y1114829D03*
Y1124869D03*
Y1128215D03*
Y1118176D03*
Y1121522D03*
Y1134908D03*
Y1141601D03*
X1710983Y1134908D03*
Y1141601D03*
X1715841Y1131562D03*
Y1138255D03*
Y1144948D03*
Y1141601D03*
Y1134908D03*
Y1148294D03*
Y1154987D03*
Y1158333D03*
X1710983Y1148294D03*
Y1158333D03*
X1715841Y1151641D03*
Y1161680D03*
Y1148294D03*
Y1154987D03*
Y1158333D03*
Y1165026D03*
Y1171719D03*
Y1178412D03*
X1710983Y1165026D03*
Y1171719D03*
X1715841Y1168373D03*
Y1175066D03*
Y1171719D03*
Y1165026D03*
Y1185105D03*
Y1191798D03*
Y1195144D03*
X1710983Y1178412D03*
Y1185105D03*
X1715841Y1181759D03*
Y1188452D03*
Y1185105D03*
Y1178412D03*
Y1191798D03*
Y1201837D03*
Y1208530D03*
X1710983Y1195144D03*
Y1201837D03*
Y1208530D03*
X1715841Y1198491D03*
Y1205184D03*
Y1208530D03*
Y1201837D03*
Y1195144D03*
Y1215223D03*
Y1221916D03*
Y1228609D03*
X1710983Y1215223D03*
Y1221916D03*
X1715841Y1211877D03*
Y1218570D03*
Y1225263D03*
Y1221916D03*
Y1215223D03*
Y1231955D03*
Y1238648D03*
Y1245341D03*
X1710983Y1231955D03*
Y1238648D03*
X1715841Y1235302D03*
Y1241995D03*
Y1238648D03*
Y1228609D03*
Y1231955D03*
X1710983Y1245341D03*
X1715841Y1248688D03*
Y1245341D03*
X1713620Y1258512D03*
X1711109Y1252034D03*
X1707514Y1273444D03*
X1718888Y1273344D03*
X1721688D03*
X1715839Y1265420D03*
X1731983Y770144D03*
Y766798D03*
X1724541Y770144D03*
X1731983D03*
Y776837D03*
Y783530D03*
Y786877D03*
Y773491D03*
Y780184D03*
X1724541Y783530D03*
Y776837D03*
X1731983D03*
Y786877D03*
Y783530D03*
Y800263D03*
Y793570D03*
X1724541D03*
Y800263D03*
X1731983Y790223D03*
Y796916D03*
Y803609D03*
Y800263D03*
Y793570D03*
Y813648D03*
Y806955D03*
Y820341D03*
X1724541Y806955D03*
Y813648D03*
Y820341D03*
X1731983Y810302D03*
Y816995D03*
Y813648D03*
Y806955D03*
Y820341D03*
Y830381D03*
Y823688D03*
Y837074D03*
X1724541Y830381D03*
X1731983Y827034D03*
Y833727D03*
Y830381D03*
Y823688D03*
Y850459D03*
Y843766D03*
X1724541Y837074D03*
Y843766D03*
Y850459D03*
X1731983Y840420D03*
Y847113D03*
Y850459D03*
Y843766D03*
Y837074D03*
Y867192D03*
Y860499D03*
Y857152D03*
X1724541D03*
Y867192D03*
X1731983Y853806D03*
Y863845D03*
Y867192D03*
Y860499D03*
Y857152D03*
Y873885D03*
Y880577D03*
Y887270D03*
X1724541Y873885D03*
Y880577D03*
X1731983Y870538D03*
Y877231D03*
Y883924D03*
Y873885D03*
Y880577D03*
Y897310D03*
Y893963D03*
Y904003D03*
X1724541Y893963D03*
Y887270D03*
X1731983Y890617D03*
Y900656D03*
Y887270D03*
Y897310D03*
Y893963D03*
Y917389D03*
Y910696D03*
X1724541Y904003D03*
Y910696D03*
Y917389D03*
X1731983Y907349D03*
Y914042D03*
Y917389D03*
Y910696D03*
Y904003D03*
Y924081D03*
Y934121D03*
Y930774D03*
X1724541Y924081D03*
Y930774D03*
X1731983Y920735D03*
Y927428D03*
Y924081D03*
Y934121D03*
Y930774D03*
Y947507D03*
Y940814D03*
X1724541D03*
Y947507D03*
X1731983Y937467D03*
Y944160D03*
Y947507D03*
Y940814D03*
Y964239D03*
X1724541Y954200D03*
Y964239D03*
X1731983Y950853D03*
Y960892D03*
Y964239D03*
Y957546D03*
Y954200D03*
Y977625D03*
X1731883Y970932D03*
X1731983Y984318D03*
X1724541Y970932D03*
Y977625D03*
X1731983Y967585D03*
Y974278D03*
Y980971D03*
Y977625D03*
X1731883Y970932D03*
X1731983Y991011D03*
X1724541Y984318D03*
Y991011D03*
X1731983Y987664D03*
Y991011D03*
Y984318D03*
Y994357D03*
Y1021129D03*
Y1024475D03*
Y1031168D03*
X1724541Y1017782D03*
Y1024475D03*
Y1031168D03*
X1731983Y1017782D03*
Y1027822D03*
Y1021129D03*
Y1024475D03*
Y1031168D03*
X1731683Y1044554D03*
Y1037861D03*
X1724541D03*
Y1044554D03*
X1731983Y1034515D03*
Y1041207D03*
Y1047900D03*
X1731683Y1044554D03*
Y1037861D03*
X1731983Y1051247D03*
X1731883Y1064633D03*
X1724541Y1051247D03*
Y1057940D03*
X1731983Y1054593D03*
Y1061286D03*
Y1051247D03*
X1731683Y1057940D03*
X1731818Y1071326D03*
X1731983Y1078018D03*
Y1081365D03*
X1724541Y1071326D03*
Y1064633D03*
Y1078018D03*
X1731983Y1074672D03*
Y1067979D03*
X1731818Y1071326D03*
X1731883Y1064633D03*
X1731983Y1078018D03*
Y1094751D03*
Y1088058D03*
X1724541D03*
Y1094751D03*
X1731983Y1084711D03*
Y1091404D03*
Y1094751D03*
Y1088058D03*
Y1081365D03*
Y1101444D03*
X1731818Y1108137D03*
X1731983Y1114829D03*
X1724541Y1101444D03*
Y1108137D03*
X1731983Y1098097D03*
Y1104790D03*
Y1111483D03*
X1731818Y1108137D03*
X1731983Y1101444D03*
Y1118176D03*
Y1124869D03*
Y1131562D03*
X1724541Y1114829D03*
Y1124869D03*
X1731983Y1121522D03*
Y1128215D03*
Y1124869D03*
Y1118176D03*
Y1114829D03*
Y1144947D03*
Y1138255D03*
X1724541Y1131562D03*
Y1138255D03*
Y1144948D03*
X1731983Y1134908D03*
Y1141601D03*
Y1144947D03*
Y1138255D03*
Y1131562D03*
Y1151640D03*
Y1161680D03*
Y1154987D03*
X1724541Y1151641D03*
Y1161680D03*
X1731983Y1148294D03*
Y1158333D03*
Y1161680D03*
Y1154987D03*
Y1151640D03*
Y1168373D03*
Y1175066D03*
X1724541Y1168373D03*
Y1175066D03*
X1731983Y1165026D03*
Y1171719D03*
Y1175066D03*
Y1168373D03*
X1731818Y1181759D03*
X1731983Y1191798D03*
X1731818Y1188452D03*
X1724541Y1181759D03*
Y1188452D03*
X1731983Y1178412D03*
Y1185105D03*
X1731818Y1181759D03*
X1731983Y1191798D03*
X1731818Y1188452D03*
X1731983Y1198491D03*
Y1205184D03*
Y1211877D03*
X1724541Y1198491D03*
Y1205184D03*
X1731983Y1195144D03*
Y1201837D03*
Y1208530D03*
Y1205184D03*
Y1198491D03*
Y1218569D03*
Y1225262D03*
Y1228609D03*
X1724541Y1211877D03*
Y1218570D03*
Y1225263D03*
X1731983Y1215223D03*
Y1221916D03*
Y1218569D03*
Y1211877D03*
Y1225262D03*
Y1235302D03*
Y1241995D03*
X1724541Y1235302D03*
Y1241995D03*
X1731983Y1231955D03*
Y1238648D03*
Y1241995D03*
Y1235302D03*
Y1228609D03*
X1724541Y1248688D03*
X1724588Y1257164D03*
X1731983Y1245341D03*
X1727041Y1248688D03*
X1731983Y1255381D03*
Y1258727D03*
Y1252034D03*
Y1248688D03*
X1734888Y1273344D03*
X1737688D03*
X1731939Y1265420D03*
X1731983Y1262074D03*
X1740683Y766798D03*
X1745541Y770144D03*
X1754241D03*
X1745541Y766798D03*
X1740683Y773491D03*
Y780184D03*
X1745541Y776837D03*
X1754241D03*
X1745541Y783530D03*
X1754241D03*
X1740683Y790223D03*
Y796916D03*
Y803609D03*
X1745541Y793570D03*
X1754241D03*
X1745541Y800263D03*
X1754241D03*
X1740683Y810302D03*
Y816995D03*
X1745541Y806955D03*
X1754241D03*
X1745541Y813648D03*
X1754241D03*
X1745541Y820341D03*
X1754241D03*
X1740683Y827034D03*
Y833727D03*
X1745541Y830381D03*
X1754241D03*
X1740683Y840420D03*
Y847113D03*
X1754241Y843766D03*
X1745541D03*
Y837074D03*
X1754241D03*
X1745541Y850459D03*
X1754241D03*
X1740683Y853806D03*
Y863845D03*
X1745541Y857152D03*
X1754241D03*
Y867192D03*
X1745541D03*
X1740683Y870538D03*
Y877231D03*
Y883924D03*
X1745541Y873885D03*
X1754241D03*
X1745541Y880577D03*
X1754241D03*
X1740683Y890617D03*
Y900656D03*
X1754241Y893963D03*
X1745541D03*
Y887270D03*
X1754241D03*
X1740683Y907349D03*
Y914042D03*
X1754241Y904003D03*
X1745541D03*
X1754241Y910696D03*
X1745541D03*
X1754241Y917389D03*
X1745541D03*
X1740683Y920735D03*
Y927428D03*
X1754241Y924081D03*
X1745541D03*
X1754241Y930774D03*
X1745541D03*
X1740683Y937467D03*
Y944160D03*
X1754241Y940814D03*
X1745541D03*
X1754241Y947507D03*
X1745541D03*
Y960892D03*
Y957546D03*
Y967585D03*
X1740683Y950853D03*
Y960892D03*
X1754241Y954200D03*
X1745541D03*
X1754241Y964239D03*
X1745541D03*
Y960892D03*
Y957546D03*
X1740683Y967585D03*
Y974278D03*
Y980971D03*
X1754241Y970932D03*
X1745541D03*
X1754241Y977625D03*
X1745541D03*
Y967585D03*
X1740683Y987664D03*
X1754241Y984318D03*
X1745541D03*
X1754241Y991011D03*
X1745541D03*
X1740683Y1017782D03*
Y1027822D03*
X1754241Y1017782D03*
X1745541D03*
Y1024475D03*
X1754241D03*
X1745541Y1031168D03*
X1754241D03*
X1740683Y1034515D03*
Y1041207D03*
Y1047900D03*
X1754241Y1044554D03*
X1745541D03*
Y1037861D03*
X1754241D03*
X1745541Y1054593D03*
X1740683D03*
Y1061286D03*
X1745541Y1051247D03*
X1754241D03*
X1745541Y1057940D03*
X1754241D03*
X1745541Y1054593D03*
X1740683Y1074672D03*
Y1067979D03*
X1754241Y1071326D03*
X1745541D03*
Y1064633D03*
X1754241D03*
Y1078018D03*
X1745541D03*
X1740683Y1084711D03*
Y1091404D03*
X1754241Y1088058D03*
X1745541D03*
X1754241Y1094751D03*
X1745541D03*
X1740683Y1098097D03*
Y1104790D03*
Y1111483D03*
X1754241Y1101444D03*
X1745541D03*
X1754241Y1108137D03*
X1745541D03*
X1740683Y1121522D03*
Y1128215D03*
X1754241Y1114829D03*
X1745541D03*
X1754241Y1124869D03*
X1745541D03*
X1740683Y1134908D03*
Y1141601D03*
X1754241Y1131562D03*
X1745541D03*
X1754241Y1138255D03*
X1745541D03*
X1754241Y1144948D03*
X1745541D03*
X1740683Y1148294D03*
Y1158333D03*
X1754241Y1151641D03*
X1745541D03*
X1754241Y1161680D03*
X1745541D03*
X1740683Y1165026D03*
Y1171719D03*
X1745541Y1175066D03*
X1754241D03*
Y1168373D03*
X1745541D03*
X1740683Y1178412D03*
Y1185105D03*
X1745541Y1181759D03*
X1754241D03*
Y1188452D03*
X1745541D03*
X1740683Y1195144D03*
Y1201837D03*
Y1208530D03*
X1754241Y1198491D03*
X1745541D03*
X1754241Y1205184D03*
X1745541D03*
X1740683Y1215223D03*
Y1221916D03*
X1754241Y1211877D03*
X1745541D03*
X1754241Y1218570D03*
X1745541D03*
X1754241Y1225263D03*
X1745541D03*
X1740683Y1231955D03*
Y1238648D03*
X1754241Y1235302D03*
X1745541D03*
X1754241Y1241995D03*
X1745541D03*
X1740683Y1245341D03*
X1754241Y1248688D03*
X1745541D03*
X1754488Y1257264D03*
X1745541Y1258727D03*
X1751388Y1273344D03*
X1748588D03*
X1745541Y1265420D03*
X1749088Y1310474D03*
X1746288D03*
X1770383Y766798D03*
X1761683D03*
X1770383Y773491D03*
X1761683D03*
Y780184D03*
X1770383D03*
X1761683Y790223D03*
X1770383D03*
X1761683Y796916D03*
X1770383D03*
X1761683Y803609D03*
X1770383D03*
X1761683Y810302D03*
X1770383D03*
X1761683Y816995D03*
X1770383D03*
X1761683Y827034D03*
X1770383D03*
X1761683Y833727D03*
X1770383D03*
X1761683Y840420D03*
X1770383D03*
X1761683Y847113D03*
X1770383D03*
X1761683Y853806D03*
X1770383D03*
X1761683Y863845D03*
X1770383D03*
X1761683Y870538D03*
X1770383D03*
X1761683Y877231D03*
X1770383D03*
X1761683Y883924D03*
X1770383D03*
X1761683Y890617D03*
X1770383D03*
X1761683Y900656D03*
X1770383D03*
X1761683Y907349D03*
X1770383D03*
X1761683Y914042D03*
X1770383D03*
Y927428D03*
X1761683D03*
Y920735D03*
X1770383D03*
X1761683Y937467D03*
X1770383D03*
X1761683Y944160D03*
X1770383D03*
X1761683Y964239D03*
Y950853D03*
X1770383D03*
X1761683Y960892D03*
X1770383D03*
X1761683Y964239D03*
Y957546D03*
Y954200D03*
Y967585D03*
X1770383D03*
X1761683Y974278D03*
X1770383D03*
X1761683Y980971D03*
X1770383D03*
X1761683Y987664D03*
X1770383D03*
X1761683Y994357D03*
Y1021129D03*
Y1024475D03*
Y1017782D03*
X1770383D03*
X1761683Y1027822D03*
X1770383D03*
X1761683Y1021129D03*
Y1024475D03*
Y1034515D03*
X1770383D03*
X1761683Y1041207D03*
X1770383D03*
X1761683Y1047900D03*
X1770383D03*
X1761683Y1051247D03*
Y1054593D03*
X1770383D03*
X1761683Y1061286D03*
X1770383D03*
X1761683Y1051247D03*
Y1067979D03*
X1770383D03*
X1761683Y1074672D03*
X1770383D03*
X1761683Y1084711D03*
X1770383D03*
X1761683Y1091404D03*
X1770383D03*
Y1098097D03*
X1761683D03*
Y1104790D03*
X1770383D03*
X1761683Y1111483D03*
X1770383D03*
X1761683Y1121522D03*
X1770383D03*
X1761683Y1128215D03*
X1770383D03*
X1761683Y1134908D03*
X1770383D03*
X1761683Y1141601D03*
X1770383D03*
X1761683Y1148294D03*
X1770383D03*
X1761683Y1158333D03*
X1770383D03*
X1761683Y1165026D03*
X1770383D03*
X1761683Y1171719D03*
X1770383D03*
X1761683Y1178412D03*
X1770383D03*
X1761683Y1185105D03*
X1770383D03*
X1761683Y1195144D03*
X1770383D03*
X1761683Y1201837D03*
X1770383D03*
X1761683Y1208530D03*
X1770383D03*
X1761683Y1215223D03*
X1770383D03*
X1761683Y1221916D03*
X1770383D03*
X1761683Y1231955D03*
X1770383D03*
X1761683Y1238648D03*
X1770383D03*
X1761683Y1245341D03*
X1770383D03*
X1756922Y1247632D03*
X1761683Y1255381D03*
Y1258727D03*
X1770299Y1252034D03*
X1761683Y1248688D03*
X1767388Y1273344D03*
X1764588D03*
X1761683Y1262074D03*
Y1265420D03*
X1775241Y773491D03*
Y770144D03*
X1783941D03*
X1773559Y767345D03*
X1775241Y780184D03*
Y786877D03*
Y776837D03*
X1783941D03*
X1775241Y783530D03*
X1783941D03*
X1775241Y780184D03*
Y773491D03*
Y786877D03*
Y796916D03*
Y803609D03*
Y790223D03*
Y793570D03*
X1783941D03*
X1775241Y800263D03*
X1783941D03*
X1775241Y803609D03*
Y796916D03*
Y790223D03*
Y816995D03*
Y810302D03*
Y806955D03*
X1783941D03*
X1775241Y813648D03*
X1783941D03*
X1775241Y820341D03*
X1783941D03*
X1775241Y816995D03*
Y810302D03*
Y833727D03*
Y823688D03*
Y827034D03*
X1783941Y830381D03*
X1775241D03*
Y833727D03*
Y823688D03*
Y827034D03*
Y840420D03*
Y847113D03*
Y853806D03*
Y837074D03*
X1783941D03*
X1775241Y843766D03*
X1783941D03*
X1775241Y850459D03*
X1783941D03*
X1775241Y847113D03*
Y840420D03*
Y863845D03*
Y860499D03*
Y870538D03*
Y857152D03*
X1783941D03*
X1775241Y867192D03*
X1783941D03*
X1775241Y853806D03*
Y860499D03*
Y863845D03*
Y883924D03*
Y877231D03*
Y873885D03*
X1783941D03*
X1775241Y880577D03*
X1783941D03*
X1775241Y883924D03*
Y877231D03*
Y870538D03*
Y890617D03*
Y900656D03*
Y897310D03*
Y887270D03*
X1783941D03*
X1775241Y893963D03*
X1783941D03*
X1775241Y890617D03*
Y897310D03*
Y900656D03*
Y914042D03*
Y907349D03*
Y904003D03*
X1783941D03*
X1775241Y910696D03*
X1783941D03*
X1775241Y917389D03*
X1783941D03*
X1775241Y914042D03*
Y907349D03*
Y927428D03*
Y920735D03*
Y934121D03*
Y924081D03*
X1783941D03*
X1775241Y930774D03*
X1783941D03*
X1775241Y927428D03*
Y920735D03*
Y934121D03*
Y944160D03*
Y937467D03*
Y950853D03*
Y940814D03*
X1783941D03*
X1775241Y947507D03*
X1783941D03*
X1775241Y944160D03*
Y937467D03*
Y960892D03*
Y957546D03*
Y967585D03*
Y954200D03*
X1783941D03*
X1775241Y964239D03*
X1783941D03*
X1775241Y960892D03*
Y950853D03*
Y957546D03*
Y980971D03*
Y974278D03*
Y970932D03*
X1783941D03*
X1775241Y977625D03*
X1783941D03*
X1775241Y980971D03*
Y974278D03*
Y967585D03*
Y994357D03*
Y987664D03*
Y984318D03*
X1783941D03*
X1775241Y991011D03*
X1783941D03*
X1775241Y994357D03*
Y987664D03*
Y1027822D03*
Y1021129D03*
Y1017782D03*
X1783941D03*
X1775241Y1024475D03*
X1783941D03*
X1775241Y1031168D03*
X1783941D03*
X1775241Y1027822D03*
Y1021129D03*
Y1034515D03*
Y1041207D03*
Y1047900D03*
Y1037861D03*
X1783941D03*
X1775241Y1044554D03*
X1783941D03*
X1775241Y1047900D03*
Y1041207D03*
Y1034515D03*
Y1054593D03*
Y1051247D03*
X1783941D03*
X1775241Y1057940D03*
X1783941D03*
X1775241Y1061286D03*
Y1054593D03*
Y1067979D03*
Y1074672D03*
Y1081365D03*
Y1064633D03*
X1783941D03*
X1775241Y1071326D03*
X1783941D03*
X1775241Y1078018D03*
X1783941D03*
X1775241Y1074672D03*
Y1067979D03*
Y1091404D03*
Y1084711D03*
Y1098097D03*
Y1088058D03*
X1783941D03*
X1775241Y1094751D03*
X1783941D03*
X1775241Y1091404D03*
Y1081365D03*
Y1084711D03*
Y1111483D03*
Y1104790D03*
Y1101444D03*
X1783941D03*
X1775241Y1108137D03*
X1783941D03*
X1775241Y1098097D03*
Y1111483D03*
Y1104790D03*
Y1128215D03*
Y1121522D03*
Y1118176D03*
Y1114829D03*
X1783941D03*
X1775241Y1124869D03*
X1783941D03*
X1775241Y1128215D03*
Y1118176D03*
Y1121522D03*
Y1134908D03*
Y1141601D03*
Y1131562D03*
X1783941D03*
X1775241Y1138255D03*
X1783941D03*
X1775241Y1144948D03*
X1783941D03*
X1775241Y1141601D03*
Y1134908D03*
Y1148294D03*
Y1154987D03*
Y1158333D03*
X1783941Y1151641D03*
X1775241D03*
Y1161680D03*
X1783941D03*
X1775241Y1148294D03*
Y1154987D03*
Y1158333D03*
Y1165026D03*
Y1171719D03*
Y1178412D03*
Y1168373D03*
X1783941D03*
X1775241Y1175066D03*
X1783941D03*
X1775241Y1171719D03*
Y1165026D03*
Y1185105D03*
Y1191798D03*
Y1195144D03*
Y1181759D03*
X1783941D03*
X1775241Y1188452D03*
X1783941D03*
X1775241Y1185105D03*
Y1178412D03*
Y1191798D03*
Y1201837D03*
Y1208530D03*
Y1198491D03*
X1783941D03*
X1775241Y1205184D03*
X1783941D03*
X1775241Y1208530D03*
Y1201837D03*
Y1195144D03*
Y1215223D03*
Y1221916D03*
Y1228609D03*
Y1211877D03*
X1783941D03*
X1775241Y1218570D03*
X1783941D03*
X1775241Y1225263D03*
X1783941D03*
X1775241Y1221916D03*
Y1215223D03*
Y1231955D03*
Y1238648D03*
Y1245341D03*
Y1235302D03*
X1783941D03*
X1775241Y1241995D03*
X1783941D03*
X1775241Y1238648D03*
Y1228609D03*
Y1231955D03*
X1784188Y1257664D03*
X1775241Y1248688D03*
X1783941D03*
X1775241Y1245341D03*
Y1258727D03*
X1781088Y1273344D03*
X1778288D03*
X1775241Y1265420D03*
X1791383Y770144D03*
Y766798D03*
X1800083D03*
X1791383Y770144D03*
Y776837D03*
Y783530D03*
Y786877D03*
Y773491D03*
X1800083D03*
X1791383Y780184D03*
X1800083D03*
X1791383Y776837D03*
Y786877D03*
Y783530D03*
Y800263D03*
Y793570D03*
Y790223D03*
X1800083D03*
X1791383Y796916D03*
X1800083D03*
X1791383Y803609D03*
X1800083D03*
X1791383Y800263D03*
Y793570D03*
Y813648D03*
Y806955D03*
Y820341D03*
Y810302D03*
X1800083D03*
X1791383Y816995D03*
X1800083D03*
X1791383Y813648D03*
Y806955D03*
Y820341D03*
Y830381D03*
Y823688D03*
Y837074D03*
Y827034D03*
X1800083D03*
Y833727D03*
X1791383D03*
Y830381D03*
Y823688D03*
Y850459D03*
Y843766D03*
Y840420D03*
X1800083D03*
X1791383Y847113D03*
X1800083D03*
X1791383Y850459D03*
Y843766D03*
Y837074D03*
Y867192D03*
Y857152D03*
Y860499D03*
Y853806D03*
X1800083D03*
X1791383Y863845D03*
X1800083D03*
X1791383Y867192D03*
Y860499D03*
Y857152D03*
Y873885D03*
Y880577D03*
Y887270D03*
Y870538D03*
X1800083D03*
X1791383Y877231D03*
X1800083D03*
X1791383Y883924D03*
X1800083D03*
X1791383Y873885D03*
Y880577D03*
Y893963D03*
Y897310D03*
Y904003D03*
Y890617D03*
X1800083D03*
X1791383Y900656D03*
X1800083D03*
X1791383Y887270D03*
Y897310D03*
Y893963D03*
Y917389D03*
Y910696D03*
Y907349D03*
X1800083D03*
X1791383Y914042D03*
X1800083D03*
X1791383Y917389D03*
Y910696D03*
Y904003D03*
Y924081D03*
Y930774D03*
Y934121D03*
Y920735D03*
X1800083D03*
X1791383Y927428D03*
X1800083D03*
X1791383Y924081D03*
Y934121D03*
Y930774D03*
Y947507D03*
Y940814D03*
Y937467D03*
X1800083D03*
X1791383Y944160D03*
X1800083D03*
X1791383Y947507D03*
Y940814D03*
Y964239D03*
X1804941Y960892D03*
Y957546D03*
Y967585D03*
X1800083Y950853D03*
X1791383D03*
Y960892D03*
X1800083D03*
X1791383Y964239D03*
Y957546D03*
Y954200D03*
Y977625D03*
Y970932D03*
Y984318D03*
Y967585D03*
X1800083D03*
X1791383Y974278D03*
X1800083D03*
X1791383Y980971D03*
X1800083D03*
X1791383Y977625D03*
Y970932D03*
Y991011D03*
Y987664D03*
X1800083D03*
X1791383Y991011D03*
Y984318D03*
Y994357D03*
Y1021129D03*
Y1024475D03*
Y1031168D03*
Y1017782D03*
X1800083D03*
X1791383Y1027822D03*
X1800083D03*
X1791383Y1021129D03*
Y1024475D03*
Y1031168D03*
Y1044554D03*
Y1037861D03*
Y1034515D03*
X1800083D03*
X1791383Y1041207D03*
X1800083D03*
X1791383Y1047900D03*
X1800083D03*
X1791383Y1044554D03*
Y1037861D03*
X1791083Y1051247D03*
X1804941Y1054593D03*
X1791383Y1064633D03*
Y1054593D03*
X1800083D03*
X1791383Y1061286D03*
X1800083D03*
X1791083Y1051247D03*
X1791383Y1071325D03*
Y1078018D03*
Y1081365D03*
Y1067979D03*
X1800083D03*
X1791383Y1074672D03*
X1800083D03*
X1791383Y1071325D03*
Y1064633D03*
Y1078018D03*
Y1094751D03*
Y1088058D03*
Y1084711D03*
X1800083D03*
X1791383Y1091404D03*
X1800083D03*
X1791383Y1094751D03*
Y1088058D03*
Y1081365D03*
Y1101444D03*
Y1108136D03*
Y1114829D03*
Y1098097D03*
X1800083D03*
X1791383Y1104790D03*
X1800083D03*
X1791383Y1111483D03*
X1800083D03*
X1791383Y1108136D03*
Y1101444D03*
Y1124869D03*
Y1118176D03*
Y1131562D03*
Y1121522D03*
X1800083D03*
X1791383Y1128215D03*
X1800083D03*
X1791383Y1124869D03*
Y1118176D03*
Y1114829D03*
Y1144947D03*
Y1138255D03*
X1800083Y1134908D03*
X1791383D03*
Y1141601D03*
X1800083D03*
X1791383Y1144947D03*
Y1138255D03*
Y1131562D03*
Y1161680D03*
Y1151640D03*
Y1154987D03*
Y1148294D03*
X1800083D03*
X1791383Y1158333D03*
X1800083D03*
X1791383Y1161680D03*
Y1154987D03*
Y1151640D03*
Y1168373D03*
Y1175066D03*
Y1165026D03*
X1800083D03*
X1791383Y1171719D03*
X1800083D03*
X1791383Y1175066D03*
Y1168373D03*
Y1181758D03*
Y1188451D03*
Y1191798D03*
Y1178412D03*
X1800083D03*
X1791383Y1185105D03*
X1800083D03*
X1791383Y1181758D03*
Y1191798D03*
Y1188451D03*
Y1198491D03*
Y1205184D03*
Y1211877D03*
Y1195144D03*
X1800083D03*
X1791383Y1201837D03*
X1800083D03*
X1791383Y1208530D03*
X1800083D03*
X1791383Y1205184D03*
Y1198491D03*
Y1218570D03*
Y1225263D03*
Y1228609D03*
Y1215223D03*
X1800083D03*
X1791383Y1221916D03*
X1800083D03*
X1791383Y1218570D03*
Y1211877D03*
Y1225263D03*
Y1235302D03*
Y1241995D03*
Y1231955D03*
X1800083D03*
X1791383Y1238648D03*
X1800083D03*
X1788373Y1241769D03*
X1791383Y1241995D03*
Y1235302D03*
Y1228609D03*
Y1245341D03*
X1800083D03*
X1800427Y1248125D03*
X1800019Y1252034D03*
X1791383Y1248688D03*
X1797088Y1273344D03*
X1794288D03*
X1791383Y1265420D03*
Y1262074D03*
X1804941Y770144D03*
X1813641D03*
X1804841Y766798D03*
X1804941Y776837D03*
X1813641D03*
X1804941Y783530D03*
X1813641D03*
X1804941Y793570D03*
X1813641D03*
X1804941Y800263D03*
X1813641D03*
X1804941Y806955D03*
X1813641D03*
X1804941Y813648D03*
X1813641D03*
X1804941Y820341D03*
X1813641D03*
X1804941Y830381D03*
X1813641D03*
X1804941Y843766D03*
X1813641D03*
X1804941Y837074D03*
X1813641D03*
X1804941Y850459D03*
X1813641D03*
X1804941Y857152D03*
X1813641D03*
Y867192D03*
X1804941D03*
Y873885D03*
X1813641D03*
X1804941Y880577D03*
X1813641D03*
X1804941Y887270D03*
X1813641D03*
X1804941Y893963D03*
X1813641D03*
X1804941Y904003D03*
X1813641D03*
X1804941Y910696D03*
X1813641D03*
X1804941Y917389D03*
X1813641D03*
X1804941Y924081D03*
X1813641D03*
X1804941Y930774D03*
X1813641D03*
X1804941Y940814D03*
X1813641D03*
X1804941Y947507D03*
X1813641D03*
X1821083Y964239D03*
X1804941Y954200D03*
X1813641D03*
X1804941Y964239D03*
X1813641D03*
X1804941Y960892D03*
Y957546D03*
Y970932D03*
X1813641D03*
X1804941Y977625D03*
X1813641D03*
X1804941Y967585D03*
Y984318D03*
X1813641D03*
X1804941Y991011D03*
X1813641D03*
X1821083Y1021129D03*
Y1024475D03*
X1804941Y1017782D03*
X1813641D03*
X1804941Y1024475D03*
X1813641D03*
X1804941Y1031168D03*
X1813641D03*
X1804941Y1037861D03*
X1813641D03*
X1804941Y1044554D03*
X1813641D03*
X1821083Y1051247D03*
X1813641Y1057940D03*
X1804941D03*
Y1051247D03*
X1813641D03*
X1804941Y1054593D03*
Y1064633D03*
X1813641D03*
Y1071326D03*
X1804941D03*
X1813641Y1078018D03*
X1804941D03*
X1813641Y1088058D03*
X1804941D03*
X1813641Y1094751D03*
X1804941D03*
X1813641Y1101444D03*
X1804941D03*
X1813641Y1108137D03*
X1804941D03*
X1813641Y1114829D03*
X1804941D03*
X1813641Y1124869D03*
X1804941D03*
X1813641Y1131562D03*
X1804941D03*
X1813641Y1138255D03*
X1804941D03*
X1813641Y1144948D03*
X1804941D03*
X1813641Y1151641D03*
X1804941D03*
X1813641Y1161680D03*
X1804941D03*
X1813641Y1168373D03*
X1804941D03*
X1813641Y1175066D03*
X1804941D03*
X1813641Y1181759D03*
X1804941D03*
X1813641Y1188452D03*
X1804941D03*
X1813641Y1198491D03*
X1804941D03*
X1813641Y1205184D03*
X1804941D03*
X1813641Y1211877D03*
X1804941D03*
X1813641Y1218570D03*
X1804941D03*
X1813641Y1225263D03*
X1804941D03*
X1813641Y1235302D03*
X1804941D03*
X1813641Y1241995D03*
X1804941D03*
X1815063Y1233103D03*
X1813641Y1248688D03*
X1804941D03*
X1819054Y1253986D03*
X1804941Y1258727D03*
X1813814Y1254693D03*
X1818188Y1273044D03*
X1810788Y1273344D03*
X1807988D03*
X1815388Y1273044D03*
X1804941Y1265420D03*
X1829783Y766798D03*
X1821083D03*
X1829783Y773491D03*
X1821083D03*
X1829783Y780184D03*
X1821083D03*
X1829783Y790223D03*
X1821083D03*
X1829783Y796916D03*
X1821083D03*
X1829783Y803609D03*
X1821083D03*
X1829783Y810302D03*
X1821083D03*
X1829783Y816995D03*
X1821083D03*
X1829783Y827034D03*
X1821083D03*
X1829783Y833727D03*
X1821083D03*
Y847113D03*
X1829783D03*
Y840420D03*
X1821083D03*
X1829783Y853806D03*
X1821083D03*
X1829783Y863845D03*
X1821083D03*
X1829783Y870538D03*
X1821083D03*
X1829783Y877231D03*
X1821083D03*
X1829783Y883924D03*
X1821083D03*
X1829783Y890617D03*
X1821083D03*
X1829783Y900656D03*
X1821083D03*
X1829783Y907349D03*
X1821083D03*
X1829783Y914042D03*
X1821083D03*
X1829783Y920735D03*
X1821083D03*
X1829783Y927428D03*
X1821083D03*
X1829783Y937467D03*
X1821083D03*
X1829783Y944160D03*
X1821083D03*
X1829783Y950853D03*
X1821083D03*
X1829783Y960892D03*
X1821083D03*
Y964239D03*
X1820983Y957546D03*
Y954200D03*
X1829783Y967585D03*
X1821083D03*
X1829783Y974278D03*
X1821083D03*
X1829783Y980971D03*
X1821083D03*
X1829783Y987664D03*
X1821083D03*
X1820983Y994357D03*
X1829783Y1017782D03*
X1821083D03*
X1829783Y1027822D03*
X1821083D03*
Y1021129D03*
Y1024475D03*
X1829783Y1034515D03*
X1821083D03*
X1829783Y1041207D03*
X1821083D03*
X1829783Y1047900D03*
X1821083D03*
X1829783Y1054593D03*
X1821083D03*
X1829783Y1061286D03*
X1821083D03*
Y1051247D03*
X1829783Y1067979D03*
X1821083D03*
Y1074672D03*
X1829783D03*
X1821083Y1084711D03*
X1829783D03*
X1821083Y1091404D03*
X1829783D03*
X1821083Y1098097D03*
X1829783D03*
X1821083Y1104790D03*
X1829783D03*
X1821083Y1111483D03*
X1829783D03*
X1821083Y1121522D03*
X1829783D03*
X1821083Y1128215D03*
X1829783D03*
X1821083Y1134908D03*
X1829783D03*
X1821083Y1141601D03*
X1829783D03*
X1821083Y1148294D03*
X1829783D03*
X1821083Y1158333D03*
X1829783D03*
X1821083Y1165026D03*
X1829783D03*
X1821083Y1171719D03*
X1829783D03*
X1821083Y1178412D03*
X1829783D03*
X1821083Y1185105D03*
X1829783D03*
X1821083Y1195144D03*
X1829783D03*
X1821083Y1201837D03*
X1829783D03*
X1821083Y1208530D03*
X1829783D03*
X1821083Y1215223D03*
X1829783D03*
X1821083Y1221916D03*
X1829783D03*
X1821083Y1231955D03*
X1829783D03*
X1821083Y1238648D03*
X1829783D03*
Y1245341D03*
X1821083D03*
X1830379Y1250358D03*
X1821139Y1248155D03*
X1821083Y1262074D03*
Y1265420D03*
X1955500Y3399622D03*
X1954950Y3689362D03*
X2822321Y1936329D03*
X2828490Y3412175D03*
X2832826Y2905599D03*
X2832836Y3156169D03*
X2833595Y3697637D03*
G54D32*
X791280Y1704890D03*
X1066280D03*
X2822321Y458829D03*
G54D42*
X1879155Y344948D03*
Y354948D03*
Y458898D03*
Y478898D03*
Y468898D03*
D03*
Y592848D03*
D03*
Y582848D03*
Y602848D03*
Y706798D03*
Y716798D03*
D03*
Y726798D03*
Y830748D03*
Y840748D03*
X1900275Y-19342D03*
Y-9342D03*
X1889155Y344948D03*
Y354948D03*
Y458898D03*
Y468898D03*
Y478898D03*
Y468898D03*
X1900275Y582858D03*
Y592858D03*
X1889155Y592848D03*
Y582848D03*
Y592848D03*
Y602848D03*
Y706798D03*
X1900275Y716808D03*
X1889155Y716798D03*
D03*
X1900275Y726808D03*
X1889155Y726798D03*
X1900275Y830758D03*
X1889155Y830748D03*
X1900275Y850758D03*
Y840758D03*
D03*
X1889155Y840748D03*
X1900275Y964708D03*
Y954708D03*
X1910275Y-9342D03*
Y-19342D03*
Y592858D03*
Y582858D03*
Y716808D03*
Y726808D03*
Y830758D03*
Y840758D03*
Y850758D03*
Y840758D03*
Y954708D03*
Y964708D03*
X1921395Y-9332D03*
Y-19332D03*
X1931395D03*
Y-9332D03*
Y582868D03*
Y592868D03*
X1921395D03*
Y582868D03*
X1931395Y592868D03*
X1921395D03*
X1931395Y602868D03*
X1921395D03*
Y1195068D03*
X1931395D03*
X1921395Y1205068D03*
X1931395D03*
X1952395Y-19152D03*
X1942395D03*
Y-9152D03*
Y583048D03*
Y593048D03*
X1952395D03*
X1942395D03*
X1952395D03*
X1942395Y603048D03*
Y1195248D03*
X1952395Y1205248D03*
X1942395D03*
X1963362Y-9190D03*
Y-19190D03*
X1952395Y-9152D03*
X1963362Y593010D03*
Y583010D03*
Y593010D03*
X1952395Y583048D03*
X1963362Y603010D03*
X1952395Y603048D03*
X1963362Y1195210D03*
X1952395Y1195248D03*
X1963362Y1205210D03*
X1984482Y-19180D03*
X1973362Y-19190D03*
Y-9190D03*
X1984482Y593020D03*
D03*
X1973362Y583010D03*
Y593010D03*
D03*
Y603010D03*
Y1195210D03*
X1984482Y1205220D03*
X1973362Y1205210D03*
X1994482Y-9180D03*
Y-19180D03*
X1984482Y-9180D03*
Y583020D03*
X1994482Y593020D03*
Y583020D03*
Y593020D03*
X1984482Y603020D03*
X1994482D03*
Y1195220D03*
X1984482D03*
X1994482Y1205220D03*
X2005452Y-9180D03*
Y-19180D03*
X2015452D03*
Y-9180D03*
Y583020D03*
Y593020D03*
X2005452D03*
Y583020D03*
X2015452Y593020D03*
X2005452D03*
X2015452Y603020D03*
X2005452D03*
Y1195220D03*
X2015452D03*
X2005452Y1205220D03*
X2015452D03*
X2026452Y-19000D03*
Y-9000D03*
Y583200D03*
Y593200D03*
D03*
Y603200D03*
Y1195400D03*
Y1205400D03*
X2047419Y-9038D03*
Y-19038D03*
X2036452Y-9000D03*
Y-19000D03*
X2047419Y593162D03*
Y583162D03*
X2036452Y593200D03*
Y583200D03*
X2047419Y593162D03*
X2036452Y593200D03*
X2047419Y603162D03*
X2036452Y603200D03*
X2047419Y1195362D03*
X2036452Y1195400D03*
X2047419Y1205362D03*
X2036452Y1205400D03*
X2057419Y-19038D03*
Y-9038D03*
Y583162D03*
Y593162D03*
D03*
Y603162D03*
Y1195362D03*
Y1205362D03*
X2068539Y593172D03*
X2078539D03*
X2068539Y603172D03*
X2078539D03*
Y1195372D03*
X2068539D03*
X2078539Y1205372D03*
X2068539D03*
X2822321Y1877229D03*
G54D33*
X793879Y194881D03*
X789942Y204724D03*
X793879Y214567D03*
X805690Y188976D03*
Y220472D03*
X817501Y194881D03*
Y214567D03*
X821438Y204724D03*
X841240Y1407480D03*
X832154Y1411244D03*
X828390Y1420330D03*
X832154Y1429416D03*
X841240Y1433180D03*
X850326Y1411244D03*
X854090Y1420330D03*
X850326Y1429416D03*
X916545Y309459D03*
X911494Y321653D03*
X916545Y333847D03*
X940933Y309459D03*
X928739Y304408D03*
Y338898D03*
X940933Y333847D03*
X945984Y321653D03*
X1003390Y1420330D03*
X1016240Y1407480D03*
X1007154Y1411244D03*
Y1429416D03*
X1016240Y1433180D03*
X1025326Y1411244D03*
X1029090Y1420330D03*
X1025326Y1429416D03*
X1045847Y194881D03*
X1041910Y204724D03*
X1045847Y214567D03*
X1069469Y194881D03*
X1057658Y188976D03*
X1069469Y214567D03*
X1057658Y220472D03*
X1073406Y204724D03*
X2822321Y1581729D03*
G54D15*
X38346Y1420330D03*
X117932Y605380D03*
X763601Y605413D03*
X1094074Y605380D03*
X1739706Y605455D03*
X1819208Y1420330D03*
X2822321Y45129D03*
G54D24*
X238780Y1648385D03*
X230906Y1644448D03*
X238780Y1643661D03*
X230906Y1649173D03*
X238780Y1662558D03*
X230906Y1658621D03*
X238780Y1653110D03*
Y1657834D03*
X230906Y1653897D03*
Y1663346D03*
Y1682244D03*
X238780Y1681456D03*
X230906Y1677519D03*
X238780Y1676732D03*
X230906Y1672795D03*
X238780Y1667283D03*
Y1672007D03*
Y1681456D03*
X230906Y1668070D03*
Y1677519D03*
Y1682244D03*
X238780Y1695629D03*
Y1686180D03*
X230906Y1696417D03*
Y1691692D03*
X238780Y1700354D03*
Y1690905D03*
X230906Y1686968D03*
X238780Y1686180D03*
Y1695629D03*
X230906Y1691692D03*
Y1696417D03*
X238780Y1714527D03*
X230906Y1710590D03*
X238780Y1709803D03*
X230906Y1705866D03*
X238780Y1705078D03*
X230906Y1701141D03*
Y1715314D03*
X238780Y1700354D03*
Y1709803D03*
Y1714527D03*
X230906Y1705866D03*
Y1710590D03*
X238780Y1728700D03*
Y1723976D03*
X230906Y1724763D03*
Y1720039D03*
X238780Y1719251D03*
X230906Y1729488D03*
X238780Y1723976D03*
Y1728700D03*
X230906Y1720039D03*
Y1724763D03*
X238780Y1733425D03*
X230906Y1734212D03*
X254528Y1648385D03*
X246654Y1644448D03*
X254528Y1643661D03*
X246654Y1649173D03*
X254528Y1662558D03*
X246654Y1658621D03*
X254528Y1653110D03*
Y1657834D03*
X246654Y1653897D03*
Y1663346D03*
Y1682244D03*
X254528Y1681456D03*
X246654Y1677519D03*
X254528Y1676732D03*
X246654Y1672795D03*
X254528Y1667283D03*
Y1672007D03*
Y1681456D03*
X246654Y1668070D03*
Y1677519D03*
Y1682244D03*
Y1696417D03*
X254528Y1695629D03*
X246654Y1691692D03*
X254528Y1686180D03*
Y1700354D03*
Y1690905D03*
X246654Y1686968D03*
X254528Y1686180D03*
Y1695629D03*
X246654Y1691692D03*
Y1696417D03*
Y1705866D03*
X254528Y1714527D03*
X246654Y1710590D03*
X254528Y1709803D03*
Y1705078D03*
X246654Y1701141D03*
Y1715314D03*
X254528Y1700354D03*
Y1709803D03*
Y1714527D03*
X246654Y1705866D03*
Y1710590D03*
X254528Y1728700D03*
X246654Y1724763D03*
X254528Y1723976D03*
X246654Y1720039D03*
X254528Y1719251D03*
X246654Y1729488D03*
X254528Y1723976D03*
Y1728700D03*
X246654Y1720039D03*
Y1724763D03*
X254528Y1733425D03*
X246654Y1734212D03*
X270276Y1648385D03*
X262402Y1644448D03*
X270276Y1643661D03*
X262402Y1649173D03*
X270276Y1657834D03*
Y1653110D03*
Y1662558D03*
X262402Y1658621D03*
X270276Y1653110D03*
Y1657834D03*
X262402Y1653897D03*
Y1663346D03*
Y1682244D03*
X270276Y1681456D03*
X262402Y1677519D03*
X270276Y1676732D03*
X262402Y1672795D03*
X270276Y1667283D03*
Y1672007D03*
Y1681456D03*
X262402Y1668070D03*
Y1677519D03*
Y1682244D03*
Y1696417D03*
X270276Y1695629D03*
X262402Y1691692D03*
X270276Y1686180D03*
Y1700354D03*
Y1690905D03*
X262402Y1686968D03*
X270276Y1686180D03*
Y1695629D03*
X262402Y1691692D03*
Y1696417D03*
X270276Y1714527D03*
X262402Y1710590D03*
X270276Y1709803D03*
X262402Y1705866D03*
X270276Y1705078D03*
X262402Y1701141D03*
Y1715314D03*
X270276Y1700354D03*
Y1709803D03*
Y1714527D03*
X262402Y1705866D03*
Y1710590D03*
X270276Y1728700D03*
X262402Y1724763D03*
X270276Y1723976D03*
X262402Y1720039D03*
X270276Y1719251D03*
X262402Y1729488D03*
X270276Y1723976D03*
Y1728700D03*
X262402Y1720039D03*
Y1724763D03*
X270276Y1733425D03*
X262402Y1734212D03*
X286024Y1648385D03*
X278150Y1644448D03*
X286024Y1643661D03*
X278150Y1649173D03*
X286024Y1657834D03*
Y1653110D03*
Y1667283D03*
Y1662558D03*
X278150Y1658621D03*
X286024Y1653110D03*
Y1657834D03*
X278150Y1653897D03*
Y1663346D03*
Y1682244D03*
X286024Y1681456D03*
X278150Y1677519D03*
X286024Y1672007D03*
Y1676732D03*
X278150Y1672795D03*
X286024Y1667283D03*
Y1672007D03*
Y1681456D03*
X278150Y1668070D03*
Y1677519D03*
Y1682244D03*
Y1696417D03*
X286024Y1695629D03*
X278150Y1691692D03*
X286024Y1686180D03*
Y1700354D03*
Y1690905D03*
X278150Y1686968D03*
X286024Y1686180D03*
Y1695629D03*
X278150Y1691692D03*
Y1696417D03*
X286024Y1714527D03*
X278150Y1710590D03*
X286024Y1709803D03*
X278150Y1705866D03*
X286024Y1705078D03*
X278150Y1701141D03*
Y1715314D03*
X286024Y1700354D03*
Y1709803D03*
Y1714527D03*
X278150Y1705866D03*
Y1710590D03*
X286024Y1728700D03*
X278150Y1724763D03*
X286024Y1723976D03*
X278150Y1720039D03*
X286024Y1719251D03*
X278150Y1729488D03*
X286024Y1723976D03*
Y1728700D03*
X278150Y1720039D03*
Y1724763D03*
X286024Y1733425D03*
X278150Y1734212D03*
X297835Y1682244D03*
X305709Y1681456D03*
X297835Y1677519D03*
Y1672795D03*
X305709Y1672007D03*
X297835Y1677519D03*
X305709Y1676732D03*
X297835Y1682244D03*
X305709Y1681456D03*
Y1695629D03*
Y1686180D03*
X297835Y1696417D03*
Y1691692D03*
X305709Y1700354D03*
X297835Y1686968D03*
X305709Y1686180D03*
X297835Y1691692D03*
X305709Y1690905D03*
X297835Y1696417D03*
X305709Y1695629D03*
Y1714527D03*
X297835Y1710590D03*
X305709Y1709803D03*
X297835Y1705866D03*
Y1701141D03*
X305709Y1700354D03*
X297835Y1705866D03*
X305709Y1705078D03*
X297835Y1710590D03*
X305709Y1709803D03*
X297835Y1715314D03*
X305709Y1714527D03*
Y1728700D03*
Y1723976D03*
X297835Y1724763D03*
Y1720039D03*
D03*
X305709Y1719251D03*
X297835Y1724763D03*
X305709Y1723976D03*
X297835Y1729488D03*
X305709Y1728700D03*
X297835Y1734212D03*
X305709Y1733425D03*
X313583Y1682244D03*
X321457Y1681456D03*
X313583Y1677519D03*
Y1672795D03*
X321457Y1672007D03*
X313583Y1677519D03*
X321457Y1676732D03*
X313583Y1682244D03*
X321457Y1681456D03*
Y1695629D03*
Y1686180D03*
X313583Y1696417D03*
Y1691692D03*
X321457Y1700354D03*
X313583Y1686968D03*
X321457Y1686180D03*
X313583Y1691692D03*
X321457Y1690905D03*
X313583Y1696417D03*
X321457Y1695629D03*
Y1714527D03*
X313583Y1710590D03*
X321457Y1709803D03*
X313583Y1705866D03*
Y1701141D03*
X321457Y1700354D03*
X313583Y1705866D03*
X321457Y1705078D03*
X313583Y1710590D03*
X321457Y1709803D03*
X313583Y1715314D03*
X321457Y1714527D03*
Y1728700D03*
Y1723976D03*
X313583Y1724763D03*
Y1720039D03*
D03*
X321457Y1719251D03*
X313583Y1724763D03*
X321457Y1723976D03*
X313583Y1729488D03*
X321457Y1728700D03*
X313583Y1734212D03*
X321457Y1733425D03*
X329331Y1682244D03*
X337205Y1681456D03*
X329331Y1677519D03*
Y1672795D03*
X337205Y1672007D03*
X329331Y1677519D03*
X337205Y1676732D03*
X329331Y1682244D03*
X337205Y1681456D03*
Y1695629D03*
Y1686180D03*
X329331Y1696417D03*
Y1691692D03*
X337205Y1700354D03*
X329331Y1686968D03*
X337205Y1686180D03*
X329331Y1691692D03*
X337205Y1690905D03*
X329331Y1696417D03*
X337205Y1695629D03*
Y1714527D03*
X329331Y1710590D03*
X337205Y1709803D03*
X329331Y1705866D03*
Y1701141D03*
X337205Y1700354D03*
X329331Y1705866D03*
X337205Y1705078D03*
X329331Y1710590D03*
X337205Y1709803D03*
X329331Y1715314D03*
X337205Y1714527D03*
Y1728700D03*
Y1723976D03*
X329331Y1724763D03*
Y1720039D03*
D03*
X337205Y1719251D03*
X329331Y1724763D03*
X337205Y1723976D03*
X329331Y1729488D03*
X337205Y1728700D03*
X329331Y1734212D03*
X337205Y1733425D03*
X345079Y1682244D03*
X352953Y1681456D03*
X345079Y1677519D03*
Y1672795D03*
X352953Y1672007D03*
X345079Y1677519D03*
X352953Y1676732D03*
X345079Y1682244D03*
X352953Y1681456D03*
Y1695629D03*
Y1686180D03*
X345079Y1696417D03*
Y1691692D03*
X352953Y1700354D03*
X345079Y1686968D03*
X352953Y1686180D03*
X345079Y1691692D03*
X352953Y1690905D03*
X345079Y1696417D03*
X352953Y1695629D03*
Y1714527D03*
X345079Y1710590D03*
X352953Y1709803D03*
X345079Y1705866D03*
Y1701141D03*
X352953Y1700354D03*
X345079Y1705866D03*
X352953Y1705078D03*
X345079Y1710590D03*
X352953Y1709803D03*
X345079Y1715314D03*
X352953Y1714527D03*
Y1728700D03*
Y1723976D03*
X345079Y1724763D03*
Y1720039D03*
D03*
X352953Y1719251D03*
X345079Y1724763D03*
X352953Y1723976D03*
X345079Y1729488D03*
X352953Y1728700D03*
X345079Y1734212D03*
X352953Y1733425D03*
X495079Y1682244D03*
Y1677519D03*
X502953Y1681456D03*
X495079Y1672795D03*
Y1677519D03*
Y1682244D03*
X502953Y1695629D03*
Y1686180D03*
X495079Y1696417D03*
Y1691692D03*
X502953Y1700354D03*
X495079Y1686968D03*
Y1691692D03*
Y1696417D03*
Y1710590D03*
Y1705866D03*
X502953Y1714527D03*
Y1709803D03*
X495079Y1701141D03*
Y1705866D03*
Y1710590D03*
Y1715314D03*
X502953Y1728700D03*
Y1723976D03*
X495079Y1724763D03*
Y1720039D03*
D03*
Y1724763D03*
Y1729488D03*
Y1734212D03*
X510827Y1682244D03*
Y1677519D03*
X518701Y1681456D03*
X502953Y1672007D03*
X510827Y1672795D03*
X502953Y1676732D03*
X510827Y1677519D03*
X518701Y1676732D03*
X502953Y1681456D03*
X510827Y1682244D03*
X518701Y1695629D03*
Y1686180D03*
X510827Y1696417D03*
Y1691692D03*
X518701Y1700354D03*
X502953Y1686180D03*
X510827Y1686968D03*
X502953Y1690905D03*
X510827Y1691692D03*
X518701Y1690905D03*
X502953Y1695629D03*
X510827Y1696417D03*
Y1710590D03*
Y1705866D03*
X518701Y1714527D03*
Y1709803D03*
X502953Y1700354D03*
X510827Y1701141D03*
X502953Y1705078D03*
X510827Y1705866D03*
X518701Y1705078D03*
X502953Y1709803D03*
X510827Y1710590D03*
X502953Y1714527D03*
X510827Y1715314D03*
X518701Y1728700D03*
Y1723976D03*
X510827Y1724763D03*
Y1720039D03*
X502953Y1719251D03*
X510827Y1720039D03*
X518701Y1719251D03*
X502953Y1723976D03*
X510827Y1724763D03*
X502953Y1728700D03*
X510827Y1729488D03*
X502953Y1733425D03*
X510827Y1734212D03*
X518701Y1733425D03*
X526575Y1682244D03*
X534449Y1681456D03*
X526575Y1677519D03*
X518701Y1672007D03*
X526575Y1672795D03*
X534449Y1672007D03*
X526575Y1677519D03*
X534449Y1676732D03*
X518701Y1681456D03*
X526575Y1682244D03*
X534449Y1681456D03*
Y1695629D03*
Y1686180D03*
X526575Y1696417D03*
Y1691692D03*
X534449Y1700354D03*
X518701Y1686180D03*
X526575Y1686968D03*
X534449Y1686180D03*
X526575Y1691692D03*
X534449Y1690905D03*
X518701Y1695629D03*
X526575Y1696417D03*
X534449Y1695629D03*
Y1714527D03*
X526575Y1710590D03*
X534449Y1709803D03*
X526575Y1705866D03*
X518701Y1700354D03*
X526575Y1701141D03*
X534449Y1700354D03*
X526575Y1705866D03*
X534449Y1705078D03*
X518701Y1709803D03*
X526575Y1710590D03*
X534449Y1709803D03*
X518701Y1714527D03*
X526575Y1715314D03*
X534449Y1714527D03*
Y1728700D03*
Y1723976D03*
X526575Y1724763D03*
Y1720039D03*
D03*
X534449Y1719251D03*
X518701Y1723976D03*
X526575Y1724763D03*
X534449Y1723976D03*
X518701Y1728700D03*
X526575Y1729488D03*
X534449Y1728700D03*
X526575Y1734212D03*
X534449Y1733425D03*
X542323Y1682244D03*
X550197Y1681456D03*
X542323Y1677519D03*
Y1672795D03*
X550197Y1672007D03*
X542323Y1677519D03*
X550197Y1676732D03*
X542323Y1682244D03*
X550197Y1681456D03*
Y1695629D03*
Y1686180D03*
X542323Y1696417D03*
Y1691692D03*
X550197Y1700354D03*
X542323Y1686968D03*
X550197Y1686180D03*
X542323Y1691692D03*
X550197Y1690905D03*
X542323Y1696417D03*
X550197Y1695629D03*
Y1714527D03*
X542323Y1710590D03*
X550197Y1709803D03*
X542323Y1705866D03*
Y1701141D03*
X550197Y1700354D03*
X542323Y1705866D03*
X550197Y1705078D03*
X542323Y1710590D03*
X550197Y1709803D03*
X542323Y1715314D03*
X550197Y1714527D03*
Y1728700D03*
Y1723976D03*
X542323Y1724763D03*
Y1720039D03*
D03*
X550197Y1719251D03*
X542323Y1724763D03*
X550197Y1723976D03*
X542323Y1729488D03*
X550197Y1728700D03*
X542323Y1734212D03*
X550197Y1733425D03*
X562008Y1682244D03*
Y1677519D03*
Y1672795D03*
Y1677519D03*
Y1682244D03*
Y1696417D03*
Y1691692D03*
Y1686968D03*
Y1691692D03*
Y1696417D03*
Y1710590D03*
Y1705866D03*
Y1701141D03*
Y1705866D03*
Y1710590D03*
Y1715314D03*
Y1724763D03*
Y1720039D03*
D03*
Y1724763D03*
Y1729488D03*
Y1734212D03*
X569882Y1681456D03*
X577756Y1682244D03*
Y1677519D03*
X569882Y1672007D03*
X577756Y1672795D03*
X569882Y1676732D03*
X577756Y1677519D03*
X569882Y1681456D03*
X577756Y1682244D03*
X569882Y1695629D03*
X577756Y1696417D03*
Y1691692D03*
X569882Y1686180D03*
Y1700354D03*
Y1686180D03*
X577756Y1686968D03*
X569882Y1690905D03*
X577756Y1691692D03*
X569882Y1695629D03*
X577756Y1696417D03*
X569882Y1714527D03*
Y1709803D03*
X577756Y1710590D03*
Y1705866D03*
X569882Y1700354D03*
X577756Y1701141D03*
X569882Y1705078D03*
X577756Y1705866D03*
X569882Y1709803D03*
X577756Y1710590D03*
X569882Y1714527D03*
X577756Y1715314D03*
X569882Y1728700D03*
Y1723976D03*
X577756Y1724763D03*
Y1720039D03*
X569882Y1719251D03*
X577756Y1720039D03*
X569882Y1723976D03*
X577756Y1724763D03*
X569882Y1728700D03*
X577756Y1729488D03*
X569882Y1733425D03*
X577756Y1734212D03*
X593504Y1682244D03*
Y1677519D03*
X585630Y1681456D03*
X601378D03*
X585630Y1672007D03*
X593504Y1672795D03*
X585630Y1676732D03*
X593504Y1677519D03*
X585630Y1681456D03*
X593504Y1682244D03*
X601378Y1695629D03*
Y1686180D03*
X593504Y1696417D03*
Y1691692D03*
X585630Y1695629D03*
Y1686180D03*
Y1700354D03*
X601378D03*
X585630Y1686180D03*
X593504Y1686968D03*
X585630Y1690905D03*
X593504Y1691692D03*
X585630Y1695629D03*
X593504Y1696417D03*
Y1710590D03*
Y1705866D03*
X585630Y1714527D03*
Y1709803D03*
X601378Y1714527D03*
Y1709803D03*
X585630Y1700354D03*
X593504Y1701141D03*
X585630Y1705078D03*
X593504Y1705866D03*
X585630Y1709803D03*
X593504Y1710590D03*
X585630Y1714527D03*
X593504Y1715314D03*
X601378Y1728700D03*
Y1723976D03*
X593504Y1724763D03*
Y1720039D03*
X585630Y1728700D03*
Y1723976D03*
Y1719251D03*
X593504Y1720039D03*
X585630Y1723976D03*
X593504Y1724763D03*
X585630Y1728700D03*
X593504Y1729488D03*
X585630Y1733425D03*
X593504Y1734212D03*
X609252Y1682244D03*
Y1677519D03*
X617126Y1681456D03*
X601378Y1672007D03*
X609252Y1672795D03*
X601378Y1676732D03*
X609252Y1677519D03*
X601378Y1681456D03*
X609252Y1682244D03*
X617126Y1695629D03*
Y1686180D03*
X609252Y1696417D03*
Y1691692D03*
X617126Y1700354D03*
X601378Y1686180D03*
X609252Y1686968D03*
X601378Y1690905D03*
X609252Y1691692D03*
X601378Y1695629D03*
X609252Y1696417D03*
Y1710590D03*
Y1705866D03*
X617126Y1714527D03*
Y1709803D03*
X601378Y1700354D03*
X609252Y1701141D03*
X601378Y1705078D03*
X609252Y1705866D03*
X601378Y1709803D03*
X609252Y1710590D03*
X601378Y1714527D03*
X609252Y1715314D03*
X617126Y1728700D03*
Y1723976D03*
X609252Y1724763D03*
Y1720039D03*
X601378Y1719251D03*
X609252Y1720039D03*
X601378Y1723976D03*
X609252Y1724763D03*
X601378Y1728700D03*
X609252Y1729488D03*
X601378Y1733425D03*
X609252Y1734212D03*
X617126Y1672007D03*
Y1676732D03*
Y1681456D03*
Y1686180D03*
Y1690905D03*
Y1695629D03*
Y1700354D03*
Y1705078D03*
Y1709803D03*
Y1714527D03*
Y1719251D03*
Y1723976D03*
Y1728700D03*
Y1733425D03*
X828780Y1694890D03*
Y1684890D03*
X818780Y1694890D03*
Y1684890D03*
X828780Y1704890D03*
X818780D03*
X828780Y1714890D03*
X818780D03*
X853780Y1694890D03*
Y1684890D03*
Y1704890D03*
Y1714890D03*
X863780Y1694890D03*
Y1684890D03*
Y1704890D03*
Y1714890D03*
X888780Y1684890D03*
Y1694890D03*
Y1704890D03*
Y1714890D03*
X898780Y1684890D03*
Y1694890D03*
Y1704890D03*
Y1714890D03*
X918780Y1684890D03*
Y1694890D03*
Y1704890D03*
Y1714890D03*
X928780Y1684890D03*
X938780D03*
X928780Y1694890D03*
X938780D03*
X928780Y1704890D03*
X938780D03*
X928780Y1714890D03*
X938780D03*
X958780Y1694890D03*
Y1684890D03*
Y1704890D03*
Y1714890D03*
X968780Y1694890D03*
Y1684890D03*
Y1704890D03*
Y1714890D03*
X993780Y1684890D03*
Y1694890D03*
X1003780Y1684890D03*
Y1694890D03*
X993780Y1704890D03*
Y1714890D03*
X1003780Y1704890D03*
Y1714890D03*
X1028780Y1684890D03*
Y1694890D03*
X1038780Y1684890D03*
Y1694890D03*
X1028780Y1704890D03*
Y1714890D03*
X1038780Y1704890D03*
Y1714890D03*
X1238780Y1682244D03*
X1246654Y1681456D03*
X1238780Y1677519D03*
Y1672795D03*
X1246654Y1672007D03*
X1238780Y1677519D03*
X1246654Y1676732D03*
X1238780Y1682244D03*
X1246654Y1681456D03*
X1238780Y1696417D03*
X1246654Y1695629D03*
X1238780Y1691692D03*
X1246654Y1686180D03*
Y1700354D03*
X1238780Y1686968D03*
X1246654Y1686180D03*
X1238780Y1691692D03*
X1246654Y1690905D03*
X1238780Y1696417D03*
X1246654Y1695629D03*
X1238780Y1710590D03*
X1246654Y1709803D03*
X1238780Y1705866D03*
X1246654Y1714527D03*
X1238780Y1701141D03*
X1246654Y1700354D03*
X1238780Y1705866D03*
X1246654Y1705078D03*
X1238780Y1710590D03*
X1246654Y1709803D03*
X1238780Y1715314D03*
X1246654Y1714527D03*
Y1728700D03*
X1238780Y1724763D03*
X1246654Y1723976D03*
X1238780Y1720039D03*
D03*
X1246654Y1719251D03*
X1238780Y1724763D03*
X1246654Y1723976D03*
X1238780Y1729488D03*
X1246654Y1728700D03*
X1238780Y1734212D03*
X1246654Y1733425D03*
X1254528Y1682244D03*
X1262402Y1681456D03*
X1254528Y1677519D03*
Y1672795D03*
X1262402Y1672007D03*
X1254528Y1677519D03*
X1262402Y1676732D03*
X1254528Y1682244D03*
X1262402Y1681456D03*
X1254528Y1696417D03*
X1262402Y1695629D03*
X1254528Y1691692D03*
X1262402Y1686180D03*
Y1700354D03*
X1254528Y1686968D03*
X1262402Y1686180D03*
X1254528Y1691692D03*
X1262402Y1690905D03*
X1254528Y1696417D03*
X1262402Y1695629D03*
Y1714527D03*
X1254528Y1710590D03*
X1262402Y1709803D03*
X1254528Y1705866D03*
Y1701141D03*
X1262402Y1700354D03*
X1254528Y1705866D03*
X1262402Y1705078D03*
X1254528Y1710590D03*
X1262402Y1709803D03*
X1254528Y1715314D03*
X1262402Y1714527D03*
Y1728700D03*
X1254528Y1724763D03*
X1262402Y1723976D03*
X1254528Y1720039D03*
D03*
X1262402Y1719251D03*
X1254528Y1724763D03*
X1262402Y1723976D03*
X1254528Y1729488D03*
X1262402Y1728700D03*
X1254528Y1734212D03*
X1262402Y1733425D03*
X1270276Y1682244D03*
X1278150Y1681456D03*
X1270276Y1677519D03*
Y1672795D03*
X1278150Y1672007D03*
X1270276Y1677519D03*
X1278150Y1676732D03*
X1270276Y1682244D03*
X1278150Y1681456D03*
X1270276Y1696417D03*
X1278150Y1695629D03*
X1270276Y1691692D03*
X1278150Y1686180D03*
Y1700354D03*
X1270276Y1686968D03*
X1278150Y1686180D03*
X1270276Y1691692D03*
X1278150Y1690905D03*
X1270276Y1696417D03*
X1278150Y1695629D03*
Y1714527D03*
X1270276Y1710590D03*
X1278150Y1709803D03*
X1270276Y1705866D03*
Y1701141D03*
X1278150Y1700354D03*
X1270276Y1705866D03*
X1278150Y1705078D03*
X1270276Y1710590D03*
X1278150Y1709803D03*
X1270276Y1715314D03*
X1278150Y1714527D03*
Y1728700D03*
X1270276Y1724763D03*
X1278150Y1723976D03*
X1270276Y1720039D03*
D03*
X1278150Y1719251D03*
X1270276Y1724763D03*
X1278150Y1723976D03*
X1270276Y1729488D03*
X1278150Y1728700D03*
X1270276Y1734212D03*
X1278150Y1733425D03*
X1286024Y1682244D03*
X1293898Y1681456D03*
X1286024Y1677519D03*
Y1672795D03*
X1293898Y1672007D03*
X1286024Y1677519D03*
X1293898Y1676732D03*
X1286024Y1682244D03*
X1293898Y1681456D03*
X1286024Y1696417D03*
X1293898Y1695629D03*
X1286024Y1691692D03*
X1293898Y1686180D03*
Y1700354D03*
X1286024Y1686968D03*
X1293898Y1686180D03*
X1286024Y1691692D03*
X1293898Y1690905D03*
X1286024Y1696417D03*
X1293898Y1695629D03*
Y1714527D03*
X1286024Y1710590D03*
X1293898Y1709803D03*
X1286024Y1705866D03*
Y1701141D03*
X1293898Y1700354D03*
X1286024Y1705866D03*
X1293898Y1705078D03*
X1286024Y1710590D03*
X1293898Y1709803D03*
X1286024Y1715314D03*
X1293898Y1714527D03*
Y1728700D03*
X1286024Y1724763D03*
X1293898Y1723976D03*
X1286024Y1720039D03*
D03*
X1293898Y1719251D03*
X1286024Y1724763D03*
X1293898Y1723976D03*
X1286024Y1729488D03*
X1293898Y1728700D03*
X1286024Y1734212D03*
X1293898Y1733425D03*
X1305709Y1682244D03*
X1313583Y1681456D03*
X1305709Y1677519D03*
Y1672795D03*
X1313583Y1672007D03*
X1305709Y1677519D03*
X1313583Y1676732D03*
X1305709Y1682244D03*
X1313583Y1681456D03*
Y1695629D03*
Y1686180D03*
X1305709Y1696417D03*
Y1691692D03*
X1313583Y1700354D03*
X1305709Y1686968D03*
X1313583Y1686180D03*
X1305709Y1691692D03*
X1313583Y1690905D03*
X1305709Y1696417D03*
X1313583Y1695629D03*
X1305709Y1710590D03*
X1313583Y1709803D03*
X1305709Y1705866D03*
X1313583Y1714527D03*
X1305709Y1701141D03*
X1313583Y1700354D03*
X1305709Y1705866D03*
X1313583Y1705078D03*
X1305709Y1710590D03*
X1313583Y1709803D03*
X1305709Y1715314D03*
X1313583Y1714527D03*
Y1728700D03*
Y1723976D03*
X1305709Y1724763D03*
Y1720039D03*
D03*
X1313583Y1719251D03*
X1305709Y1724763D03*
X1313583Y1723976D03*
X1305709Y1729488D03*
X1313583Y1728700D03*
X1305709Y1734212D03*
X1313583Y1733425D03*
X1321457Y1682244D03*
X1329331Y1681456D03*
X1321457Y1677519D03*
Y1672795D03*
X1329331Y1672007D03*
X1321457Y1677519D03*
X1329331Y1676732D03*
X1321457Y1682244D03*
X1329331Y1681456D03*
Y1695629D03*
Y1686180D03*
X1321457Y1696417D03*
Y1691692D03*
X1329331Y1700354D03*
X1321457Y1686968D03*
X1329331Y1686180D03*
X1321457Y1691692D03*
X1329331Y1690905D03*
X1321457Y1696417D03*
X1329331Y1695629D03*
Y1714527D03*
X1321457Y1710590D03*
X1329331Y1709803D03*
X1321457Y1705866D03*
Y1701141D03*
X1329331Y1700354D03*
X1321457Y1705866D03*
X1329331Y1705078D03*
X1321457Y1710590D03*
X1329331Y1709803D03*
X1321457Y1715314D03*
X1329331Y1714527D03*
Y1728700D03*
Y1723976D03*
X1321457Y1724763D03*
Y1720039D03*
D03*
X1329331Y1719251D03*
X1321457Y1724763D03*
X1329331Y1723976D03*
X1321457Y1729488D03*
X1329331Y1728700D03*
X1321457Y1734212D03*
X1329331Y1733425D03*
X1337205Y1682244D03*
X1345079Y1681456D03*
X1337205Y1677519D03*
Y1672795D03*
X1345079Y1672007D03*
X1337205Y1677519D03*
X1345079Y1676732D03*
X1337205Y1682244D03*
X1345079Y1681456D03*
Y1695629D03*
Y1686180D03*
X1337205Y1696417D03*
Y1691692D03*
X1345079Y1700354D03*
X1337205Y1686968D03*
X1345079Y1686180D03*
X1337205Y1691692D03*
X1345079Y1690905D03*
X1337205Y1696417D03*
X1345079Y1695629D03*
Y1714527D03*
X1337205Y1710590D03*
X1345079Y1709803D03*
X1337205Y1705866D03*
Y1701141D03*
X1345079Y1700354D03*
X1337205Y1705866D03*
X1345079Y1705078D03*
X1337205Y1710590D03*
X1345079Y1709803D03*
X1337205Y1715314D03*
X1345079Y1714527D03*
Y1728700D03*
Y1723976D03*
X1337205Y1724763D03*
Y1720039D03*
D03*
X1345079Y1719251D03*
X1337205Y1724763D03*
X1345079Y1723976D03*
X1337205Y1729488D03*
X1345079Y1728700D03*
X1337205Y1734212D03*
X1345079Y1733425D03*
X1352953Y1682244D03*
X1360827Y1681456D03*
X1352953Y1677519D03*
Y1672795D03*
X1360827Y1672007D03*
X1352953Y1677519D03*
X1360827Y1676732D03*
X1352953Y1682244D03*
X1360827Y1681456D03*
X1352953Y1696417D03*
X1360827Y1695629D03*
X1352953Y1691692D03*
X1360827Y1686180D03*
Y1700354D03*
X1352953Y1686968D03*
X1360827Y1686180D03*
X1352953Y1691692D03*
X1360827Y1690905D03*
X1352953Y1696417D03*
X1360827Y1695629D03*
Y1714527D03*
X1352953Y1710590D03*
X1360827Y1709803D03*
X1352953Y1705866D03*
Y1701141D03*
X1360827Y1700354D03*
X1352953Y1705866D03*
X1360827Y1705078D03*
X1352953Y1710590D03*
X1360827Y1709803D03*
X1352953Y1715314D03*
X1360827Y1714527D03*
Y1728700D03*
X1352953Y1724763D03*
X1360827Y1723976D03*
X1352953Y1720039D03*
D03*
X1360827Y1719251D03*
X1352953Y1724763D03*
X1360827Y1723976D03*
X1352953Y1729488D03*
X1360827Y1728700D03*
X1352953Y1734212D03*
X1360827Y1733425D03*
X1502953Y1682244D03*
X1510827Y1681456D03*
X1502953Y1677519D03*
Y1672795D03*
X1510827Y1672007D03*
X1502953Y1677519D03*
X1510827Y1676732D03*
X1502953Y1682244D03*
X1510827Y1681456D03*
Y1695629D03*
Y1686180D03*
X1502953Y1696417D03*
Y1691692D03*
X1510827Y1700354D03*
X1502953Y1686968D03*
X1510827Y1686180D03*
X1502953Y1691692D03*
X1510827Y1690905D03*
X1502953Y1696417D03*
X1510827Y1695629D03*
Y1714527D03*
X1502953Y1710590D03*
X1510827Y1709803D03*
X1502953Y1705866D03*
Y1701141D03*
X1510827Y1700354D03*
X1502953Y1705866D03*
X1510827Y1705078D03*
X1502953Y1710590D03*
X1510827Y1709803D03*
X1502953Y1715314D03*
X1510827Y1714527D03*
Y1728700D03*
Y1723976D03*
X1502953Y1724763D03*
Y1720039D03*
D03*
X1510827Y1719251D03*
X1502953Y1724763D03*
X1510827Y1723976D03*
X1502953Y1729488D03*
X1510827Y1728700D03*
X1502953Y1734212D03*
X1510827Y1733425D03*
X1518701Y1682244D03*
X1526575Y1681456D03*
X1518701Y1677519D03*
Y1672795D03*
X1526575Y1672007D03*
X1518701Y1677519D03*
X1526575Y1676732D03*
X1518701Y1682244D03*
X1526575Y1681456D03*
Y1695629D03*
Y1686180D03*
X1518701Y1696417D03*
Y1691692D03*
X1526575Y1700354D03*
X1518701Y1686968D03*
X1526575Y1686180D03*
X1518701Y1691692D03*
X1526575Y1690905D03*
X1518701Y1696417D03*
X1526575Y1695629D03*
Y1714527D03*
X1518701Y1710590D03*
X1526575Y1709803D03*
X1518701Y1705866D03*
Y1701141D03*
X1526575Y1700354D03*
X1518701Y1705866D03*
X1526575Y1705078D03*
X1518701Y1710590D03*
X1526575Y1709803D03*
X1518701Y1715314D03*
X1526575Y1714527D03*
Y1728700D03*
Y1723976D03*
X1518701Y1724763D03*
Y1720039D03*
D03*
X1526575Y1719251D03*
X1518701Y1724763D03*
X1526575Y1723976D03*
X1518701Y1729488D03*
X1526575Y1728700D03*
X1518701Y1734212D03*
X1526575Y1733425D03*
X1534449Y1682244D03*
X1542323Y1681456D03*
X1534449Y1677519D03*
Y1672795D03*
X1542323Y1672007D03*
X1534449Y1677519D03*
X1542323Y1676732D03*
X1534449Y1682244D03*
X1542323Y1681456D03*
Y1695629D03*
Y1686180D03*
X1534449Y1696417D03*
Y1691692D03*
X1542323Y1700354D03*
X1534449Y1686968D03*
X1542323Y1686180D03*
X1534449Y1691692D03*
X1542323Y1690905D03*
X1534449Y1696417D03*
X1542323Y1695629D03*
Y1714527D03*
X1534449Y1710590D03*
X1542323Y1709803D03*
X1534449Y1705866D03*
Y1701141D03*
X1542323Y1700354D03*
X1534449Y1705866D03*
X1542323Y1705078D03*
X1534449Y1710590D03*
X1542323Y1709803D03*
X1534449Y1715314D03*
X1542323Y1714527D03*
Y1728700D03*
Y1723976D03*
X1534449Y1724763D03*
Y1720039D03*
D03*
X1542323Y1719251D03*
X1534449Y1724763D03*
X1542323Y1723976D03*
X1534449Y1729488D03*
X1542323Y1728700D03*
X1534449Y1734212D03*
X1542323Y1733425D03*
X1550197Y1682244D03*
X1558071Y1681456D03*
X1550197Y1677519D03*
Y1672795D03*
X1558071Y1672007D03*
X1550197Y1677519D03*
X1558071Y1676732D03*
X1550197Y1682244D03*
X1558071Y1681456D03*
Y1695629D03*
Y1686180D03*
X1550197Y1696417D03*
Y1691692D03*
X1558071Y1700354D03*
X1550197Y1686968D03*
X1558071Y1686180D03*
X1550197Y1691692D03*
X1558071Y1690905D03*
X1550197Y1696417D03*
X1558071Y1695629D03*
Y1714527D03*
X1550197Y1710590D03*
X1558071Y1709803D03*
X1550197Y1705866D03*
Y1701141D03*
X1558071Y1700354D03*
X1550197Y1705866D03*
X1558071Y1705078D03*
X1550197Y1710590D03*
X1558071Y1709803D03*
X1550197Y1715314D03*
X1558071Y1714527D03*
Y1728700D03*
Y1723976D03*
X1550197Y1724763D03*
Y1720039D03*
D03*
X1558071Y1719251D03*
X1550197Y1724763D03*
X1558071Y1723976D03*
X1550197Y1729488D03*
X1558071Y1728700D03*
X1550197Y1734212D03*
X1558071Y1733425D03*
X1569882Y1682244D03*
Y1677519D03*
X1577756Y1681456D03*
X1569882Y1672795D03*
Y1677519D03*
Y1682244D03*
X1577756Y1695629D03*
Y1686180D03*
X1569882Y1696417D03*
Y1691692D03*
X1577756Y1700354D03*
X1569882Y1686968D03*
Y1691692D03*
Y1696417D03*
Y1710590D03*
Y1705866D03*
X1577756Y1714527D03*
Y1709803D03*
X1569882Y1701141D03*
Y1705866D03*
Y1710590D03*
Y1715314D03*
X1577756Y1728700D03*
Y1723976D03*
X1569882Y1724763D03*
Y1720039D03*
D03*
Y1724763D03*
Y1729488D03*
Y1734212D03*
X1585630Y1682244D03*
Y1677519D03*
X1593504Y1681456D03*
X1577756Y1672007D03*
X1585630Y1672795D03*
X1577756Y1676732D03*
X1585630Y1677519D03*
X1577756Y1681456D03*
X1585630Y1682244D03*
X1593504Y1695629D03*
Y1686180D03*
X1585630Y1696417D03*
Y1691692D03*
X1593504Y1700354D03*
X1577756Y1686180D03*
X1585630Y1686968D03*
X1577756Y1690905D03*
X1585630Y1691692D03*
X1577756Y1695629D03*
X1585630Y1696417D03*
Y1710590D03*
Y1705866D03*
X1593504Y1714527D03*
Y1709803D03*
X1577756Y1700354D03*
X1585630Y1701141D03*
X1577756Y1705078D03*
X1585630Y1705866D03*
X1577756Y1709803D03*
X1585630Y1710590D03*
X1577756Y1714527D03*
X1585630Y1715314D03*
X1593504Y1728700D03*
Y1723976D03*
X1585630Y1724763D03*
Y1720039D03*
X1577756Y1719251D03*
X1585630Y1720039D03*
X1577756Y1723976D03*
X1585630Y1724763D03*
X1577756Y1728700D03*
X1585630Y1729488D03*
X1577756Y1733425D03*
X1585630Y1734212D03*
X1601378Y1682244D03*
Y1677519D03*
X1609252Y1681456D03*
X1593504Y1672007D03*
X1601378Y1672795D03*
X1593504Y1676732D03*
X1601378Y1677519D03*
X1593504Y1681456D03*
X1601378Y1682244D03*
X1609252Y1695629D03*
Y1686180D03*
X1601378Y1696417D03*
Y1691692D03*
X1609252Y1700354D03*
X1593504Y1686180D03*
X1601378Y1686968D03*
X1593504Y1690905D03*
X1601378Y1691692D03*
X1593504Y1695629D03*
X1601378Y1696417D03*
Y1710590D03*
Y1705866D03*
X1609252Y1714527D03*
Y1709803D03*
X1593504Y1700354D03*
X1601378Y1701141D03*
X1593504Y1705078D03*
X1601378Y1705866D03*
X1593504Y1709803D03*
X1601378Y1710590D03*
X1593504Y1714527D03*
X1601378Y1715314D03*
X1609252Y1728700D03*
Y1723976D03*
X1601378Y1724763D03*
Y1720039D03*
X1593504Y1719251D03*
X1601378Y1720039D03*
X1593504Y1723976D03*
X1601378Y1724763D03*
X1593504Y1728700D03*
X1601378Y1729488D03*
X1593504Y1733425D03*
X1601378Y1734212D03*
X1617126Y1682244D03*
Y1677519D03*
X1625000Y1681456D03*
X1609252Y1672007D03*
X1617126Y1672795D03*
X1609252Y1676732D03*
X1617126Y1677519D03*
X1625000Y1676732D03*
X1609252Y1681456D03*
X1617126Y1682244D03*
X1625000Y1695629D03*
Y1686180D03*
X1617126Y1696417D03*
Y1691692D03*
X1625000Y1700354D03*
X1609252Y1686180D03*
X1617126Y1686968D03*
X1609252Y1690905D03*
X1617126Y1691692D03*
X1625000Y1690905D03*
X1609252Y1695629D03*
X1617126Y1696417D03*
Y1710590D03*
Y1705866D03*
X1625000Y1714527D03*
Y1709803D03*
X1609252Y1700354D03*
X1617126Y1701141D03*
X1609252Y1705078D03*
X1617126Y1705866D03*
X1625000Y1705078D03*
X1609252Y1709803D03*
X1617126Y1710590D03*
X1609252Y1714527D03*
X1617126Y1715314D03*
X1625000Y1728700D03*
Y1723976D03*
X1617126Y1724763D03*
Y1720039D03*
X1609252Y1719251D03*
X1617126Y1720039D03*
X1625000Y1719251D03*
X1609252Y1723976D03*
X1617126Y1724763D03*
X1609252Y1728700D03*
X1617126Y1729488D03*
X1609252Y1733425D03*
X1617126Y1734212D03*
X1625000Y1733425D03*
Y1672007D03*
Y1681456D03*
Y1686180D03*
Y1695629D03*
Y1700354D03*
Y1709803D03*
Y1714527D03*
Y1723976D03*
Y1728700D03*
X1956183Y2890790D03*
X1955500Y3349622D03*
X1954950Y3639362D03*
X2822321Y1404429D03*
Y1640829D03*
Y1699929D03*
X2833595Y3647637D03*
G54D43*
X1881720Y988279D03*
X1886720Y1001463D03*
X1876720D03*
X1875836Y1303980D03*
X1885836D03*
X1880836Y1317164D03*
X1881211Y1350983D03*
X1886211Y1364167D03*
X1876211D03*
X1876165Y1669023D03*
X1886165D03*
X1881165Y1682207D03*
X1902608Y988322D03*
X1897608Y1001506D03*
X1898086Y1305044D03*
X1903086Y1318228D03*
X1902682Y1351295D03*
X1897682Y1364479D03*
X1902402Y1683256D03*
X1897402Y1670072D03*
X1907608Y1001506D03*
X1908086Y1305044D03*
X1907682Y1364479D03*
X1907402Y1670072D03*
X1930200Y1349548D03*
X1935200Y1362732D03*
X1925200D03*
X1929695Y1683220D03*
X1924695Y1670036D03*
X1934695D03*
X1951178Y1349597D03*
X1946178Y1362781D03*
X1950484Y1683497D03*
X1945484Y1670313D03*
X1967697Y1362790D03*
X1956178Y1362781D03*
X1966555Y1669946D03*
X1955484Y1670313D03*
X1972697Y1349606D03*
X1977697Y1362790D03*
X1976555Y1669946D03*
X1971555Y1683130D03*
X1993618Y1349897D03*
X1988618Y1363081D03*
X1998618D03*
X1998147Y1669691D03*
X1988147D03*
X1993147Y1682875D03*
X2822321Y1168029D03*
G54D16*
X49280Y337402D03*
X41870Y1511291D03*
X441043Y1672205D03*
Y1698268D03*
Y1718465D03*
X1416437Y1672204D03*
Y1698267D03*
Y1718464D03*
X1808192Y1569255D03*
X1812980Y502472D03*
X2822321Y281529D03*
Y340629D03*
G54D25*
X277098Y185236D03*
X395208D03*
X2822321Y990729D03*
G54D34*
X805690Y204724D03*
X1057658D03*
X2822321Y104229D03*
G54D44*
G01X2794720Y1427303D02*
X4327110D01*
Y1382553D01*
X2779980D01*
Y1427303D01*
X2794720D01*
G01X2785960Y1662792D02*
X3820110D01*
Y1652422D01*
X4633780D01*
Y1592392D01*
X3833750D01*
Y1622412D01*
X2784320D01*
Y1662792D01*
X2785960D01*
G01X2784870Y1722822D02*
X4657790D01*
Y1660062D01*
X3833750D01*
Y1675892D01*
X2784870D01*
Y1722822D01*
G54D17*
X40120Y744554D03*
Y1000853D03*
Y1287664D03*
X69820Y744554D03*
Y1000853D03*
Y1287664D03*
X99520Y744554D03*
Y1000853D03*
Y1287664D03*
X129220Y744554D03*
Y1000853D03*
Y1287664D03*
X158920Y744554D03*
Y1000853D03*
Y1287664D03*
X188620Y744554D03*
Y1000853D03*
Y1287664D03*
X218320Y744554D03*
Y1000853D03*
Y1287664D03*
X248020Y744554D03*
Y1000853D03*
Y1287664D03*
X633320Y744554D03*
Y1000853D03*
Y1287664D03*
X663020Y744554D03*
Y1000853D03*
Y1287664D03*
X692720Y744554D03*
Y1000853D03*
Y1287664D03*
X722420Y744554D03*
Y1000853D03*
Y1287664D03*
X752120Y744554D03*
Y1000853D03*
Y1287664D03*
X781820Y744554D03*
Y1000853D03*
Y1287664D03*
X811520Y744554D03*
Y1000853D03*
Y1287664D03*
X841220Y744554D03*
Y1000853D03*
Y1287664D03*
X1016262Y744554D03*
Y1000853D03*
Y1287664D03*
X1045962Y744554D03*
Y1000853D03*
Y1287664D03*
X1075662Y744554D03*
Y1000853D03*
Y1287664D03*
X1105362Y744554D03*
Y1000853D03*
Y1287664D03*
X1135062Y744554D03*
Y1000853D03*
Y1287664D03*
X1164762Y744554D03*
Y1000853D03*
Y1287664D03*
X1194462Y744554D03*
Y1000853D03*
Y1287664D03*
X1224162Y744554D03*
Y1000853D03*
Y1287664D03*
X1609462Y744554D03*
Y1000853D03*
Y1287664D03*
X1639162Y744554D03*
Y1000853D03*
Y1287664D03*
X1668862Y744554D03*
Y1000853D03*
Y1287664D03*
X1698562Y744554D03*
Y1000853D03*
Y1287664D03*
X1728262Y744554D03*
Y1000853D03*
Y1287664D03*
X1757962Y744554D03*
Y1000853D03*
Y1287664D03*
X1787662Y744554D03*
Y1000853D03*
Y1287664D03*
X1817362Y744554D03*
Y1000853D03*
Y1287664D03*
X2822321Y-13971D03*
G54D35*
X841240Y1420330D03*
X1016240D03*
X2822321Y163329D03*
G54D26*
X306772Y991220D03*
X350099Y811121D03*
X356063Y1171318D03*
X531240Y811121D03*
X525276Y1171318D03*
X574567Y991220D03*
X1282914D03*
X1326240Y811121D03*
X1332205Y1171318D03*
X1507382Y811121D03*
X1501418Y1171318D03*
X1550709Y991220D03*
X2822321Y222429D03*
G54D45*
G01X-298760Y560500D02*
X-303410D01*
Y573000D01*
X-298760D01*
G01X-296350Y599205D02*
X-301000D01*
Y611705D01*
X-296350D01*
G01X-293950Y804871D02*
X-298600D01*
Y817371D01*
X-293950D01*
G01X-301170Y984970D02*
X-305820D01*
Y997470D01*
X-301170D01*
G01X-297370Y1165068D02*
X-302020D01*
Y1177568D01*
X-297370D01*
G01X-304590Y1420790D02*
X-309240D01*
Y1433290D01*
X-304590D01*
G01X-303390Y1450870D02*
X-308040D01*
Y1463370D01*
X-303390D01*
G01X-302190Y1679470D02*
X-306840D01*
Y1691970D01*
X-302190D01*
G01X-279260Y105758D02*
X-283910D01*
Y118258D01*
X-279260D01*
G01X-278660Y178986D02*
X-283310D01*
Y191486D01*
X-278660D01*
G01X-279260Y263238D02*
X-283910D01*
Y275738D01*
X-279260D01*
G01X-280530Y287520D02*
X-285180D01*
Y300020D01*
X-280530D01*
G01X-265910Y315403D02*
X-270560D01*
Y327903D01*
X-265910D01*
G01X-231060Y-18750D02*
X-235710D01*
Y-6250D01*
X-231060D01*
G01X-241410Y198474D02*
X-246060D01*
Y210974D01*
X-241410D01*
G01X-218160Y560500D02*
X-213510D01*
Y573000D01*
X-218160D01*
G01X-215750Y599205D02*
X-211100D01*
Y611705D01*
X-215750D01*
G01X-220570Y984970D02*
X-215920D01*
Y997470D01*
X-220570D01*
G01X-216770Y1165068D02*
X-212120D01*
Y1177568D01*
X-216770D01*
G01X-223990Y1420790D02*
X-219340D01*
Y1433290D01*
X-223990D01*
G01X-222790Y1450870D02*
X-218140D01*
Y1463370D01*
X-222790D01*
G01X-221590Y1679470D02*
X-216940D01*
Y1691970D01*
X-221590D01*
G01X-212460Y-18750D02*
X-207810D01*
Y-6250D01*
X-212460D01*
G01X-211060Y105758D02*
X-206410D01*
Y118258D01*
X-211060D01*
G01X-210460Y178986D02*
X-205810D01*
Y191486D01*
X-210460D01*
G01X-210410Y198474D02*
X-205760D01*
Y210974D01*
X-210410D01*
G01X-211060Y263238D02*
X-206410D01*
Y275738D01*
X-211060D01*
G01X-212330Y287520D02*
X-207680D01*
Y300020D01*
X-212330D01*
G01X-210110Y315403D02*
X-205460D01*
Y327903D01*
X-210110D01*
G01X1084074Y605380D02*
X-171300D01*
Y566750D01*
X-204135D01*
G01X1729706Y605455D02*
X-201725D01*
G01X1497382Y811121D02*
X-199325D01*
G01X-213350Y804871D02*
X-208700D01*
Y817371D01*
X-213350D01*
G01X1540709Y991220D02*
X-206545D01*
G01X1491418Y1171318D02*
X-202745D01*
G01X1503618Y1395413D02*
X-174910D01*
Y1427040D01*
X-209965D01*
G01X1809208Y1420330D02*
X-150840D01*
Y1460730D01*
X-208765Y1459489D01*
G01X1406437Y1698267D02*
X-171300D01*
Y1683320D01*
X-207565Y1683913D01*
G01X-10000Y0D02*
X-198435D01*
G01X1395118Y112008D02*
X-197035D01*
G01X385208Y185236D02*
X-196435D01*
G01X1047658Y204724D02*
X-196385D01*
G01X1237638Y269488D02*
X-197035D01*
G01X1676448Y277236D02*
X-176110D01*
Y292570D01*
X-198305Y292791D01*
G01X918739Y321653D02*
X-196085D01*
G01X-46439Y3271724D02*
X-58939D01*
X-56439Y3269864D01*
G01X-46439D02*
Y3273584D01*
G01X-58939Y3284124D02*
X-58522Y3282884D01*
X-57481Y3281954D01*
X-56231Y3281334D01*
X-54564Y3280869D01*
X-52689Y3280714D01*
X-50814Y3280869D01*
X-49147Y3281334D01*
X-47897Y3281954D01*
X-46856Y3282884D01*
X-46439Y3284124D01*
X-46856Y3285364D01*
X-47897Y3286294D01*
X-49147Y3286914D01*
X-50814Y3287379D01*
X-52689Y3287534D01*
X-54564Y3287379D01*
X-56231Y3286914D01*
X-57481Y3286294D01*
X-58522Y3285364D01*
X-58939Y3284124D01*
G01X-46439Y3292494D02*
X-58939D01*
X-48522Y3296524D01*
X-58939Y3300554D01*
X-46439D01*
G01Y3304894D02*
X-58939D01*
X-48522Y3308924D01*
X-58939Y3312954D01*
X-46439D01*
G01X-37580Y3276544D02*
Y3245048D01*
G01D02*
Y3296229D01*
G01X28650Y3276544D02*
X-45454D01*
G01X-37580Y3347410D02*
Y3296229D01*
G01Y3315914D02*
Y3347410D01*
G01X27796Y3315914D02*
X-45454D01*
G01X-48210Y3527092D02*
Y3535092D01*
X-49410Y3533492D01*
G01Y3527092D02*
X-47010D01*
G01X-40210Y3535092D02*
X-41010Y3534825D01*
X-41610Y3534159D01*
X-42010Y3533359D01*
X-42310Y3532292D01*
X-42410Y3531092D01*
X-42310Y3529892D01*
X-42010Y3528825D01*
X-41610Y3528025D01*
X-41010Y3527359D01*
X-40210Y3527092D01*
X-39410Y3527359D01*
X-38810Y3528025D01*
X-38410Y3528825D01*
X-38110Y3529892D01*
X-38010Y3531092D01*
X-38110Y3532292D01*
X-38410Y3533359D01*
X-38810Y3534159D01*
X-39410Y3534825D01*
X-40210Y3535092D01*
G01X-32210Y3526825D02*
X-32410Y3526959D01*
Y3527225D01*
X-32210Y3527359D01*
X-32010Y3527225D01*
Y3526959D01*
X-32210Y3526825D01*
G01X-26110Y3527092D02*
Y3535092D01*
X-22310D01*
G01X-23710Y3531225D02*
X-26110D01*
G01X-16210Y3527092D02*
X-17010Y3527225D01*
X-17710Y3527759D01*
X-18310Y3528559D01*
X-18710Y3529492D01*
X-18910Y3530559D01*
Y3531625D01*
X-18710Y3532692D01*
X-18310Y3533625D01*
X-17710Y3534425D01*
X-17010Y3534959D01*
X-16210Y3535092D01*
X-15410Y3534959D01*
X-14710Y3534425D01*
X-14110Y3533625D01*
X-13710Y3532692D01*
X-13510Y3531625D01*
Y3530559D01*
X-13710Y3529492D01*
X-14110Y3528559D01*
X-14710Y3527759D01*
X-15410Y3527225D01*
X-16210Y3527092D01*
G01X-10210D02*
Y3535092D01*
X-7710D01*
X-6910Y3534692D01*
X-6410Y3534159D01*
X-6210Y3533092D01*
X-6410Y3532025D01*
X-7010Y3531359D01*
X-7710Y3530959D01*
X-10210D01*
G01X-7710D02*
X-6210Y3527092D01*
G01X7790Y3535092D02*
Y3527092D01*
G01X5490Y3535092D02*
X10090D01*
G01X13690Y3527092D02*
Y3535092D01*
G01X17890D02*
Y3527092D01*
G01Y3531092D02*
X13690D01*
G01X25790Y3527092D02*
X21790D01*
Y3535092D01*
X25790D01*
G01X24190Y3531225D02*
X21790D01*
G01X37790Y3527092D02*
Y3535092D01*
X40190D01*
X40990Y3534692D01*
X41590Y3533759D01*
X41790Y3532692D01*
X41590Y3531625D01*
X41090Y3530825D01*
X40190Y3530425D01*
X37790D01*
G01X47790Y3535092D02*
Y3527092D01*
G01X45490Y3535092D02*
X50090D01*
G01X53690Y3527092D02*
Y3535092D01*
G01X57890D02*
Y3527092D01*
G01Y3531092D02*
X53690D01*
G01X71790Y3535092D02*
Y3527092D01*
G01X69490Y3535092D02*
X74090D01*
G01X79790Y3527092D02*
X78990Y3527225D01*
X78290Y3527759D01*
X77690Y3528559D01*
X77290Y3529492D01*
X77090Y3530559D01*
Y3531625D01*
X77290Y3532692D01*
X77690Y3533625D01*
X78290Y3534425D01*
X78990Y3534959D01*
X79790Y3535092D01*
X80590Y3534959D01*
X81290Y3534425D01*
X81890Y3533625D01*
X82290Y3532692D01*
X82490Y3531625D01*
Y3530559D01*
X82290Y3529492D01*
X81890Y3528559D01*
X81290Y3527759D01*
X80590Y3527225D01*
X79790Y3527092D01*
G01X87790D02*
X86990Y3527225D01*
X86290Y3527759D01*
X85690Y3528559D01*
X85290Y3529492D01*
X85090Y3530559D01*
Y3531625D01*
X85290Y3532692D01*
X85690Y3533625D01*
X86290Y3534425D01*
X86990Y3534959D01*
X87790Y3535092D01*
X88590Y3534959D01*
X89290Y3534425D01*
X89890Y3533625D01*
X90290Y3532692D01*
X90490Y3531625D01*
Y3530559D01*
X90290Y3529492D01*
X89890Y3528559D01*
X89290Y3527759D01*
X88590Y3527225D01*
X87790Y3527092D01*
G01X93790Y3535092D02*
Y3527092D01*
X97790D01*
G01X102590Y3535092D02*
X104990D01*
G01X103790D02*
Y3527092D01*
G01X102590D02*
X104990D01*
G01X109490D02*
Y3535092D01*
X114090Y3527092D01*
Y3535092D01*
G01X120390Y3531092D02*
X122390D01*
Y3528692D01*
X121790Y3527892D01*
X121090Y3527359D01*
X120090Y3527092D01*
X119090Y3527359D01*
X118390Y3527892D01*
X117790Y3528692D01*
X117390Y3529625D01*
X117190Y3530692D01*
Y3531625D01*
X117390Y3532425D01*
X117790Y3533359D01*
X118390Y3534159D01*
X118990Y3534692D01*
X119790Y3535092D01*
X120490D01*
X121290Y3534825D01*
X121890Y3534292D01*
G01X133690Y3527092D02*
Y3535092D01*
G01X137890D02*
Y3527092D01*
G01Y3531092D02*
X133690D01*
G01X143790Y3527092D02*
X142990Y3527225D01*
X142290Y3527759D01*
X141690Y3528559D01*
X141290Y3529492D01*
X141090Y3530559D01*
Y3531625D01*
X141290Y3532692D01*
X141690Y3533625D01*
X142290Y3534425D01*
X142990Y3534959D01*
X143790Y3535092D01*
X144590Y3534959D01*
X145290Y3534425D01*
X145890Y3533625D01*
X146290Y3532692D01*
X146490Y3531625D01*
Y3530559D01*
X146290Y3529492D01*
X145890Y3528559D01*
X145290Y3527759D01*
X144590Y3527225D01*
X143790Y3527092D01*
G01X149790Y3535092D02*
Y3527092D01*
X153790D01*
G01X161790D02*
X157790D01*
Y3535092D01*
X161790D01*
G01X160190Y3531225D02*
X157790D01*
G01X165690Y3528158D02*
X166490Y3527492D01*
X167390Y3527092D01*
X168190D01*
X168990Y3527492D01*
X169590Y3528158D01*
X169890Y3529092D01*
X169690Y3530025D01*
X169190Y3530825D01*
X168290Y3531359D01*
X167090Y3531625D01*
X166390Y3532159D01*
X166090Y3533092D01*
X166290Y3534025D01*
X166790Y3534692D01*
X167490Y3535092D01*
X168190D01*
X168890Y3534825D01*
X169490Y3534159D01*
G01X180790Y3535092D02*
X182190Y3527092D01*
X183790Y3535092D01*
X185390Y3527092D01*
X186790Y3535092D01*
G01X189690Y3527092D02*
Y3535092D01*
G01X193890D02*
Y3527092D01*
G01Y3531092D02*
X189690D01*
G01X198590Y3535092D02*
X200990D01*
G01X199790D02*
Y3527092D01*
G01X198590D02*
X200990D01*
G01X209990Y3534425D02*
X209390Y3534825D01*
X208690Y3535092D01*
X207890D01*
X206990Y3534692D01*
X206290Y3534025D01*
X205790Y3533225D01*
X205390Y3531892D01*
X205290Y3530692D01*
X205490Y3529492D01*
X205790Y3528692D01*
X206390Y3527892D01*
X207090Y3527359D01*
X207790Y3527092D01*
X208490D01*
X209190Y3527359D01*
X209790Y3527759D01*
X210290Y3528292D01*
G01X213690Y3527092D02*
Y3535092D01*
G01X217890D02*
Y3527092D01*
G01Y3531092D02*
X213690D01*
G01X229690Y3528158D02*
X230490Y3527492D01*
X231390Y3527092D01*
X232190D01*
X232990Y3527492D01*
X233590Y3528158D01*
X233890Y3529092D01*
X233690Y3530025D01*
X233190Y3530825D01*
X232290Y3531359D01*
X231090Y3531625D01*
X230390Y3532159D01*
X230090Y3533092D01*
X230290Y3534025D01*
X230790Y3534692D01*
X231490Y3535092D01*
X232190D01*
X232890Y3534825D01*
X233490Y3534159D01*
G01X238590Y3535092D02*
X240990D01*
G01X239790D02*
Y3527092D01*
G01X238590D02*
X240990D01*
G01X245890Y3535092D02*
X249690D01*
X245890Y3527092D01*
X249690D01*
G01X257790D02*
X253790D01*
Y3535092D01*
X257790D01*
G01X256190Y3531225D02*
X253790D01*
G01X270590Y3535092D02*
X272990D01*
G01X271790D02*
Y3527092D01*
G01X270590D02*
X272990D01*
G01X277690Y3528158D02*
X278490Y3527492D01*
X279390Y3527092D01*
X280190D01*
X280990Y3527492D01*
X281590Y3528158D01*
X281890Y3529092D01*
X281690Y3530025D01*
X281190Y3530825D01*
X280290Y3531359D01*
X279090Y3531625D01*
X278390Y3532159D01*
X278090Y3533092D01*
X278290Y3534025D01*
X278790Y3534692D01*
X279490Y3535092D01*
X280190D01*
X280890Y3534825D01*
X281490Y3534159D01*
G01X297790Y3527092D02*
X293790D01*
Y3535092D01*
X297790D01*
G01X296190Y3531225D02*
X293790D01*
G01X303790Y3527092D02*
X302990Y3527225D01*
X302290Y3527759D01*
X301690Y3528559D01*
X301290Y3529492D01*
X301090Y3530559D01*
Y3531625D01*
X301290Y3532692D01*
X301690Y3533625D01*
X302290Y3534425D01*
X302990Y3534959D01*
X303790Y3535092D01*
X304590Y3534959D01*
X305290Y3534425D01*
X305890Y3533625D01*
X306290Y3532692D01*
X306490Y3531625D01*
Y3530559D01*
X306290Y3529492D01*
X305890Y3528559D01*
X305290Y3527759D01*
X304590Y3527225D01*
X303790Y3527092D01*
G01X304590Y3529225D02*
X305790Y3527092D01*
G01X309590Y3535092D02*
Y3529359D01*
X309990Y3528158D01*
X310790Y3527359D01*
X311790Y3527092D01*
X312790Y3527359D01*
X313590Y3528158D01*
X313990Y3529359D01*
Y3535092D01*
G01X317290Y3527092D02*
X319790Y3535092D01*
X322290Y3527092D01*
G01X321390Y3529892D02*
X318190D01*
G01X325790Y3535092D02*
Y3527092D01*
X329790D01*
G01X343790Y3535092D02*
Y3527092D01*
G01X341490Y3535092D02*
X346090D01*
G01X351790Y3527092D02*
X350990Y3527225D01*
X350290Y3527759D01*
X349690Y3528559D01*
X349290Y3529492D01*
X349090Y3530559D01*
Y3531625D01*
X349290Y3532692D01*
X349690Y3533625D01*
X350290Y3534425D01*
X350990Y3534959D01*
X351790Y3535092D01*
X352590Y3534959D01*
X353290Y3534425D01*
X353890Y3533625D01*
X354290Y3532692D01*
X354490Y3531625D01*
Y3530559D01*
X354290Y3529492D01*
X353890Y3528559D01*
X353290Y3527759D01*
X352590Y3527225D01*
X351790Y3527092D01*
G01X367790D02*
X366990Y3527225D01*
X366290Y3527759D01*
X365690Y3528559D01*
X365290Y3529492D01*
X365090Y3530559D01*
Y3531625D01*
X365290Y3532692D01*
X365690Y3533625D01*
X366290Y3534425D01*
X366990Y3534959D01*
X367790Y3535092D01*
X368590Y3534959D01*
X369290Y3534425D01*
X369890Y3533625D01*
X370290Y3532692D01*
X370490Y3531625D01*
Y3530559D01*
X370290Y3529492D01*
X369890Y3528559D01*
X369290Y3527759D01*
X368590Y3527225D01*
X367790Y3527092D01*
G01X373790D02*
Y3535092D01*
X376290D01*
X377090Y3534692D01*
X377590Y3534159D01*
X377790Y3533092D01*
X377590Y3532025D01*
X376990Y3531359D01*
X376290Y3530959D01*
X373790D01*
G01X376290D02*
X377790Y3527092D01*
G01X389190D02*
Y3535092D01*
X391790Y3528425D01*
X394390Y3535092D01*
Y3527092D01*
G01X399790D02*
X398990Y3527225D01*
X398290Y3527759D01*
X397690Y3528559D01*
X397290Y3529492D01*
X397090Y3530559D01*
Y3531625D01*
X397290Y3532692D01*
X397690Y3533625D01*
X398290Y3534425D01*
X398990Y3534959D01*
X399790Y3535092D01*
X400590Y3534959D01*
X401290Y3534425D01*
X401890Y3533625D01*
X402290Y3532692D01*
X402490Y3531625D01*
Y3530559D01*
X402290Y3529492D01*
X401890Y3528559D01*
X401290Y3527759D01*
X400590Y3527225D01*
X399790Y3527092D01*
G01X405790D02*
Y3535092D01*
X408290D01*
X409090Y3534692D01*
X409590Y3534159D01*
X409790Y3533092D01*
X409590Y3532025D01*
X408990Y3531359D01*
X408290Y3530959D01*
X405790D01*
G01X408290D02*
X409790Y3527092D01*
G01X417790D02*
X413790D01*
Y3535092D01*
X417790D01*
G01X416190Y3531225D02*
X413790D01*
G01X431790Y3535092D02*
Y3527092D01*
G01X429490Y3535092D02*
X434090D01*
G01X437690Y3527092D02*
Y3535092D01*
G01X441890D02*
Y3527092D01*
G01Y3531092D02*
X437690D01*
G01X445290Y3527092D02*
X447790Y3535092D01*
X450290Y3527092D01*
G01X449390Y3529892D02*
X446190D01*
G01X453490Y3527092D02*
Y3535092D01*
X458090Y3527092D01*
Y3535092D01*
G01X471590Y3527092D02*
X471790Y3528825D01*
X472090Y3530292D01*
X472490Y3531625D01*
X472990Y3533092D01*
X473790Y3535092D01*
X469790D01*
G01X479790D02*
X478990Y3534825D01*
X478390Y3534159D01*
X477990Y3533359D01*
X477690Y3532292D01*
X477590Y3531092D01*
X477690Y3529892D01*
X477990Y3528825D01*
X478390Y3528025D01*
X478990Y3527359D01*
X479790Y3527092D01*
X480590Y3527359D01*
X481190Y3528025D01*
X481590Y3528825D01*
X481890Y3529892D01*
X481990Y3531092D01*
X481890Y3532292D01*
X481590Y3533359D01*
X481190Y3534159D01*
X480590Y3534825D01*
X479790Y3535092D01*
G01X493190Y3527092D02*
Y3535092D01*
X495790Y3528425D01*
X498390Y3535092D01*
Y3527092D01*
G01X502590Y3535092D02*
X504990D01*
G01X503790D02*
Y3527092D01*
G01X502590D02*
X504990D01*
G01X509790Y3535092D02*
Y3527092D01*
X513790D01*
G01X519790Y3526825D02*
X519590Y3526959D01*
Y3527225D01*
X519790Y3527359D01*
X519990Y3527225D01*
Y3526959D01*
X519790Y3526825D01*
G01X541490Y3527092D02*
Y3535092D01*
X546090Y3527092D01*
Y3535092D01*
G01X551790Y3527092D02*
X550990Y3527225D01*
X550290Y3527759D01*
X549690Y3528559D01*
X549290Y3529492D01*
X549090Y3530559D01*
Y3531625D01*
X549290Y3532692D01*
X549690Y3533625D01*
X550290Y3534425D01*
X550990Y3534959D01*
X551790Y3535092D01*
X552590Y3534959D01*
X553290Y3534425D01*
X553890Y3533625D01*
X554290Y3532692D01*
X554490Y3531625D01*
Y3530559D01*
X554290Y3529492D01*
X553890Y3528559D01*
X553290Y3527759D01*
X552590Y3527225D01*
X551790Y3527092D01*
G01X557490D02*
Y3535092D01*
X562090Y3527092D01*
Y3535092D01*
G01X566490Y3529759D02*
X569090D01*
G01X573890Y3527092D02*
Y3535092D01*
X577690D01*
G01X576290Y3531225D02*
X573890D01*
G01X581590Y3535092D02*
Y3529359D01*
X581990Y3528158D01*
X582790Y3527359D01*
X583790Y3527092D01*
X584790Y3527359D01*
X585590Y3528158D01*
X585990Y3529359D01*
Y3535092D01*
G01X589490Y3527092D02*
Y3535092D01*
X594090Y3527092D01*
Y3535092D01*
G01X601990Y3534425D02*
X601390Y3534825D01*
X600690Y3535092D01*
X599890D01*
X598990Y3534692D01*
X598290Y3534025D01*
X597790Y3533225D01*
X597390Y3531892D01*
X597290Y3530692D01*
X597490Y3529492D01*
X597790Y3528692D01*
X598390Y3527892D01*
X599090Y3527359D01*
X599790Y3527092D01*
X600490D01*
X601190Y3527359D01*
X601790Y3527759D01*
X602290Y3528292D01*
G01X607790Y3535092D02*
Y3527092D01*
G01X605490Y3535092D02*
X610090D01*
G01X614590D02*
X616990D01*
G01X615790D02*
Y3527092D01*
G01X614590D02*
X616990D01*
G01X623790D02*
X622990Y3527225D01*
X622290Y3527759D01*
X621690Y3528559D01*
X621290Y3529492D01*
X621090Y3530559D01*
Y3531625D01*
X621290Y3532692D01*
X621690Y3533625D01*
X622290Y3534425D01*
X622990Y3534959D01*
X623790Y3535092D01*
X624590Y3534959D01*
X625290Y3534425D01*
X625890Y3533625D01*
X626290Y3532692D01*
X626490Y3531625D01*
Y3530559D01*
X626290Y3529492D01*
X625890Y3528559D01*
X625290Y3527759D01*
X624590Y3527225D01*
X623790Y3527092D01*
G01X629490D02*
Y3535092D01*
X634090Y3527092D01*
Y3535092D01*
G01X637290Y3527092D02*
X639790Y3535092D01*
X642290Y3527092D01*
G01X641390Y3529892D02*
X638190D01*
G01X645790Y3535092D02*
Y3527092D01*
X649790D01*
G01X661790D02*
Y3535092D01*
X664190D01*
X664990Y3534692D01*
X665590Y3533759D01*
X665790Y3532692D01*
X665590Y3531625D01*
X665090Y3530825D01*
X664190Y3530425D01*
X661790D01*
G01X669290Y3527092D02*
X671790Y3535092D01*
X674290Y3527092D01*
G01X673390Y3529892D02*
X670190D01*
G01X677590Y3527092D02*
Y3535092D01*
X679590D01*
X680390Y3534692D01*
X680990Y3534159D01*
X681490Y3533359D01*
X681890Y3532425D01*
X681990Y3531092D01*
X681890Y3529759D01*
X681490Y3528825D01*
X680990Y3528025D01*
X680390Y3527492D01*
X679590Y3527092D01*
X677590D01*
G01X694590Y3535092D02*
X696990D01*
G01X695790D02*
Y3527092D01*
G01X694590D02*
X696990D01*
G01X701690Y3528158D02*
X702490Y3527492D01*
X703390Y3527092D01*
X704190D01*
X704990Y3527492D01*
X705590Y3528158D01*
X705890Y3529092D01*
X705690Y3530025D01*
X705190Y3530825D01*
X704290Y3531359D01*
X703090Y3531625D01*
X702390Y3532159D01*
X702090Y3533092D01*
X702290Y3534025D01*
X702790Y3534692D01*
X703490Y3535092D01*
X704190D01*
X704890Y3534825D01*
X705490Y3534159D01*
G01X717790Y3527092D02*
Y3535092D01*
X720290D01*
X721090Y3534692D01*
X721590Y3534159D01*
X721790Y3533092D01*
X721590Y3532025D01*
X720990Y3531359D01*
X720290Y3530959D01*
X717790D01*
G01X720290D02*
X721790Y3527092D01*
G01X729790D02*
X725790D01*
Y3535092D01*
X729790D01*
G01X728190Y3531225D02*
X725790D01*
G01X735790Y3527092D02*
X734990Y3527225D01*
X734290Y3527759D01*
X733690Y3528559D01*
X733290Y3529492D01*
X733090Y3530559D01*
Y3531625D01*
X733290Y3532692D01*
X733690Y3533625D01*
X734290Y3534425D01*
X734990Y3534959D01*
X735790Y3535092D01*
X736590Y3534959D01*
X737290Y3534425D01*
X737890Y3533625D01*
X738290Y3532692D01*
X738490Y3531625D01*
Y3530559D01*
X738290Y3529492D01*
X737890Y3528559D01*
X737290Y3527759D01*
X736590Y3527225D01*
X735790Y3527092D01*
G01X736590Y3529225D02*
X737790Y3527092D01*
G01X741590Y3535092D02*
Y3529359D01*
X741990Y3528158D01*
X742790Y3527359D01*
X743790Y3527092D01*
X744790Y3527359D01*
X745590Y3528158D01*
X745990Y3529359D01*
Y3535092D01*
G01X750590D02*
X752990D01*
G01X751790D02*
Y3527092D01*
G01X750590D02*
X752990D01*
G01X757790D02*
Y3535092D01*
X760290D01*
X761090Y3534692D01*
X761590Y3534159D01*
X761790Y3533092D01*
X761590Y3532025D01*
X760990Y3531359D01*
X760290Y3530959D01*
X757790D01*
G01X760290D02*
X761790Y3527092D01*
G01X769790D02*
X765790D01*
Y3535092D01*
X769790D01*
G01X768190Y3531225D02*
X765790D01*
G01X773590Y3527092D02*
Y3535092D01*
X775590D01*
X776390Y3534692D01*
X776990Y3534159D01*
X777490Y3533359D01*
X777890Y3532425D01*
X777990Y3531092D01*
X777890Y3529759D01*
X777490Y3528825D01*
X776990Y3528025D01*
X776390Y3527492D01*
X775590Y3527092D01*
X773590D01*
G01X791790Y3535092D02*
Y3527092D01*
G01X789490Y3535092D02*
X794090D01*
G01X799790Y3527092D02*
X798990Y3527225D01*
X798290Y3527759D01*
X797690Y3528559D01*
X797290Y3529492D01*
X797090Y3530559D01*
Y3531625D01*
X797290Y3532692D01*
X797690Y3533625D01*
X798290Y3534425D01*
X798990Y3534959D01*
X799790Y3535092D01*
X800590Y3534959D01*
X801290Y3534425D01*
X801890Y3533625D01*
X802290Y3532692D01*
X802490Y3531625D01*
Y3530559D01*
X802290Y3529492D01*
X801890Y3528559D01*
X801290Y3527759D01*
X800590Y3527225D01*
X799790Y3527092D01*
G01X816590Y3531359D02*
X816990Y3531759D01*
X817290Y3532425D01*
X817490Y3533359D01*
X817290Y3534159D01*
X816890Y3534692D01*
X816190Y3535092D01*
X813490D01*
Y3527092D01*
X816790D01*
X817490Y3527625D01*
X817890Y3528425D01*
X818090Y3529359D01*
X817890Y3530292D01*
X817290Y3531092D01*
X816590Y3531359D01*
X813490D01*
G01X825790Y3527092D02*
X821790D01*
Y3535092D01*
X825790D01*
G01X824190Y3531225D02*
X821790D01*
G01X837290Y3527092D02*
X839790Y3535092D01*
X842290Y3527092D01*
G01X841390Y3529892D02*
X838190D01*
G01X845590Y3527092D02*
Y3535092D01*
X847590D01*
X848390Y3534692D01*
X848990Y3534159D01*
X849490Y3533359D01*
X849890Y3532425D01*
X849990Y3531092D01*
X849890Y3529759D01*
X849490Y3528825D01*
X848990Y3528025D01*
X848390Y3527492D01*
X847590Y3527092D01*
X845590D01*
G01X853590D02*
Y3535092D01*
X855590D01*
X856390Y3534692D01*
X856990Y3534159D01*
X857490Y3533359D01*
X857890Y3532425D01*
X857990Y3531092D01*
X857890Y3529759D01*
X857490Y3528825D01*
X856990Y3528025D01*
X856390Y3527492D01*
X855590Y3527092D01*
X853590D01*
G01X865790D02*
X861790D01*
Y3535092D01*
X865790D01*
G01X864190Y3531225D02*
X861790D01*
G01X869590Y3527092D02*
Y3535092D01*
X871590D01*
X872390Y3534692D01*
X872990Y3534159D01*
X873490Y3533359D01*
X873890Y3532425D01*
X873990Y3531092D01*
X873890Y3529759D01*
X873490Y3528825D01*
X872990Y3528025D01*
X872390Y3527492D01*
X871590Y3527092D01*
X869590D01*
G01X887790Y3535092D02*
Y3527092D01*
G01X885490Y3535092D02*
X890090D01*
G01X895790Y3527092D02*
X894990Y3527225D01*
X894290Y3527759D01*
X893690Y3528559D01*
X893290Y3529492D01*
X893090Y3530559D01*
Y3531625D01*
X893290Y3532692D01*
X893690Y3533625D01*
X894290Y3534425D01*
X894990Y3534959D01*
X895790Y3535092D01*
X896590Y3534959D01*
X897290Y3534425D01*
X897890Y3533625D01*
X898290Y3532692D01*
X898490Y3531625D01*
Y3530559D01*
X898290Y3529492D01*
X897890Y3528559D01*
X897290Y3527759D01*
X896590Y3527225D01*
X895790Y3527092D01*
G01X909790D02*
Y3535092D01*
X912190D01*
X912990Y3534692D01*
X913590Y3533759D01*
X913790Y3532692D01*
X913590Y3531625D01*
X913090Y3530825D01*
X912190Y3530425D01*
X909790D01*
G01X917790Y3527092D02*
Y3535092D01*
X920290D01*
X921090Y3534692D01*
X921590Y3534159D01*
X921790Y3533092D01*
X921590Y3532025D01*
X920990Y3531359D01*
X920290Y3530959D01*
X917790D01*
G01X920290D02*
X921790Y3527092D01*
G01X929790D02*
X925790D01*
Y3535092D01*
X929790D01*
G01X928190Y3531225D02*
X925790D01*
G01X933290Y3535092D02*
X935790Y3527092D01*
X938290Y3535092D01*
G01X945790Y3527092D02*
X941790D01*
Y3535092D01*
X945790D01*
G01X944190Y3531225D02*
X941790D01*
G01X949490Y3527092D02*
Y3535092D01*
X954090Y3527092D01*
Y3535092D01*
G01X959790D02*
Y3527092D01*
G01X957490Y3535092D02*
X962090D01*
G01X975790D02*
Y3527092D01*
G01X973490Y3535092D02*
X978090D01*
G01X981690Y3527092D02*
Y3535092D01*
G01X985890D02*
Y3527092D01*
G01Y3531092D02*
X981690D01*
G01X993790Y3527092D02*
X989790D01*
Y3535092D01*
X993790D01*
G01X992190Y3531225D02*
X989790D01*
G01X1005790Y3527092D02*
Y3535092D01*
X1008190D01*
X1008990Y3534692D01*
X1009590Y3533759D01*
X1009790Y3532692D01*
X1009590Y3531625D01*
X1009090Y3530825D01*
X1008190Y3530425D01*
X1005790D01*
G01X1015790Y3527092D02*
X1014990Y3527225D01*
X1014290Y3527759D01*
X1013690Y3528559D01*
X1013290Y3529492D01*
X1013090Y3530559D01*
Y3531625D01*
X1013290Y3532692D01*
X1013690Y3533625D01*
X1014290Y3534425D01*
X1014990Y3534959D01*
X1015790Y3535092D01*
X1016590Y3534959D01*
X1017290Y3534425D01*
X1017890Y3533625D01*
X1018290Y3532692D01*
X1018490Y3531625D01*
Y3530559D01*
X1018290Y3529492D01*
X1017890Y3528559D01*
X1017290Y3527759D01*
X1016590Y3527225D01*
X1015790Y3527092D01*
G01X1023790Y3535092D02*
Y3527092D01*
G01X1021490Y3535092D02*
X1026090D01*
G01X1033790Y3527092D02*
X1029790D01*
Y3535092D01*
X1033790D01*
G01X1032190Y3531225D02*
X1029790D01*
G01X1037490Y3527092D02*
Y3535092D01*
X1042090Y3527092D01*
Y3535092D01*
G01X1047790D02*
Y3527092D01*
G01X1045490Y3535092D02*
X1050090D01*
G01X1054590D02*
X1056990D01*
G01X1055790D02*
Y3527092D01*
G01X1054590D02*
X1056990D01*
G01X1061290D02*
X1063790Y3535092D01*
X1066290Y3527092D01*
G01X1065390Y3529892D02*
X1062190D01*
G01X1069790Y3535092D02*
Y3527092D01*
X1073790D01*
G01X1085790D02*
Y3535092D01*
X1088190D01*
X1088990Y3534692D01*
X1089590Y3533759D01*
X1089790Y3532692D01*
X1089590Y3531625D01*
X1089090Y3530825D01*
X1088190Y3530425D01*
X1085790D01*
G01X1093590Y3535092D02*
Y3529359D01*
X1093990Y3528158D01*
X1094790Y3527359D01*
X1095790Y3527092D01*
X1096790Y3527359D01*
X1097590Y3528158D01*
X1097990Y3529359D01*
Y3535092D01*
G01X1101790D02*
Y3527092D01*
X1105790D01*
G01X1109790Y3535092D02*
Y3527092D01*
X1113790D01*
G01X1125290D02*
X1127790Y3535092D01*
X1130290Y3527092D01*
G01X1129390Y3529892D02*
X1126190D01*
G01X1132790Y3535092D02*
X1134190Y3527092D01*
X1135790Y3535092D01*
X1137390Y3527092D01*
X1138790Y3535092D01*
G01X1141290Y3527092D02*
X1143790Y3535092D01*
X1146290Y3527092D01*
G01X1145390Y3529892D02*
X1142190D01*
G01X1151790Y3527092D02*
Y3530692D01*
X1149790Y3535092D01*
G01X1153790D02*
X1151790Y3530692D01*
G01X1159790Y3526825D02*
X1159590Y3526959D01*
Y3527225D01*
X1159790Y3527359D01*
X1159990Y3527225D01*
Y3526959D01*
X1159790Y3526825D01*
G01X-49910Y3543025D02*
X-49210Y3542359D01*
X-48410Y3542092D01*
X-47610Y3542359D01*
X-46910Y3543158D01*
X-46410Y3544359D01*
X-46210Y3545559D01*
Y3547025D01*
X-46410Y3548225D01*
X-46910Y3549292D01*
X-47510Y3549825D01*
X-48210Y3550092D01*
X-49010Y3549825D01*
X-49610Y3549292D01*
X-50010Y3548492D01*
X-50210Y3547425D01*
X-50010Y3546492D01*
X-49510Y3545559D01*
X-48910Y3545025D01*
X-48210Y3544892D01*
X-47410Y3545158D01*
X-46810Y3545825D01*
X-46210Y3547025D01*
G01X-40210Y3541825D02*
X-40410Y3541959D01*
Y3542225D01*
X-40210Y3542359D01*
X-40010Y3542225D01*
Y3541959D01*
X-40210Y3541825D01*
G01X-34710Y3542092D02*
X-32210Y3550092D01*
X-29710Y3542092D01*
G01X-30610Y3544892D02*
X-33810D01*
G01X-26510Y3542092D02*
Y3550092D01*
X-21910Y3542092D01*
Y3550092D01*
G01X-16210Y3542092D02*
Y3545692D01*
X-18210Y3550092D01*
G01X-14210D02*
X-16210Y3545692D01*
G01X-2310Y3543158D02*
X-1510Y3542492D01*
X-610Y3542092D01*
X190D01*
X990Y3542492D01*
X1590Y3543158D01*
X1890Y3544092D01*
X1690Y3545025D01*
X1190Y3545825D01*
X290Y3546359D01*
X-910Y3546625D01*
X-1610Y3547159D01*
X-1910Y3548092D01*
X-1710Y3549025D01*
X-1210Y3549692D01*
X-510Y3550092D01*
X190D01*
X890Y3549825D01*
X1490Y3549159D01*
G01X5790Y3542092D02*
Y3550092D01*
X8190D01*
X8990Y3549692D01*
X9590Y3548759D01*
X9790Y3547692D01*
X9590Y3546625D01*
X9090Y3545825D01*
X8190Y3545425D01*
X5790D01*
G01X17790Y3542092D02*
X13790D01*
Y3550092D01*
X17790D01*
G01X16190Y3546225D02*
X13790D01*
G01X25990Y3549425D02*
X25390Y3549825D01*
X24690Y3550092D01*
X23890D01*
X22990Y3549692D01*
X22290Y3549025D01*
X21790Y3548225D01*
X21390Y3546892D01*
X21290Y3545692D01*
X21490Y3544492D01*
X21790Y3543692D01*
X22390Y3542892D01*
X23090Y3542359D01*
X23790Y3542092D01*
X24490D01*
X25190Y3542359D01*
X25790Y3542759D01*
X26290Y3543292D01*
G01X30590Y3550092D02*
X32990D01*
G01X31790D02*
Y3542092D01*
G01X30590D02*
X32990D01*
G01X37290D02*
X39790Y3550092D01*
X42290Y3542092D01*
G01X41390Y3544892D02*
X38190D01*
G01X45790Y3550092D02*
Y3542092D01*
X49790D01*
G01X61590D02*
Y3550092D01*
X63590D01*
X64390Y3549692D01*
X64990Y3549159D01*
X65490Y3548359D01*
X65890Y3547425D01*
X65990Y3546092D01*
X65890Y3544759D01*
X65490Y3543825D01*
X64990Y3543025D01*
X64390Y3542492D01*
X63590Y3542092D01*
X61590D01*
G01X69790D02*
Y3550092D01*
X72290D01*
X73090Y3549692D01*
X73590Y3549159D01*
X73790Y3548092D01*
X73590Y3547025D01*
X72990Y3546359D01*
X72290Y3545959D01*
X69790D01*
G01X72290D02*
X73790Y3542092D01*
G01X78590Y3550092D02*
X80990D01*
G01X79790D02*
Y3542092D01*
G01X78590D02*
X80990D01*
G01X85790Y3550092D02*
Y3542092D01*
X89790D01*
G01X93790Y3550092D02*
Y3542092D01*
X97790D01*
G01X109290D02*
X111790Y3550092D01*
X114290Y3542092D01*
G01X113390Y3544892D02*
X110190D01*
G01X117490Y3542092D02*
Y3550092D01*
X122090Y3542092D01*
Y3550092D01*
G01X125590Y3542092D02*
Y3550092D01*
X127590D01*
X128390Y3549692D01*
X128990Y3549159D01*
X129490Y3548359D01*
X129890Y3547425D01*
X129990Y3546092D01*
X129890Y3544759D01*
X129490Y3543825D01*
X128990Y3543025D01*
X128390Y3542492D01*
X127590Y3542092D01*
X125590D01*
G01X141690Y3543158D02*
X142490Y3542492D01*
X143390Y3542092D01*
X144190D01*
X144990Y3542492D01*
X145590Y3543158D01*
X145890Y3544092D01*
X145690Y3545025D01*
X145190Y3545825D01*
X144290Y3546359D01*
X143090Y3546625D01*
X142390Y3547159D01*
X142090Y3548092D01*
X142290Y3549025D01*
X142790Y3549692D01*
X143490Y3550092D01*
X144190D01*
X144890Y3549825D01*
X145490Y3549159D01*
G01X151790Y3550092D02*
Y3542092D01*
G01X149490Y3550092D02*
X154090D01*
G01X157290Y3542092D02*
X159790Y3550092D01*
X162290Y3542092D01*
G01X161390Y3544892D02*
X158190D01*
G01X169990Y3549425D02*
X169390Y3549825D01*
X168690Y3550092D01*
X167890D01*
X166990Y3549692D01*
X166290Y3549025D01*
X165790Y3548225D01*
X165390Y3546892D01*
X165290Y3545692D01*
X165490Y3544492D01*
X165790Y3543692D01*
X166390Y3542892D01*
X167090Y3542359D01*
X167790Y3542092D01*
X168490D01*
X169190Y3542359D01*
X169790Y3542759D01*
X170290Y3543292D01*
G01X173590Y3542092D02*
Y3550092D01*
G01X177390D02*
X173590Y3545158D01*
G01X177990Y3542092D02*
X175290Y3547425D01*
G01X185790Y3542092D02*
X181790D01*
Y3550092D01*
X185790D01*
G01X184190Y3546225D02*
X181790D01*
G01X189590Y3542092D02*
Y3550092D01*
X191590D01*
X192390Y3549692D01*
X192990Y3549159D01*
X193490Y3548359D01*
X193890Y3547425D01*
X193990Y3546092D01*
X193890Y3544759D01*
X193490Y3543825D01*
X192990Y3543025D01*
X192390Y3542492D01*
X191590Y3542092D01*
X189590D01*
G01X205690D02*
Y3550092D01*
G01X209890D02*
Y3542092D01*
G01Y3546092D02*
X205690D01*
G01X215790Y3542092D02*
X214990Y3542225D01*
X214290Y3542759D01*
X213690Y3543559D01*
X213290Y3544492D01*
X213090Y3545559D01*
Y3546625D01*
X213290Y3547692D01*
X213690Y3548625D01*
X214290Y3549425D01*
X214990Y3549959D01*
X215790Y3550092D01*
X216590Y3549959D01*
X217290Y3549425D01*
X217890Y3548625D01*
X218290Y3547692D01*
X218490Y3546625D01*
Y3545559D01*
X218290Y3544492D01*
X217890Y3543559D01*
X217290Y3542759D01*
X216590Y3542225D01*
X215790Y3542092D01*
G01X221790Y3550092D02*
Y3542092D01*
X225790D01*
G01X233790D02*
X229790D01*
Y3550092D01*
X233790D01*
G01X232190Y3546225D02*
X229790D01*
G01X245790Y3542092D02*
Y3550092D01*
X248190D01*
X248990Y3549692D01*
X249590Y3548759D01*
X249790Y3547692D01*
X249590Y3546625D01*
X249090Y3545825D01*
X248190Y3545425D01*
X245790D01*
G01X253790Y3550092D02*
Y3542092D01*
X257790D01*
G01X265790D02*
X261790D01*
Y3550092D01*
X265790D01*
G01X264190Y3546225D02*
X261790D01*
G01X269290Y3542092D02*
X271790Y3550092D01*
X274290Y3542092D01*
G01X273390Y3544892D02*
X270190D01*
G01X277690Y3543158D02*
X278490Y3542492D01*
X279390Y3542092D01*
X280190D01*
X280990Y3542492D01*
X281590Y3543158D01*
X281890Y3544092D01*
X281690Y3545025D01*
X281190Y3545825D01*
X280290Y3546359D01*
X279090Y3546625D01*
X278390Y3547159D01*
X278090Y3548092D01*
X278290Y3549025D01*
X278790Y3549692D01*
X279490Y3550092D01*
X280190D01*
X280890Y3549825D01*
X281490Y3549159D01*
G01X289790Y3542092D02*
X285790D01*
Y3550092D01*
X289790D01*
G01X288190Y3546225D02*
X285790D01*
G01X301890Y3542092D02*
Y3550092D01*
X305690D01*
G01X304290Y3546225D02*
X301890D01*
G01X311790Y3542092D02*
X310990Y3542225D01*
X310290Y3542759D01*
X309690Y3543559D01*
X309290Y3544492D01*
X309090Y3545559D01*
Y3546625D01*
X309290Y3547692D01*
X309690Y3548625D01*
X310290Y3549425D01*
X310990Y3549959D01*
X311790Y3550092D01*
X312590Y3549959D01*
X313290Y3549425D01*
X313890Y3548625D01*
X314290Y3547692D01*
X314490Y3546625D01*
Y3545559D01*
X314290Y3544492D01*
X313890Y3543559D01*
X313290Y3542759D01*
X312590Y3542225D01*
X311790Y3542092D01*
G01X317790Y3550092D02*
Y3542092D01*
X321790D01*
G01X325790Y3550092D02*
Y3542092D01*
X329790D01*
G01X335790D02*
X334990Y3542225D01*
X334290Y3542759D01*
X333690Y3543559D01*
X333290Y3544492D01*
X333090Y3545559D01*
Y3546625D01*
X333290Y3547692D01*
X333690Y3548625D01*
X334290Y3549425D01*
X334990Y3549959D01*
X335790Y3550092D01*
X336590Y3549959D01*
X337290Y3549425D01*
X337890Y3548625D01*
X338290Y3547692D01*
X338490Y3546625D01*
Y3545559D01*
X338290Y3544492D01*
X337890Y3543559D01*
X337290Y3542759D01*
X336590Y3542225D01*
X335790Y3542092D01*
G01X340790Y3550092D02*
X342190Y3542092D01*
X343790Y3550092D01*
X345390Y3542092D01*
X346790Y3550092D01*
G01X359790Y3542092D02*
X358990Y3542225D01*
X358290Y3542759D01*
X357690Y3543559D01*
X357290Y3544492D01*
X357090Y3545559D01*
Y3546625D01*
X357290Y3547692D01*
X357690Y3548625D01*
X358290Y3549425D01*
X358990Y3549959D01*
X359790Y3550092D01*
X360590Y3549959D01*
X361290Y3549425D01*
X361890Y3548625D01*
X362290Y3547692D01*
X362490Y3546625D01*
Y3545559D01*
X362290Y3544492D01*
X361890Y3543559D01*
X361290Y3542759D01*
X360590Y3542225D01*
X359790Y3542092D01*
G01X365590Y3550092D02*
Y3544359D01*
X365990Y3543158D01*
X366790Y3542359D01*
X367790Y3542092D01*
X368790Y3542359D01*
X369590Y3543158D01*
X369990Y3544359D01*
Y3550092D01*
G01X375790D02*
Y3542092D01*
G01X373490Y3550092D02*
X378090D01*
G01X381790D02*
Y3542092D01*
X385790D01*
G01X390590Y3550092D02*
X392990D01*
G01X391790D02*
Y3542092D01*
G01X390590D02*
X392990D01*
G01X397490D02*
Y3550092D01*
X402090Y3542092D01*
Y3550092D01*
G01X409790Y3542092D02*
X405790D01*
Y3550092D01*
X409790D01*
G01X408190Y3546225D02*
X405790D01*
G01X415790Y3541825D02*
X415590Y3541959D01*
Y3542225D01*
X415790Y3542359D01*
X415990Y3542225D01*
Y3541959D01*
X415790Y3541825D01*
G01X429790Y3542092D02*
Y3550092D01*
X432190D01*
X432990Y3549692D01*
X433590Y3548759D01*
X433790Y3547692D01*
X433590Y3546625D01*
X433090Y3545825D01*
X432190Y3545425D01*
X429790D01*
G01X439790Y3550092D02*
Y3542092D01*
G01X437490Y3550092D02*
X442090D01*
G01X445690Y3542092D02*
Y3550092D01*
G01X449890D02*
Y3542092D01*
G01Y3546092D02*
X445690D01*
G01X463790Y3550092D02*
Y3542092D01*
G01X461490Y3550092D02*
X466090D01*
G01X471790Y3542092D02*
X470990Y3542225D01*
X470290Y3542759D01*
X469690Y3543559D01*
X469290Y3544492D01*
X469090Y3545559D01*
Y3546625D01*
X469290Y3547692D01*
X469690Y3548625D01*
X470290Y3549425D01*
X470990Y3549959D01*
X471790Y3550092D01*
X472590Y3549959D01*
X473290Y3549425D01*
X473890Y3548625D01*
X474290Y3547692D01*
X474490Y3546625D01*
Y3545559D01*
X474290Y3544492D01*
X473890Y3543559D01*
X473290Y3542759D01*
X472590Y3542225D01*
X471790Y3542092D01*
G01X477790Y3550092D02*
Y3542092D01*
X481790D01*
G01X489790D02*
X485790D01*
Y3550092D01*
X489790D01*
G01X488190Y3546225D02*
X485790D01*
G01X493790Y3542092D02*
Y3550092D01*
X496290D01*
X497090Y3549692D01*
X497590Y3549159D01*
X497790Y3548092D01*
X497590Y3547025D01*
X496990Y3546359D01*
X496290Y3545959D01*
X493790D01*
G01X496290D02*
X497790Y3542092D01*
G01X501290D02*
X503790Y3550092D01*
X506290Y3542092D01*
G01X505390Y3544892D02*
X502190D01*
G01X509490Y3542092D02*
Y3550092D01*
X514090Y3542092D01*
Y3550092D01*
G01X521990Y3549425D02*
X521390Y3549825D01*
X520690Y3550092D01*
X519890D01*
X518990Y3549692D01*
X518290Y3549025D01*
X517790Y3548225D01*
X517390Y3546892D01*
X517290Y3545692D01*
X517490Y3544492D01*
X517790Y3543692D01*
X518390Y3542892D01*
X519090Y3542359D01*
X519790Y3542092D01*
X520490D01*
X521190Y3542359D01*
X521790Y3542759D01*
X522290Y3543292D01*
G01X529790Y3542092D02*
X525790D01*
Y3550092D01*
X529790D01*
G01X528190Y3546225D02*
X525790D01*
G01X543790Y3541825D02*
X543590Y3541959D01*
Y3542225D01*
X543790Y3542359D01*
X543990Y3542225D01*
Y3541959D01*
X543790Y3541825D01*
G01Y3545425D02*
X543590Y3545559D01*
Y3545825D01*
X543790Y3545959D01*
X543990Y3545825D01*
Y3545559D01*
X543790Y3545425D01*
G01X558690Y3544759D02*
X561090D01*
G01X559790Y3546492D02*
Y3543025D01*
G01X565990Y3541825D02*
X569590Y3550092D01*
G01X574490Y3544759D02*
X577090D01*
G01X581590Y3543292D02*
X582190Y3542625D01*
X582890Y3542225D01*
X583790Y3542092D01*
X584690Y3542359D01*
X585390Y3542892D01*
X585890Y3543825D01*
X585990Y3544892D01*
X585790Y3545959D01*
X585290Y3546625D01*
X584590Y3547159D01*
X583890Y3547292D01*
X583190Y3547159D01*
X582290Y3546625D01*
X582590Y3550092D01*
X585290D01*
G01X591290Y3539425D02*
X590290Y3540759D01*
X589790Y3542092D01*
Y3547425D01*
X590290Y3548759D01*
X591290Y3550092D01*
G01X597190Y3542092D02*
Y3550092D01*
X599790Y3543425D01*
X602390Y3550092D01*
Y3542092D01*
G01X606590Y3550092D02*
X608990D01*
G01X607790D02*
Y3542092D01*
G01X606590D02*
X608990D01*
G01X613790Y3550092D02*
Y3542092D01*
X617790D01*
G01X624290Y3539425D02*
X625290Y3540759D01*
X625790Y3542092D01*
Y3547425D01*
X625290Y3548759D01*
X624290Y3550092D01*
G01X631590Y3540625D02*
X631990Y3542359D01*
G01X645490Y3542092D02*
Y3550092D01*
X650090Y3542092D01*
Y3550092D01*
G01X653790Y3542092D02*
Y3550092D01*
X656190D01*
X656990Y3549692D01*
X657590Y3548759D01*
X657790Y3547692D01*
X657590Y3546625D01*
X657090Y3545825D01*
X656190Y3545425D01*
X653790D01*
G01X663790Y3550092D02*
Y3542092D01*
G01X661490Y3550092D02*
X666090D01*
G01X669690Y3542092D02*
Y3550092D01*
G01X673890D02*
Y3542092D01*
G01Y3546092D02*
X669690D01*
G01X687790Y3550092D02*
Y3542092D01*
G01X685490Y3550092D02*
X690090D01*
G01X695790Y3542092D02*
X694990Y3542225D01*
X694290Y3542759D01*
X693690Y3543559D01*
X693290Y3544492D01*
X693090Y3545559D01*
Y3546625D01*
X693290Y3547692D01*
X693690Y3548625D01*
X694290Y3549425D01*
X694990Y3549959D01*
X695790Y3550092D01*
X696590Y3549959D01*
X697290Y3549425D01*
X697890Y3548625D01*
X698290Y3547692D01*
X698490Y3546625D01*
Y3545559D01*
X698290Y3544492D01*
X697890Y3543559D01*
X697290Y3542759D01*
X696590Y3542225D01*
X695790Y3542092D01*
G01X701790Y3550092D02*
Y3542092D01*
X705790D01*
G01X713790D02*
X709790D01*
Y3550092D01*
X713790D01*
G01X712190Y3546225D02*
X709790D01*
G01X717790Y3542092D02*
Y3550092D01*
X720290D01*
X721090Y3549692D01*
X721590Y3549159D01*
X721790Y3548092D01*
X721590Y3547025D01*
X720990Y3546359D01*
X720290Y3545959D01*
X717790D01*
G01X720290D02*
X721790Y3542092D01*
G01X725290D02*
X727790Y3550092D01*
X730290Y3542092D01*
G01X729390Y3544892D02*
X726190D01*
G01X733490Y3542092D02*
Y3550092D01*
X738090Y3542092D01*
Y3550092D01*
G01X745990Y3549425D02*
X745390Y3549825D01*
X744690Y3550092D01*
X743890D01*
X742990Y3549692D01*
X742290Y3549025D01*
X741790Y3548225D01*
X741390Y3546892D01*
X741290Y3545692D01*
X741490Y3544492D01*
X741790Y3543692D01*
X742390Y3542892D01*
X743090Y3542359D01*
X743790Y3542092D01*
X744490D01*
X745190Y3542359D01*
X745790Y3542759D01*
X746290Y3543292D01*
G01X753790Y3542092D02*
X749790D01*
Y3550092D01*
X753790D01*
G01X752190Y3546225D02*
X749790D01*
G01X759790Y3541825D02*
X759590Y3541959D01*
Y3542225D01*
X759790Y3542359D01*
X759990Y3542225D01*
Y3541959D01*
X759790Y3541825D01*
G01Y3545425D02*
X759590Y3545559D01*
Y3545825D01*
X759790Y3545959D01*
X759990Y3545825D01*
Y3545559D01*
X759790Y3545425D01*
G01X774690Y3544759D02*
X777090D01*
G01X775790Y3546492D02*
Y3543025D01*
G01X781990Y3541825D02*
X785590Y3550092D01*
G01X790490Y3544759D02*
X793090D01*
G01X800990Y3542092D02*
Y3550092D01*
X797290Y3544359D01*
X802290D01*
G01X807290Y3539425D02*
X806290Y3540759D01*
X805790Y3542092D01*
Y3547425D01*
X806290Y3548759D01*
X807290Y3550092D01*
G01X813190Y3542092D02*
Y3550092D01*
X815790Y3543425D01*
X818390Y3550092D01*
Y3542092D01*
G01X822590Y3550092D02*
X824990D01*
G01X823790D02*
Y3542092D01*
G01X822590D02*
X824990D01*
G01X829790Y3550092D02*
Y3542092D01*
X833790D01*
G01X840290Y3539425D02*
X841290Y3540759D01*
X841790Y3542092D01*
Y3547425D01*
X841290Y3548759D01*
X840290Y3550092D01*
G01X847790Y3541825D02*
X847590Y3541959D01*
Y3542225D01*
X847790Y3542359D01*
X847990Y3542225D01*
Y3541959D01*
X847790Y3541825D01*
G01X-48210Y3557092D02*
X-47510Y3557225D01*
X-46710Y3557625D01*
X-46210Y3558292D01*
X-46010Y3559225D01*
X-46210Y3560158D01*
X-46810Y3560959D01*
X-47710Y3561359D01*
X-48710D01*
X-49310Y3561625D01*
X-49810Y3562292D01*
X-50010Y3563225D01*
X-49710Y3564159D01*
X-49010Y3564825D01*
X-48210Y3565092D01*
X-47410Y3564825D01*
X-46710Y3564159D01*
X-46410Y3563225D01*
X-46610Y3562292D01*
X-47110Y3561625D01*
X-47710Y3561359D01*
X-48710D01*
X-49610Y3560959D01*
X-50210Y3560158D01*
X-50410Y3559225D01*
X-50210Y3558292D01*
X-49710Y3557625D01*
X-48910Y3557225D01*
X-48210Y3557092D01*
G01X-40210Y3556825D02*
X-40410Y3556959D01*
Y3557225D01*
X-40210Y3557359D01*
X-40010Y3557225D01*
Y3556959D01*
X-40210Y3556825D01*
G01X-34510Y3557092D02*
Y3565092D01*
X-29910Y3557092D01*
Y3565092D01*
G01X-24210Y3557092D02*
X-25010Y3557225D01*
X-25710Y3557759D01*
X-26310Y3558559D01*
X-26710Y3559492D01*
X-26910Y3560559D01*
Y3561625D01*
X-26710Y3562692D01*
X-26310Y3563625D01*
X-25710Y3564425D01*
X-25010Y3564959D01*
X-24210Y3565092D01*
X-23410Y3564959D01*
X-22710Y3564425D01*
X-22110Y3563625D01*
X-21710Y3562692D01*
X-21510Y3561625D01*
Y3560559D01*
X-21710Y3559492D01*
X-22110Y3558559D01*
X-22710Y3557759D01*
X-23410Y3557225D01*
X-24210Y3557092D01*
G01X-16210Y3565092D02*
Y3557092D01*
G01X-18510Y3565092D02*
X-13910D01*
G01X-2710Y3557092D02*
X-210Y3565092D01*
X2290Y3557092D01*
G01X1390Y3559892D02*
X-1810D01*
G01X5790Y3565092D02*
Y3557092D01*
X9790D01*
G01X13790Y3565092D02*
Y3557092D01*
X17790D01*
G01X23790D02*
X22990Y3557225D01*
X22290Y3557759D01*
X21690Y3558559D01*
X21290Y3559492D01*
X21090Y3560559D01*
Y3561625D01*
X21290Y3562692D01*
X21690Y3563625D01*
X22290Y3564425D01*
X22990Y3564959D01*
X23790Y3565092D01*
X24590Y3564959D01*
X25290Y3564425D01*
X25890Y3563625D01*
X26290Y3562692D01*
X26490Y3561625D01*
Y3560559D01*
X26290Y3559492D01*
X25890Y3558559D01*
X25290Y3557759D01*
X24590Y3557225D01*
X23790Y3557092D01*
G01X28790Y3565092D02*
X30190Y3557092D01*
X31790Y3565092D01*
X33390Y3557092D01*
X34790Y3565092D01*
G01X48590Y3561359D02*
X48990Y3561759D01*
X49290Y3562425D01*
X49490Y3563359D01*
X49290Y3564159D01*
X48890Y3564692D01*
X48190Y3565092D01*
X45490D01*
Y3557092D01*
X48790D01*
X49490Y3557625D01*
X49890Y3558425D01*
X50090Y3559359D01*
X49890Y3560292D01*
X49290Y3561092D01*
X48590Y3561359D01*
X45490D01*
G01X53790Y3557092D02*
Y3565092D01*
X56290D01*
X57090Y3564692D01*
X57590Y3564159D01*
X57790Y3563092D01*
X57590Y3562025D01*
X56990Y3561359D01*
X56290Y3560959D01*
X53790D01*
G01X56290D02*
X57790Y3557092D01*
G01X65790D02*
X61790D01*
Y3565092D01*
X65790D01*
G01X64190Y3561225D02*
X61790D01*
G01X69290Y3557092D02*
X71790Y3565092D01*
X74290Y3557092D01*
G01X73390Y3559892D02*
X70190D01*
G01X77590Y3557092D02*
Y3565092D01*
G01X81390D02*
X77590Y3560158D01*
G01X81990Y3557092D02*
X79290Y3562425D01*
G01X87790Y3557092D02*
X86990Y3557225D01*
X86290Y3557759D01*
X85690Y3558559D01*
X85290Y3559492D01*
X85090Y3560559D01*
Y3561625D01*
X85290Y3562692D01*
X85690Y3563625D01*
X86290Y3564425D01*
X86990Y3564959D01*
X87790Y3565092D01*
X88590Y3564959D01*
X89290Y3564425D01*
X89890Y3563625D01*
X90290Y3562692D01*
X90490Y3561625D01*
Y3560559D01*
X90290Y3559492D01*
X89890Y3558559D01*
X89290Y3557759D01*
X88590Y3557225D01*
X87790Y3557092D01*
G01X93590Y3565092D02*
Y3559359D01*
X93990Y3558158D01*
X94790Y3557359D01*
X95790Y3557092D01*
X96790Y3557359D01*
X97590Y3558158D01*
X97990Y3559359D01*
Y3565092D01*
G01X103790D02*
Y3557092D01*
G01X101490Y3565092D02*
X106090D01*
G01X117890Y3557092D02*
Y3565092D01*
X121690D01*
G01X120290Y3561225D02*
X117890D01*
G01X127790Y3557092D02*
X126990Y3557225D01*
X126290Y3557759D01*
X125690Y3558559D01*
X125290Y3559492D01*
X125090Y3560559D01*
Y3561625D01*
X125290Y3562692D01*
X125690Y3563625D01*
X126290Y3564425D01*
X126990Y3564959D01*
X127790Y3565092D01*
X128590Y3564959D01*
X129290Y3564425D01*
X129890Y3563625D01*
X130290Y3562692D01*
X130490Y3561625D01*
Y3560559D01*
X130290Y3559492D01*
X129890Y3558559D01*
X129290Y3557759D01*
X128590Y3557225D01*
X127790Y3557092D01*
G01X133790D02*
Y3565092D01*
X136290D01*
X137090Y3564692D01*
X137590Y3564159D01*
X137790Y3563092D01*
X137590Y3562025D01*
X136990Y3561359D01*
X136290Y3560959D01*
X133790D01*
G01X136290D02*
X137790Y3557092D01*
G01X149790Y3565092D02*
Y3557092D01*
X153790D01*
G01X157290D02*
X159790Y3565092D01*
X162290Y3557092D01*
G01X161390Y3559892D02*
X158190D01*
G01X165690Y3558158D02*
X166490Y3557492D01*
X167390Y3557092D01*
X168190D01*
X168990Y3557492D01*
X169590Y3558158D01*
X169890Y3559092D01*
X169690Y3560025D01*
X169190Y3560825D01*
X168290Y3561359D01*
X167090Y3561625D01*
X166390Y3562159D01*
X166090Y3563092D01*
X166290Y3564025D01*
X166790Y3564692D01*
X167490Y3565092D01*
X168190D01*
X168890Y3564825D01*
X169490Y3564159D01*
G01X177790Y3557092D02*
X173790D01*
Y3565092D01*
X177790D01*
G01X176190Y3561225D02*
X173790D01*
G01X181790Y3557092D02*
Y3565092D01*
X184290D01*
X185090Y3564692D01*
X185590Y3564159D01*
X185790Y3563092D01*
X185590Y3562025D01*
X184990Y3561359D01*
X184290Y3560959D01*
X181790D01*
G01X184290D02*
X185790Y3557092D01*
G01X197290Y3565092D02*
X199790Y3557092D01*
X202290Y3565092D01*
G01X206590D02*
X208990D01*
G01X207790D02*
Y3557092D01*
G01X206590D02*
X208990D01*
G01X213290D02*
X215790Y3565092D01*
X218290Y3557092D01*
G01X217390Y3559892D02*
X214190D01*
G01X229690Y3557092D02*
Y3565092D01*
G01X233890D02*
Y3557092D01*
G01Y3561092D02*
X229690D01*
G01X239790Y3557092D02*
X238990Y3557225D01*
X238290Y3557759D01*
X237690Y3558559D01*
X237290Y3559492D01*
X237090Y3560559D01*
Y3561625D01*
X237290Y3562692D01*
X237690Y3563625D01*
X238290Y3564425D01*
X238990Y3564959D01*
X239790Y3565092D01*
X240590Y3564959D01*
X241290Y3564425D01*
X241890Y3563625D01*
X242290Y3562692D01*
X242490Y3561625D01*
Y3560559D01*
X242290Y3559492D01*
X241890Y3558559D01*
X241290Y3557759D01*
X240590Y3557225D01*
X239790Y3557092D01*
G01X245790Y3565092D02*
Y3557092D01*
X249790D01*
G01X257790D02*
X253790D01*
Y3565092D01*
X257790D01*
G01X256190Y3561225D02*
X253790D01*
G01X263790Y3556825D02*
X263590Y3556959D01*
Y3557225D01*
X263790Y3557359D01*
X263990Y3557225D01*
Y3556959D01*
X263790Y3556825D01*
G01X-48410Y3572092D02*
X-48210Y3573825D01*
X-47910Y3575292D01*
X-47510Y3576625D01*
X-47010Y3578092D01*
X-46210Y3580092D01*
X-50210D01*
G01X-40210Y3571825D02*
X-40410Y3571959D01*
Y3572225D01*
X-40210Y3572359D01*
X-40010Y3572225D01*
Y3571959D01*
X-40210Y3571825D01*
G01X-34110Y3572092D02*
Y3580092D01*
X-30310D01*
G01X-31710Y3576225D02*
X-34110D01*
G01X-24210Y3572092D02*
X-25010Y3572225D01*
X-25710Y3572759D01*
X-26310Y3573559D01*
X-26710Y3574492D01*
X-26910Y3575559D01*
Y3576625D01*
X-26710Y3577692D01*
X-26310Y3578625D01*
X-25710Y3579425D01*
X-25010Y3579959D01*
X-24210Y3580092D01*
X-23410Y3579959D01*
X-22710Y3579425D01*
X-22110Y3578625D01*
X-21710Y3577692D01*
X-21510Y3576625D01*
Y3575559D01*
X-21710Y3574492D01*
X-22110Y3573559D01*
X-22710Y3572759D01*
X-23410Y3572225D01*
X-24210Y3572092D01*
G01X-18210D02*
Y3580092D01*
X-15710D01*
X-14910Y3579692D01*
X-14410Y3579159D01*
X-14210Y3578092D01*
X-14410Y3577025D01*
X-15010Y3576359D01*
X-15710Y3575959D01*
X-18210D01*
G01X-15710D02*
X-14210Y3572092D01*
G01X-210D02*
Y3580092D01*
X-1410Y3578492D01*
G01Y3572092D02*
X990D01*
G01X7790Y3580092D02*
X6990Y3579825D01*
X6390Y3579159D01*
X5990Y3578359D01*
X5690Y3577292D01*
X5590Y3576092D01*
X5690Y3574892D01*
X5990Y3573825D01*
X6390Y3573025D01*
X6990Y3572359D01*
X7790Y3572092D01*
X8590Y3572359D01*
X9190Y3573025D01*
X9590Y3573825D01*
X9890Y3574892D01*
X9990Y3576092D01*
X9890Y3577292D01*
X9590Y3578359D01*
X9190Y3579159D01*
X8590Y3579825D01*
X7790Y3580092D01*
G01X13190Y3572092D02*
Y3580092D01*
X15790Y3573425D01*
X18390Y3580092D01*
Y3572092D01*
G01X22590Y3580092D02*
X24990D01*
G01X23790D02*
Y3572092D01*
G01X22590D02*
X24990D01*
G01X29790Y3580092D02*
Y3572092D01*
X33790D01*
G01X37690Y3573158D02*
X38490Y3572492D01*
X39390Y3572092D01*
X40190D01*
X40990Y3572492D01*
X41590Y3573158D01*
X41890Y3574092D01*
X41690Y3575025D01*
X41190Y3575825D01*
X40290Y3576359D01*
X39090Y3576625D01*
X38390Y3577159D01*
X38090Y3578092D01*
X38290Y3579025D01*
X38790Y3579692D01*
X39490Y3580092D01*
X40190D01*
X40890Y3579825D01*
X41490Y3579159D01*
G01X53290Y3580092D02*
X55790Y3572092D01*
X58290Y3580092D01*
G01X62590D02*
X64990D01*
G01X63790D02*
Y3572092D01*
G01X62590D02*
X64990D01*
G01X69290D02*
X71790Y3580092D01*
X74290Y3572092D01*
G01X73390Y3574892D02*
X70190D01*
G01X77690Y3573158D02*
X78490Y3572492D01*
X79390Y3572092D01*
X80190D01*
X80990Y3572492D01*
X81590Y3573158D01*
X81890Y3574092D01*
X81690Y3575025D01*
X81190Y3575825D01*
X80290Y3576359D01*
X79090Y3576625D01*
X78390Y3577159D01*
X78090Y3578092D01*
X78290Y3579025D01*
X78790Y3579692D01*
X79490Y3580092D01*
X80190D01*
X80890Y3579825D01*
X81490Y3579159D01*
G01X93590Y3580092D02*
Y3574359D01*
X93990Y3573158D01*
X94790Y3572359D01*
X95790Y3572092D01*
X96790Y3572359D01*
X97590Y3573158D01*
X97990Y3574359D01*
Y3580092D01*
G01X101690Y3573158D02*
X102490Y3572492D01*
X103390Y3572092D01*
X104190D01*
X104990Y3572492D01*
X105590Y3573158D01*
X105890Y3574092D01*
X105690Y3575025D01*
X105190Y3575825D01*
X104290Y3576359D01*
X103090Y3576625D01*
X102390Y3577159D01*
X102090Y3578092D01*
X102290Y3579025D01*
X102790Y3579692D01*
X103490Y3580092D01*
X104190D01*
X104890Y3579825D01*
X105490Y3579159D01*
G01X113790Y3572092D02*
X109790D01*
Y3580092D01*
X113790D01*
G01X112190Y3576225D02*
X109790D01*
G01X126090Y3573025D02*
X126790Y3572359D01*
X127590Y3572092D01*
X128390Y3572359D01*
X129090Y3573158D01*
X129590Y3574359D01*
X129790Y3575559D01*
Y3577025D01*
X129590Y3578225D01*
X129090Y3579292D01*
X128490Y3579825D01*
X127790Y3580092D01*
X126990Y3579825D01*
X126390Y3579292D01*
X125990Y3578492D01*
X125790Y3577425D01*
X125990Y3576492D01*
X126490Y3575559D01*
X127090Y3575025D01*
X127790Y3574892D01*
X128590Y3575158D01*
X129190Y3575825D01*
X129790Y3577025D01*
G01X135790Y3571825D02*
X135590Y3571959D01*
Y3572225D01*
X135790Y3572359D01*
X135990Y3572225D01*
Y3571959D01*
X135790Y3571825D01*
G01X143790Y3572092D02*
X144490Y3572225D01*
X145290Y3572625D01*
X145790Y3573292D01*
X145990Y3574225D01*
X145790Y3575158D01*
X145190Y3575959D01*
X144290Y3576359D01*
X143290D01*
X142690Y3576625D01*
X142190Y3577292D01*
X141990Y3578225D01*
X142290Y3579159D01*
X142990Y3579825D01*
X143790Y3580092D01*
X144590Y3579825D01*
X145290Y3579159D01*
X145590Y3578225D01*
X145390Y3577292D01*
X144890Y3576625D01*
X144290Y3576359D01*
X143290D01*
X142390Y3575959D01*
X141790Y3575158D01*
X141590Y3574225D01*
X141790Y3573292D01*
X142290Y3572625D01*
X143090Y3572225D01*
X143790Y3572092D01*
G01X149190D02*
Y3580092D01*
X151790Y3573425D01*
X154390Y3580092D01*
Y3572092D01*
G01X158590Y3580092D02*
X160990D01*
G01X159790D02*
Y3572092D01*
G01X158590D02*
X160990D01*
G01X165790Y3580092D02*
Y3572092D01*
X169790D01*
G01X173690Y3573158D02*
X174490Y3572492D01*
X175390Y3572092D01*
X176190D01*
X176990Y3572492D01*
X177590Y3573158D01*
X177890Y3574092D01*
X177690Y3575025D01*
X177190Y3575825D01*
X176290Y3576359D01*
X175090Y3576625D01*
X174390Y3577159D01*
X174090Y3578092D01*
X174290Y3579025D01*
X174790Y3579692D01*
X175490Y3580092D01*
X176190D01*
X176890Y3579825D01*
X177490Y3579159D01*
G01X189590Y3572092D02*
Y3580092D01*
X191590D01*
X192390Y3579692D01*
X192990Y3579159D01*
X193490Y3578359D01*
X193890Y3577425D01*
X193990Y3576092D01*
X193890Y3574759D01*
X193490Y3573825D01*
X192990Y3573025D01*
X192390Y3572492D01*
X191590Y3572092D01*
X189590D01*
G01X197790D02*
Y3580092D01*
X200290D01*
X201090Y3579692D01*
X201590Y3579159D01*
X201790Y3578092D01*
X201590Y3577025D01*
X200990Y3576359D01*
X200290Y3575959D01*
X197790D01*
G01X200290D02*
X201790Y3572092D01*
G01X206590Y3580092D02*
X208990D01*
G01X207790D02*
Y3572092D01*
G01X206590D02*
X208990D01*
G01X213790Y3580092D02*
Y3572092D01*
X217790D01*
G01X221790Y3580092D02*
Y3572092D01*
X225790D01*
G01X240590Y3576359D02*
X240990Y3576759D01*
X241290Y3577425D01*
X241490Y3578359D01*
X241290Y3579159D01*
X240890Y3579692D01*
X240190Y3580092D01*
X237490D01*
Y3572092D01*
X240790D01*
X241490Y3572625D01*
X241890Y3573425D01*
X242090Y3574359D01*
X241890Y3575292D01*
X241290Y3576092D01*
X240590Y3576359D01*
X237490D01*
G01X246590Y3580092D02*
X248990D01*
G01X247790D02*
Y3572092D01*
G01X246590D02*
X248990D01*
G01X255790Y3580092D02*
Y3572092D01*
G01X253490Y3580092D02*
X258090D01*
G01X263790Y3571825D02*
X263590Y3571959D01*
Y3572225D01*
X263790Y3572359D01*
X263990Y3572225D01*
Y3571959D01*
X263790Y3571825D01*
G01X277890Y3572092D02*
Y3580092D01*
X281690D01*
G01X280290Y3576225D02*
X277890D01*
G01X287790Y3572092D02*
X286990Y3572225D01*
X286290Y3572759D01*
X285690Y3573559D01*
X285290Y3574492D01*
X285090Y3575559D01*
Y3576625D01*
X285290Y3577692D01*
X285690Y3578625D01*
X286290Y3579425D01*
X286990Y3579959D01*
X287790Y3580092D01*
X288590Y3579959D01*
X289290Y3579425D01*
X289890Y3578625D01*
X290290Y3577692D01*
X290490Y3576625D01*
Y3575559D01*
X290290Y3574492D01*
X289890Y3573559D01*
X289290Y3572759D01*
X288590Y3572225D01*
X287790Y3572092D01*
G01X293790D02*
Y3580092D01*
X296290D01*
X297090Y3579692D01*
X297590Y3579159D01*
X297790Y3578092D01*
X297590Y3577025D01*
X296990Y3576359D01*
X296290Y3575959D01*
X293790D01*
G01X296290D02*
X297790Y3572092D01*
G01X311790D02*
X312490Y3572225D01*
X313290Y3572625D01*
X313790Y3573292D01*
X313990Y3574225D01*
X313790Y3575158D01*
X313190Y3575959D01*
X312290Y3576359D01*
X311290D01*
X310690Y3576625D01*
X310190Y3577292D01*
X309990Y3578225D01*
X310290Y3579159D01*
X310990Y3579825D01*
X311790Y3580092D01*
X312590Y3579825D01*
X313290Y3579159D01*
X313590Y3578225D01*
X313390Y3577292D01*
X312890Y3576625D01*
X312290Y3576359D01*
X311290D01*
X310390Y3575959D01*
X309790Y3575158D01*
X309590Y3574225D01*
X309790Y3573292D01*
X310290Y3572625D01*
X311090Y3572225D01*
X311790Y3572092D01*
G01X317190D02*
Y3580092D01*
X319790Y3573425D01*
X322390Y3580092D01*
Y3572092D01*
G01X326590Y3580092D02*
X328990D01*
G01X327790D02*
Y3572092D01*
G01X326590D02*
X328990D01*
G01X333790Y3580092D02*
Y3572092D01*
X337790D01*
G01X341690Y3573158D02*
X342490Y3572492D01*
X343390Y3572092D01*
X344190D01*
X344990Y3572492D01*
X345590Y3573158D01*
X345890Y3574092D01*
X345690Y3575025D01*
X345190Y3575825D01*
X344290Y3576359D01*
X343090Y3576625D01*
X342390Y3577159D01*
X342090Y3578092D01*
X342290Y3579025D01*
X342790Y3579692D01*
X343490Y3580092D01*
X344190D01*
X344890Y3579825D01*
X345490Y3579159D01*
G01X357290Y3580092D02*
X359790Y3572092D01*
X362290Y3580092D01*
G01X366590D02*
X368990D01*
G01X367790D02*
Y3572092D01*
G01X366590D02*
X368990D01*
G01X373290D02*
X375790Y3580092D01*
X378290Y3572092D01*
G01X377390Y3574892D02*
X374190D01*
G01X381690Y3573158D02*
X382490Y3572492D01*
X383390Y3572092D01*
X384190D01*
X384990Y3572492D01*
X385590Y3573158D01*
X385890Y3574092D01*
X385690Y3575025D01*
X385190Y3575825D01*
X384290Y3576359D01*
X383090Y3576625D01*
X382390Y3577159D01*
X382090Y3578092D01*
X382290Y3579025D01*
X382790Y3579692D01*
X383490Y3580092D01*
X384190D01*
X384890Y3579825D01*
X385490Y3579159D01*
G01X397590Y3580092D02*
Y3574359D01*
X397990Y3573158D01*
X398790Y3572359D01*
X399790Y3572092D01*
X400790Y3572359D01*
X401590Y3573158D01*
X401990Y3574359D01*
Y3580092D01*
G01X405690Y3573158D02*
X406490Y3572492D01*
X407390Y3572092D01*
X408190D01*
X408990Y3572492D01*
X409590Y3573158D01*
X409890Y3574092D01*
X409690Y3575025D01*
X409190Y3575825D01*
X408290Y3576359D01*
X407090Y3576625D01*
X406390Y3577159D01*
X406090Y3578092D01*
X406290Y3579025D01*
X406790Y3579692D01*
X407490Y3580092D01*
X408190D01*
X408890Y3579825D01*
X409490Y3579159D01*
G01X417790Y3572092D02*
X413790D01*
Y3580092D01*
X417790D01*
G01X416190Y3576225D02*
X413790D01*
G01X431590Y3572092D02*
X431790Y3573825D01*
X432090Y3575292D01*
X432490Y3576625D01*
X432990Y3578092D01*
X433790Y3580092D01*
X429790D01*
G01X439790Y3571825D02*
X439590Y3571959D01*
Y3572225D01*
X439790Y3572359D01*
X439990Y3572225D01*
Y3571959D01*
X439790Y3571825D01*
G01X446090Y3573025D02*
X446790Y3572359D01*
X447590Y3572092D01*
X448390Y3572359D01*
X449090Y3573158D01*
X449590Y3574359D01*
X449790Y3575559D01*
Y3577025D01*
X449590Y3578225D01*
X449090Y3579292D01*
X448490Y3579825D01*
X447790Y3580092D01*
X446990Y3579825D01*
X446390Y3579292D01*
X445990Y3578492D01*
X445790Y3577425D01*
X445990Y3576492D01*
X446490Y3575559D01*
X447090Y3575025D01*
X447790Y3574892D01*
X448590Y3575158D01*
X449190Y3575825D01*
X449790Y3577025D01*
G01X453190Y3572092D02*
Y3580092D01*
X455790Y3573425D01*
X458390Y3580092D01*
Y3572092D01*
G01X462590Y3580092D02*
X464990D01*
G01X463790D02*
Y3572092D01*
G01X462590D02*
X464990D01*
G01X469790Y3580092D02*
Y3572092D01*
X473790D01*
G01X477690Y3573158D02*
X478490Y3572492D01*
X479390Y3572092D01*
X480190D01*
X480990Y3572492D01*
X481590Y3573158D01*
X481890Y3574092D01*
X481690Y3575025D01*
X481190Y3575825D01*
X480290Y3576359D01*
X479090Y3576625D01*
X478390Y3577159D01*
X478090Y3578092D01*
X478290Y3579025D01*
X478790Y3579692D01*
X479490Y3580092D01*
X480190D01*
X480890Y3579825D01*
X481490Y3579159D01*
G01X493590Y3572092D02*
Y3580092D01*
X495590D01*
X496390Y3579692D01*
X496990Y3579159D01*
X497490Y3578359D01*
X497890Y3577425D01*
X497990Y3576092D01*
X497890Y3574759D01*
X497490Y3573825D01*
X496990Y3573025D01*
X496390Y3572492D01*
X495590Y3572092D01*
X493590D01*
G01X501790D02*
Y3580092D01*
X504290D01*
X505090Y3579692D01*
X505590Y3579159D01*
X505790Y3578092D01*
X505590Y3577025D01*
X504990Y3576359D01*
X504290Y3575959D01*
X501790D01*
G01X504290D02*
X505790Y3572092D01*
G01X510590Y3580092D02*
X512990D01*
G01X511790D02*
Y3572092D01*
G01X510590D02*
X512990D01*
G01X517790Y3580092D02*
Y3572092D01*
X521790D01*
G01X525790Y3580092D02*
Y3572092D01*
X529790D01*
G01X544590Y3576359D02*
X544990Y3576759D01*
X545290Y3577425D01*
X545490Y3578359D01*
X545290Y3579159D01*
X544890Y3579692D01*
X544190Y3580092D01*
X541490D01*
Y3572092D01*
X544790D01*
X545490Y3572625D01*
X545890Y3573425D01*
X546090Y3574359D01*
X545890Y3575292D01*
X545290Y3576092D01*
X544590Y3576359D01*
X541490D01*
G01X550590Y3580092D02*
X552990D01*
G01X551790D02*
Y3572092D01*
G01X550590D02*
X552990D01*
G01X559790Y3580092D02*
Y3572092D01*
G01X557490Y3580092D02*
X562090D01*
G01X567790Y3571825D02*
X567590Y3571959D01*
Y3572225D01*
X567790Y3572359D01*
X567990Y3572225D01*
Y3571959D01*
X567790Y3571825D01*
G01X573890Y3572092D02*
Y3580092D01*
X577690D01*
G01X576290Y3576225D02*
X573890D01*
G01X583790Y3572092D02*
X582990Y3572225D01*
X582290Y3572759D01*
X581690Y3573559D01*
X581290Y3574492D01*
X581090Y3575559D01*
Y3576625D01*
X581290Y3577692D01*
X581690Y3578625D01*
X582290Y3579425D01*
X582990Y3579959D01*
X583790Y3580092D01*
X584590Y3579959D01*
X585290Y3579425D01*
X585890Y3578625D01*
X586290Y3577692D01*
X586490Y3576625D01*
Y3575559D01*
X586290Y3574492D01*
X585890Y3573559D01*
X585290Y3572759D01*
X584590Y3572225D01*
X583790Y3572092D01*
G01X589790D02*
Y3580092D01*
X592290D01*
X593090Y3579692D01*
X593590Y3579159D01*
X593790Y3578092D01*
X593590Y3577025D01*
X592990Y3576359D01*
X592290Y3575959D01*
X589790D01*
G01X592290D02*
X593790Y3572092D01*
G01X605890Y3578759D02*
X606490Y3579559D01*
X607190Y3579959D01*
X607990Y3580092D01*
X608990Y3579825D01*
X609690Y3579159D01*
X609890Y3578359D01*
X609790Y3577558D01*
X609390Y3576892D01*
X607390Y3575559D01*
X606490Y3574625D01*
X605890Y3573292D01*
X605690Y3572092D01*
X609890D01*
G01X615790Y3580092D02*
X614990Y3579825D01*
X614390Y3579159D01*
X613990Y3578359D01*
X613690Y3577292D01*
X613590Y3576092D01*
X613690Y3574892D01*
X613990Y3573825D01*
X614390Y3573025D01*
X614990Y3572359D01*
X615790Y3572092D01*
X616590Y3572359D01*
X617190Y3573025D01*
X617590Y3573825D01*
X617890Y3574892D01*
X617990Y3576092D01*
X617890Y3577292D01*
X617590Y3578359D01*
X617190Y3579159D01*
X616590Y3579825D01*
X615790Y3580092D01*
G01X621190Y3572092D02*
Y3580092D01*
X623790Y3573425D01*
X626390Y3580092D01*
Y3572092D01*
G01X630590Y3580092D02*
X632990D01*
G01X631790D02*
Y3572092D01*
G01X630590D02*
X632990D01*
G01X637790Y3580092D02*
Y3572092D01*
X641790D01*
G01X645690Y3573158D02*
X646490Y3572492D01*
X647390Y3572092D01*
X648190D01*
X648990Y3572492D01*
X649590Y3573158D01*
X649890Y3574092D01*
X649690Y3575025D01*
X649190Y3575825D01*
X648290Y3576359D01*
X647090Y3576625D01*
X646390Y3577159D01*
X646090Y3578092D01*
X646290Y3579025D01*
X646790Y3579692D01*
X647490Y3580092D01*
X648190D01*
X648890Y3579825D01*
X649490Y3579159D01*
G01X661290Y3580092D02*
X663790Y3572092D01*
X666290Y3580092D01*
G01X670590D02*
X672990D01*
G01X671790D02*
Y3572092D01*
G01X670590D02*
X672990D01*
G01X677290D02*
X679790Y3580092D01*
X682290Y3572092D01*
G01X681390Y3574892D02*
X678190D01*
G01X685690Y3573158D02*
X686490Y3572492D01*
X687390Y3572092D01*
X688190D01*
X688990Y3572492D01*
X689590Y3573158D01*
X689890Y3574092D01*
X689690Y3575025D01*
X689190Y3575825D01*
X688290Y3576359D01*
X687090Y3576625D01*
X686390Y3577159D01*
X686090Y3578092D01*
X686290Y3579025D01*
X686790Y3579692D01*
X687490Y3580092D01*
X688190D01*
X688890Y3579825D01*
X689490Y3579159D01*
G01X701590Y3580092D02*
Y3574359D01*
X701990Y3573158D01*
X702790Y3572359D01*
X703790Y3572092D01*
X704790Y3572359D01*
X705590Y3573158D01*
X705990Y3574359D01*
Y3580092D01*
G01X709690Y3573158D02*
X710490Y3572492D01*
X711390Y3572092D01*
X712190D01*
X712990Y3572492D01*
X713590Y3573158D01*
X713890Y3574092D01*
X713690Y3575025D01*
X713190Y3575825D01*
X712290Y3576359D01*
X711090Y3576625D01*
X710390Y3577159D01*
X710090Y3578092D01*
X710290Y3579025D01*
X710790Y3579692D01*
X711490Y3580092D01*
X712190D01*
X712890Y3579825D01*
X713490Y3579159D01*
G01X721790Y3572092D02*
X717790D01*
Y3580092D01*
X721790D01*
G01X720190Y3576225D02*
X717790D01*
G01X735790Y3572092D02*
Y3580092D01*
X734590Y3578492D01*
G01Y3572092D02*
X736990D01*
G01X742090Y3573025D02*
X742790Y3572359D01*
X743590Y3572092D01*
X744390Y3572359D01*
X745090Y3573158D01*
X745590Y3574359D01*
X745790Y3575559D01*
Y3577025D01*
X745590Y3578225D01*
X745090Y3579292D01*
X744490Y3579825D01*
X743790Y3580092D01*
X742990Y3579825D01*
X742390Y3579292D01*
X741990Y3578492D01*
X741790Y3577425D01*
X741990Y3576492D01*
X742490Y3575559D01*
X743090Y3575025D01*
X743790Y3574892D01*
X744590Y3575158D01*
X745190Y3575825D01*
X745790Y3577025D01*
G01X751790Y3571825D02*
X751590Y3571959D01*
Y3572225D01*
X751790Y3572359D01*
X751990Y3572225D01*
Y3571959D01*
X751790Y3571825D01*
G01X759590Y3572092D02*
X759790Y3573825D01*
X760090Y3575292D01*
X760490Y3576625D01*
X760990Y3578092D01*
X761790Y3580092D01*
X757790D01*
G01X765190Y3572092D02*
Y3580092D01*
X767790Y3573425D01*
X770390Y3580092D01*
Y3572092D01*
G01X774590Y3580092D02*
X776990D01*
G01X775790D02*
Y3572092D01*
G01X774590D02*
X776990D01*
G01X781790Y3580092D02*
Y3572092D01*
X785790D01*
G01X789690Y3573158D02*
X790490Y3572492D01*
X791390Y3572092D01*
X792190D01*
X792990Y3572492D01*
X793590Y3573158D01*
X793890Y3574092D01*
X793690Y3575025D01*
X793190Y3575825D01*
X792290Y3576359D01*
X791090Y3576625D01*
X790390Y3577159D01*
X790090Y3578092D01*
X790290Y3579025D01*
X790790Y3579692D01*
X791490Y3580092D01*
X792190D01*
X792890Y3579825D01*
X793490Y3579159D01*
G01X805590Y3572092D02*
Y3580092D01*
X807590D01*
X808390Y3579692D01*
X808990Y3579159D01*
X809490Y3578359D01*
X809890Y3577425D01*
X809990Y3576092D01*
X809890Y3574759D01*
X809490Y3573825D01*
X808990Y3573025D01*
X808390Y3572492D01*
X807590Y3572092D01*
X805590D01*
G01X813790D02*
Y3580092D01*
X816290D01*
X817090Y3579692D01*
X817590Y3579159D01*
X817790Y3578092D01*
X817590Y3577025D01*
X816990Y3576359D01*
X816290Y3575959D01*
X813790D01*
G01X816290D02*
X817790Y3572092D01*
G01X822590Y3580092D02*
X824990D01*
G01X823790D02*
Y3572092D01*
G01X822590D02*
X824990D01*
G01X829790Y3580092D02*
Y3572092D01*
X833790D01*
G01X837790Y3580092D02*
Y3572092D01*
X841790D01*
G01X856590Y3576359D02*
X856990Y3576759D01*
X857290Y3577425D01*
X857490Y3578359D01*
X857290Y3579159D01*
X856890Y3579692D01*
X856190Y3580092D01*
X853490D01*
Y3572092D01*
X856790D01*
X857490Y3572625D01*
X857890Y3573425D01*
X858090Y3574359D01*
X857890Y3575292D01*
X857290Y3576092D01*
X856590Y3576359D01*
X853490D01*
G01X862590Y3580092D02*
X864990D01*
G01X863790D02*
Y3572092D01*
G01X862590D02*
X864990D01*
G01X871790Y3580092D02*
Y3572092D01*
G01X869490Y3580092D02*
X874090D01*
G01X879790Y3571825D02*
X879590Y3571959D01*
Y3572225D01*
X879790Y3572359D01*
X879990Y3572225D01*
Y3571959D01*
X879790Y3571825D01*
G01X-50110Y3590425D02*
X-49410Y3591359D01*
X-48810Y3591892D01*
X-48010Y3592159D01*
X-47310Y3591892D01*
X-46810Y3591359D01*
X-46410Y3590559D01*
X-46310Y3589625D01*
X-46410Y3588825D01*
X-46810Y3588025D01*
X-47410Y3587359D01*
X-48110Y3587092D01*
X-48910Y3587359D01*
X-49610Y3588158D01*
X-50010Y3589359D01*
X-50110Y3590692D01*
X-49910Y3592425D01*
X-49610Y3593359D01*
X-49110Y3594292D01*
X-48410Y3594959D01*
X-47710Y3595092D01*
X-47010Y3594825D01*
X-46510Y3594159D01*
G01X-40210Y3586825D02*
X-40410Y3586959D01*
Y3587225D01*
X-40210Y3587359D01*
X-40010Y3587225D01*
Y3586959D01*
X-40210Y3586825D01*
G01X-34110Y3593759D02*
X-33510Y3594559D01*
X-32810Y3594959D01*
X-32010Y3595092D01*
X-31010Y3594825D01*
X-30310Y3594159D01*
X-30110Y3593359D01*
X-30210Y3592558D01*
X-30610Y3591892D01*
X-32610Y3590559D01*
X-33510Y3589625D01*
X-34110Y3588292D01*
X-34310Y3587092D01*
X-30110D01*
G01X-16210D02*
X-17010Y3587225D01*
X-17710Y3587759D01*
X-18310Y3588559D01*
X-18710Y3589492D01*
X-18910Y3590559D01*
Y3591625D01*
X-18710Y3592692D01*
X-18310Y3593625D01*
X-17710Y3594425D01*
X-17010Y3594959D01*
X-16210Y3595092D01*
X-15410Y3594959D01*
X-14710Y3594425D01*
X-14110Y3593625D01*
X-13710Y3592692D01*
X-13510Y3591625D01*
Y3590559D01*
X-13710Y3589492D01*
X-14110Y3588559D01*
X-14710Y3587759D01*
X-15410Y3587225D01*
X-16210Y3587092D01*
G01X-10410Y3595092D02*
Y3589359D01*
X-10010Y3588158D01*
X-9210Y3587359D01*
X-8210Y3587092D01*
X-7210Y3587359D01*
X-6410Y3588158D01*
X-6010Y3589359D01*
Y3595092D01*
G01X-210D02*
Y3587092D01*
G01X-2510Y3595092D02*
X2090D01*
G01X5690Y3588158D02*
X6490Y3587492D01*
X7390Y3587092D01*
X8190D01*
X8990Y3587492D01*
X9590Y3588158D01*
X9890Y3589092D01*
X9690Y3590025D01*
X9190Y3590825D01*
X8290Y3591359D01*
X7090Y3591625D01*
X6390Y3592159D01*
X6090Y3593092D01*
X6290Y3594025D01*
X6790Y3594692D01*
X7490Y3595092D01*
X8190D01*
X8890Y3594825D01*
X9490Y3594159D01*
G01X14590Y3595092D02*
X16990D01*
G01X15790D02*
Y3587092D01*
G01X14590D02*
X16990D01*
G01X21590D02*
Y3595092D01*
X23590D01*
X24390Y3594692D01*
X24990Y3594159D01*
X25490Y3593359D01*
X25890Y3592425D01*
X25990Y3591092D01*
X25890Y3589759D01*
X25490Y3588825D01*
X24990Y3588025D01*
X24390Y3587492D01*
X23590Y3587092D01*
X21590D01*
G01X33790D02*
X29790D01*
Y3595092D01*
X33790D01*
G01X32190Y3591225D02*
X29790D01*
G01X48590Y3591359D02*
X48990Y3591759D01*
X49290Y3592425D01*
X49490Y3593359D01*
X49290Y3594159D01*
X48890Y3594692D01*
X48190Y3595092D01*
X45490D01*
Y3587092D01*
X48790D01*
X49490Y3587625D01*
X49890Y3588425D01*
X50090Y3589359D01*
X49890Y3590292D01*
X49290Y3591092D01*
X48590Y3591359D01*
X45490D01*
G01X55790Y3587092D02*
X54990Y3587225D01*
X54290Y3587759D01*
X53690Y3588559D01*
X53290Y3589492D01*
X53090Y3590559D01*
Y3591625D01*
X53290Y3592692D01*
X53690Y3593625D01*
X54290Y3594425D01*
X54990Y3594959D01*
X55790Y3595092D01*
X56590Y3594959D01*
X57290Y3594425D01*
X57890Y3593625D01*
X58290Y3592692D01*
X58490Y3591625D01*
Y3590559D01*
X58290Y3589492D01*
X57890Y3588559D01*
X57290Y3587759D01*
X56590Y3587225D01*
X55790Y3587092D01*
G01X61290D02*
X63790Y3595092D01*
X66290Y3587092D01*
G01X65390Y3589892D02*
X62190D01*
G01X69790Y3587092D02*
Y3595092D01*
X72290D01*
X73090Y3594692D01*
X73590Y3594159D01*
X73790Y3593092D01*
X73590Y3592025D01*
X72990Y3591359D01*
X72290Y3590959D01*
X69790D01*
G01X72290D02*
X73790Y3587092D01*
G01X77590D02*
Y3595092D01*
X79590D01*
X80390Y3594692D01*
X80990Y3594159D01*
X81490Y3593359D01*
X81890Y3592425D01*
X81990Y3591092D01*
X81890Y3589759D01*
X81490Y3588825D01*
X80990Y3588025D01*
X80390Y3587492D01*
X79590Y3587092D01*
X77590D01*
G01X95790D02*
X94990Y3587225D01*
X94290Y3587759D01*
X93690Y3588559D01*
X93290Y3589492D01*
X93090Y3590559D01*
Y3591625D01*
X93290Y3592692D01*
X93690Y3593625D01*
X94290Y3594425D01*
X94990Y3594959D01*
X95790Y3595092D01*
X96590Y3594959D01*
X97290Y3594425D01*
X97890Y3593625D01*
X98290Y3592692D01*
X98490Y3591625D01*
Y3590559D01*
X98290Y3589492D01*
X97890Y3588559D01*
X97290Y3587759D01*
X96590Y3587225D01*
X95790Y3587092D01*
G01X101590Y3595092D02*
Y3589359D01*
X101990Y3588158D01*
X102790Y3587359D01*
X103790Y3587092D01*
X104790Y3587359D01*
X105590Y3588158D01*
X105990Y3589359D01*
Y3595092D01*
G01X111790D02*
Y3587092D01*
G01X109490Y3595092D02*
X114090D01*
G01X117790D02*
Y3587092D01*
X121790D01*
G01X126590Y3595092D02*
X128990D01*
G01X127790D02*
Y3587092D01*
G01X126590D02*
X128990D01*
G01X133490D02*
Y3595092D01*
X138090Y3587092D01*
Y3595092D01*
G01X145790Y3587092D02*
X141790D01*
Y3595092D01*
X145790D01*
G01X144190Y3591225D02*
X141790D01*
G01X157890Y3587092D02*
Y3595092D01*
X161690D01*
G01X160290Y3591225D02*
X157890D01*
G01X167790Y3587092D02*
X166990Y3587225D01*
X166290Y3587759D01*
X165690Y3588559D01*
X165290Y3589492D01*
X165090Y3590559D01*
Y3591625D01*
X165290Y3592692D01*
X165690Y3593625D01*
X166290Y3594425D01*
X166990Y3594959D01*
X167790Y3595092D01*
X168590Y3594959D01*
X169290Y3594425D01*
X169890Y3593625D01*
X170290Y3592692D01*
X170490Y3591625D01*
Y3590559D01*
X170290Y3589492D01*
X169890Y3588559D01*
X169290Y3587759D01*
X168590Y3587225D01*
X167790Y3587092D01*
G01X173790Y3595092D02*
Y3587092D01*
X177790D01*
G01X181790Y3595092D02*
Y3587092D01*
X185790D01*
G01X191790D02*
X190990Y3587225D01*
X190290Y3587759D01*
X189690Y3588559D01*
X189290Y3589492D01*
X189090Y3590559D01*
Y3591625D01*
X189290Y3592692D01*
X189690Y3593625D01*
X190290Y3594425D01*
X190990Y3594959D01*
X191790Y3595092D01*
X192590Y3594959D01*
X193290Y3594425D01*
X193890Y3593625D01*
X194290Y3592692D01*
X194490Y3591625D01*
Y3590559D01*
X194290Y3589492D01*
X193890Y3588559D01*
X193290Y3587759D01*
X192590Y3587225D01*
X191790Y3587092D01*
G01X196790Y3595092D02*
X198190Y3587092D01*
X199790Y3595092D01*
X201390Y3587092D01*
X202790Y3595092D01*
G01X213790Y3587092D02*
Y3595092D01*
X216190D01*
X216990Y3594692D01*
X217590Y3593759D01*
X217790Y3592692D01*
X217590Y3591625D01*
X217090Y3590825D01*
X216190Y3590425D01*
X213790D01*
G01X225990Y3594425D02*
X225390Y3594825D01*
X224690Y3595092D01*
X223890D01*
X222990Y3594692D01*
X222290Y3594025D01*
X221790Y3593225D01*
X221390Y3591892D01*
X221290Y3590692D01*
X221490Y3589492D01*
X221790Y3588692D01*
X222390Y3587892D01*
X223090Y3587359D01*
X223790Y3587092D01*
X224490D01*
X225190Y3587359D01*
X225790Y3587759D01*
X226290Y3588292D01*
G01X232590Y3591359D02*
X232990Y3591759D01*
X233290Y3592425D01*
X233490Y3593359D01*
X233290Y3594159D01*
X232890Y3594692D01*
X232190Y3595092D01*
X229490D01*
Y3587092D01*
X232790D01*
X233490Y3587625D01*
X233890Y3588425D01*
X234090Y3589359D01*
X233890Y3590292D01*
X233290Y3591092D01*
X232590Y3591359D01*
X229490D01*
G01X245690Y3588158D02*
X246490Y3587492D01*
X247390Y3587092D01*
X248190D01*
X248990Y3587492D01*
X249590Y3588158D01*
X249890Y3589092D01*
X249690Y3590025D01*
X249190Y3590825D01*
X248290Y3591359D01*
X247090Y3591625D01*
X246390Y3592159D01*
X246090Y3593092D01*
X246290Y3594025D01*
X246790Y3594692D01*
X247490Y3595092D01*
X248190D01*
X248890Y3594825D01*
X249490Y3594159D01*
G01X253690Y3587092D02*
Y3595092D01*
G01X257890D02*
Y3587092D01*
G01Y3591092D02*
X253690D01*
G01X263790Y3587092D02*
X262990Y3587225D01*
X262290Y3587759D01*
X261690Y3588559D01*
X261290Y3589492D01*
X261090Y3590559D01*
Y3591625D01*
X261290Y3592692D01*
X261690Y3593625D01*
X262290Y3594425D01*
X262990Y3594959D01*
X263790Y3595092D01*
X264590Y3594959D01*
X265290Y3594425D01*
X265890Y3593625D01*
X266290Y3592692D01*
X266490Y3591625D01*
Y3590559D01*
X266290Y3589492D01*
X265890Y3588559D01*
X265290Y3587759D01*
X264590Y3587225D01*
X263790Y3587092D01*
G01X269790D02*
Y3595092D01*
X272190D01*
X272990Y3594692D01*
X273590Y3593759D01*
X273790Y3592692D01*
X273590Y3591625D01*
X273090Y3590825D01*
X272190Y3590425D01*
X269790D01*
G01X285790Y3587092D02*
Y3595092D01*
X288190D01*
X288990Y3594692D01*
X289590Y3593759D01*
X289790Y3592692D01*
X289590Y3591625D01*
X289090Y3590825D01*
X288190Y3590425D01*
X285790D01*
G01X293790Y3587092D02*
Y3595092D01*
X296290D01*
X297090Y3594692D01*
X297590Y3594159D01*
X297790Y3593092D01*
X297590Y3592025D01*
X296990Y3591359D01*
X296290Y3590959D01*
X293790D01*
G01X296290D02*
X297790Y3587092D01*
G01X305790D02*
X301790D01*
Y3595092D01*
X305790D01*
G01X304190Y3591225D02*
X301790D01*
G01X309890Y3587092D02*
Y3595092D01*
X313690D01*
G01X312290Y3591225D02*
X309890D01*
G01X321790Y3587092D02*
X317790D01*
Y3595092D01*
X321790D01*
G01X320190Y3591225D02*
X317790D01*
G01X325790Y3587092D02*
Y3595092D01*
X328290D01*
X329090Y3594692D01*
X329590Y3594159D01*
X329790Y3593092D01*
X329590Y3592025D01*
X328990Y3591359D01*
X328290Y3590959D01*
X325790D01*
G01X328290D02*
X329790Y3587092D01*
G01X337790D02*
X333790D01*
Y3595092D01*
X337790D01*
G01X336190Y3591225D02*
X333790D01*
G01X341490Y3587092D02*
Y3595092D01*
X346090Y3587092D01*
Y3595092D01*
G01X353990Y3594425D02*
X353390Y3594825D01*
X352690Y3595092D01*
X351890D01*
X350990Y3594692D01*
X350290Y3594025D01*
X349790Y3593225D01*
X349390Y3591892D01*
X349290Y3590692D01*
X349490Y3589492D01*
X349790Y3588692D01*
X350390Y3587892D01*
X351090Y3587359D01*
X351790Y3587092D01*
X352490D01*
X353190Y3587359D01*
X353790Y3587759D01*
X354290Y3588292D01*
G01X361790Y3587092D02*
X357790D01*
Y3595092D01*
X361790D01*
G01X360190Y3591225D02*
X357790D01*
G01X376590Y3591359D02*
X376990Y3591759D01*
X377290Y3592425D01*
X377490Y3593359D01*
X377290Y3594159D01*
X376890Y3594692D01*
X376190Y3595092D01*
X373490D01*
Y3587092D01*
X376790D01*
X377490Y3587625D01*
X377890Y3588425D01*
X378090Y3589359D01*
X377890Y3590292D01*
X377290Y3591092D01*
X376590Y3591359D01*
X373490D01*
G01X381590Y3595092D02*
Y3589359D01*
X381990Y3588158D01*
X382790Y3587359D01*
X383790Y3587092D01*
X384790Y3587359D01*
X385590Y3588158D01*
X385990Y3589359D01*
Y3595092D01*
G01X391790D02*
Y3587092D01*
G01X389490Y3595092D02*
X394090D01*
G01X409990Y3594425D02*
X409390Y3594825D01*
X408690Y3595092D01*
X407890D01*
X406990Y3594692D01*
X406290Y3594025D01*
X405790Y3593225D01*
X405390Y3591892D01*
X405290Y3590692D01*
X405490Y3589492D01*
X405790Y3588692D01*
X406390Y3587892D01*
X407090Y3587359D01*
X407790Y3587092D01*
X408490D01*
X409190Y3587359D01*
X409790Y3587759D01*
X410290Y3588292D01*
G01X415790Y3587092D02*
X414990Y3587225D01*
X414290Y3587759D01*
X413690Y3588559D01*
X413290Y3589492D01*
X413090Y3590559D01*
Y3591625D01*
X413290Y3592692D01*
X413690Y3593625D01*
X414290Y3594425D01*
X414990Y3594959D01*
X415790Y3595092D01*
X416590Y3594959D01*
X417290Y3594425D01*
X417890Y3593625D01*
X418290Y3592692D01*
X418490Y3591625D01*
Y3590559D01*
X418290Y3589492D01*
X417890Y3588559D01*
X417290Y3587759D01*
X416590Y3587225D01*
X415790Y3587092D01*
G01X421590Y3595092D02*
Y3589359D01*
X421990Y3588158D01*
X422790Y3587359D01*
X423790Y3587092D01*
X424790Y3587359D01*
X425590Y3588158D01*
X425990Y3589359D01*
Y3595092D01*
G01X429790Y3587092D02*
Y3595092D01*
X432190D01*
X432990Y3594692D01*
X433590Y3593759D01*
X433790Y3592692D01*
X433590Y3591625D01*
X433090Y3590825D01*
X432190Y3590425D01*
X429790D01*
G01X439790Y3587092D02*
X438990Y3587225D01*
X438290Y3587759D01*
X437690Y3588559D01*
X437290Y3589492D01*
X437090Y3590559D01*
Y3591625D01*
X437290Y3592692D01*
X437690Y3593625D01*
X438290Y3594425D01*
X438990Y3594959D01*
X439790Y3595092D01*
X440590Y3594959D01*
X441290Y3594425D01*
X441890Y3593625D01*
X442290Y3592692D01*
X442490Y3591625D01*
Y3590559D01*
X442290Y3589492D01*
X441890Y3588559D01*
X441290Y3587759D01*
X440590Y3587225D01*
X439790Y3587092D01*
G01X445490D02*
Y3595092D01*
X450090Y3587092D01*
Y3595092D01*
G01X453990Y3586825D02*
X457590Y3595092D01*
G01X461890Y3587092D02*
Y3595092D01*
X465690D01*
G01X464290Y3591225D02*
X461890D01*
G01X470590Y3595092D02*
X472990D01*
G01X471790D02*
Y3587092D01*
G01X470590D02*
X472990D01*
G01X477590D02*
Y3595092D01*
X479590D01*
X480390Y3594692D01*
X480990Y3594159D01*
X481490Y3593359D01*
X481890Y3592425D01*
X481990Y3591092D01*
X481890Y3589759D01*
X481490Y3588825D01*
X480990Y3588025D01*
X480390Y3587492D01*
X479590Y3587092D01*
X477590D01*
G01X485590Y3595092D02*
Y3589359D01*
X485990Y3588158D01*
X486790Y3587359D01*
X487790Y3587092D01*
X488790Y3587359D01*
X489590Y3588158D01*
X489990Y3589359D01*
Y3595092D01*
G01X497990Y3594425D02*
X497390Y3594825D01*
X496690Y3595092D01*
X495890D01*
X494990Y3594692D01*
X494290Y3594025D01*
X493790Y3593225D01*
X493390Y3591892D01*
X493290Y3590692D01*
X493490Y3589492D01*
X493790Y3588692D01*
X494390Y3587892D01*
X495090Y3587359D01*
X495790Y3587092D01*
X496490D01*
X497190Y3587359D01*
X497790Y3587759D01*
X498290Y3588292D01*
G01X502590Y3595092D02*
X504990D01*
G01X503790D02*
Y3587092D01*
G01X502590D02*
X504990D01*
G01X509290D02*
X511790Y3595092D01*
X514290Y3587092D01*
G01X513390Y3589892D02*
X510190D01*
G01X517790Y3595092D02*
Y3587092D01*
X521790D01*
G01X533190D02*
Y3595092D01*
X535790Y3588425D01*
X538390Y3595092D01*
Y3587092D01*
G01X541290D02*
X543790Y3595092D01*
X546290Y3587092D01*
G01X545390Y3589892D02*
X542190D01*
G01X549790Y3587092D02*
Y3595092D01*
X552290D01*
X553090Y3594692D01*
X553590Y3594159D01*
X553790Y3593092D01*
X553590Y3592025D01*
X552990Y3591359D01*
X552290Y3590959D01*
X549790D01*
G01X552290D02*
X553790Y3587092D01*
G01X557590D02*
Y3595092D01*
G01X561390D02*
X557590Y3590158D01*
G01X561990Y3587092D02*
X559290Y3592425D01*
G01X565990Y3586825D02*
X569590Y3595092D01*
G01X575790D02*
Y3587092D01*
G01X573490Y3595092D02*
X578090D01*
G01X583790Y3587092D02*
X582990Y3587225D01*
X582290Y3587759D01*
X581690Y3588559D01*
X581290Y3589492D01*
X581090Y3590559D01*
Y3591625D01*
X581290Y3592692D01*
X581690Y3593625D01*
X582290Y3594425D01*
X582990Y3594959D01*
X583790Y3595092D01*
X584590Y3594959D01*
X585290Y3594425D01*
X585890Y3593625D01*
X586290Y3592692D01*
X586490Y3591625D01*
Y3590559D01*
X586290Y3589492D01*
X585890Y3588559D01*
X585290Y3587759D01*
X584590Y3587225D01*
X583790Y3587092D01*
G01X591790D02*
X590990Y3587225D01*
X590290Y3587759D01*
X589690Y3588559D01*
X589290Y3589492D01*
X589090Y3590559D01*
Y3591625D01*
X589290Y3592692D01*
X589690Y3593625D01*
X590290Y3594425D01*
X590990Y3594959D01*
X591790Y3595092D01*
X592590Y3594959D01*
X593290Y3594425D01*
X593890Y3593625D01*
X594290Y3592692D01*
X594490Y3591625D01*
Y3590559D01*
X594290Y3589492D01*
X593890Y3588559D01*
X593290Y3587759D01*
X592590Y3587225D01*
X591790Y3587092D01*
G01X597790Y3595092D02*
Y3587092D01*
X601790D01*
G01X606590Y3595092D02*
X608990D01*
G01X607790D02*
Y3587092D01*
G01X606590D02*
X608990D01*
G01X613490D02*
Y3595092D01*
X618090Y3587092D01*
Y3595092D01*
G01X624390Y3591092D02*
X626390D01*
Y3588692D01*
X625790Y3587892D01*
X625090Y3587359D01*
X624090Y3587092D01*
X623090Y3587359D01*
X622390Y3587892D01*
X621790Y3588692D01*
X621390Y3589625D01*
X621190Y3590692D01*
Y3591625D01*
X621390Y3592425D01*
X621790Y3593359D01*
X622390Y3594159D01*
X622990Y3594692D01*
X623790Y3595092D01*
X624490D01*
X625290Y3594825D01*
X625890Y3594292D01*
G01X637690Y3587092D02*
Y3595092D01*
G01X641890D02*
Y3587092D01*
G01Y3591092D02*
X637690D01*
G01X647790Y3587092D02*
X646990Y3587225D01*
X646290Y3587759D01*
X645690Y3588559D01*
X645290Y3589492D01*
X645090Y3590559D01*
Y3591625D01*
X645290Y3592692D01*
X645690Y3593625D01*
X646290Y3594425D01*
X646990Y3594959D01*
X647790Y3595092D01*
X648590Y3594959D01*
X649290Y3594425D01*
X649890Y3593625D01*
X650290Y3592692D01*
X650490Y3591625D01*
Y3590559D01*
X650290Y3589492D01*
X649890Y3588559D01*
X649290Y3587759D01*
X648590Y3587225D01*
X647790Y3587092D01*
G01X653790Y3595092D02*
Y3587092D01*
X657790D01*
G01X665790D02*
X661790D01*
Y3595092D01*
X665790D01*
G01X664190Y3591225D02*
X661790D01*
G01X677690Y3588158D02*
X678490Y3587492D01*
X679390Y3587092D01*
X680190D01*
X680990Y3587492D01*
X681590Y3588158D01*
X681890Y3589092D01*
X681690Y3590025D01*
X681190Y3590825D01*
X680290Y3591359D01*
X679090Y3591625D01*
X678390Y3592159D01*
X678090Y3593092D01*
X678290Y3594025D01*
X678790Y3594692D01*
X679490Y3595092D01*
X680190D01*
X680890Y3594825D01*
X681490Y3594159D01*
G01X685790Y3587092D02*
Y3595092D01*
X688190D01*
X688990Y3594692D01*
X689590Y3593759D01*
X689790Y3592692D01*
X689590Y3591625D01*
X689090Y3590825D01*
X688190Y3590425D01*
X685790D01*
G01X693290Y3587092D02*
X695790Y3595092D01*
X698290Y3587092D01*
G01X697390Y3589892D02*
X694190D01*
G01X705990Y3594425D02*
X705390Y3594825D01*
X704690Y3595092D01*
X703890D01*
X702990Y3594692D01*
X702290Y3594025D01*
X701790Y3593225D01*
X701390Y3591892D01*
X701290Y3590692D01*
X701490Y3589492D01*
X701790Y3588692D01*
X702390Y3587892D01*
X703090Y3587359D01*
X703790Y3587092D01*
X704490D01*
X705190Y3587359D01*
X705790Y3587759D01*
X706290Y3588292D01*
G01X710590Y3595092D02*
X712990D01*
G01X711790D02*
Y3587092D01*
G01X710590D02*
X712990D01*
G01X717490D02*
Y3595092D01*
X722090Y3587092D01*
Y3595092D01*
G01X728390Y3591092D02*
X730390D01*
Y3588692D01*
X729790Y3587892D01*
X729090Y3587359D01*
X728090Y3587092D01*
X727090Y3587359D01*
X726390Y3587892D01*
X725790Y3588692D01*
X725390Y3589625D01*
X725190Y3590692D01*
Y3591625D01*
X725390Y3592425D01*
X725790Y3593359D01*
X726390Y3594159D01*
X726990Y3594692D01*
X727790Y3595092D01*
X728490D01*
X729290Y3594825D01*
X729890Y3594292D01*
G01X741290Y3587092D02*
X743790Y3595092D01*
X746290Y3587092D01*
G01X745390Y3589892D02*
X742190D01*
G01X749790Y3595092D02*
Y3587092D01*
X753790D01*
G01X757790Y3595092D02*
Y3587092D01*
X761790D01*
G01X773590Y3595092D02*
Y3589359D01*
X773990Y3588158D01*
X774790Y3587359D01*
X775790Y3587092D01*
X776790Y3587359D01*
X777590Y3588158D01*
X777990Y3589359D01*
Y3595092D01*
G01X781690Y3588158D02*
X782490Y3587492D01*
X783390Y3587092D01*
X784190D01*
X784990Y3587492D01*
X785590Y3588158D01*
X785890Y3589092D01*
X785690Y3590025D01*
X785190Y3590825D01*
X784290Y3591359D01*
X783090Y3591625D01*
X782390Y3592159D01*
X782090Y3593092D01*
X782290Y3594025D01*
X782790Y3594692D01*
X783490Y3595092D01*
X784190D01*
X784890Y3594825D01*
X785490Y3594159D01*
G01X790590Y3595092D02*
X792990D01*
G01X791790D02*
Y3587092D01*
G01X790590D02*
X792990D01*
G01X797490D02*
Y3595092D01*
X802090Y3587092D01*
Y3595092D01*
G01X808390Y3591092D02*
X810390D01*
Y3588692D01*
X809790Y3587892D01*
X809090Y3587359D01*
X808090Y3587092D01*
X807090Y3587359D01*
X806390Y3587892D01*
X805790Y3588692D01*
X805390Y3589625D01*
X805190Y3590692D01*
Y3591625D01*
X805390Y3592425D01*
X805790Y3593359D01*
X806390Y3594159D01*
X806990Y3594692D01*
X807790Y3595092D01*
X808490D01*
X809290Y3594825D01*
X809890Y3594292D01*
G01X821590Y3588292D02*
X822190Y3587625D01*
X822890Y3587225D01*
X823790Y3587092D01*
X824690Y3587359D01*
X825390Y3587892D01*
X825890Y3588825D01*
X825990Y3589892D01*
X825790Y3590959D01*
X825290Y3591625D01*
X824590Y3592159D01*
X823890Y3592292D01*
X823190Y3592159D01*
X822290Y3591625D01*
X822590Y3595092D01*
X825290D01*
G01X831790D02*
X830990Y3594825D01*
X830390Y3594159D01*
X829990Y3593359D01*
X829690Y3592292D01*
X829590Y3591092D01*
X829690Y3589892D01*
X829990Y3588825D01*
X830390Y3588025D01*
X830990Y3587359D01*
X831790Y3587092D01*
X832590Y3587359D01*
X833190Y3588025D01*
X833590Y3588825D01*
X833890Y3589892D01*
X833990Y3591092D01*
X833890Y3592292D01*
X833590Y3593359D01*
X833190Y3594159D01*
X832590Y3594825D01*
X831790Y3595092D01*
G01X837190Y3587092D02*
Y3595092D01*
X839790Y3588425D01*
X842390Y3595092D01*
Y3587092D01*
G01X846590Y3595092D02*
X848990D01*
G01X847790D02*
Y3587092D01*
G01X846590D02*
X848990D01*
G01X853790Y3595092D02*
Y3587092D01*
X857790D01*
G01X861690Y3588158D02*
X862490Y3587492D01*
X863390Y3587092D01*
X864190D01*
X864990Y3587492D01*
X865590Y3588158D01*
X865890Y3589092D01*
X865690Y3590025D01*
X865190Y3590825D01*
X864290Y3591359D01*
X863090Y3591625D01*
X862390Y3592159D01*
X862090Y3593092D01*
X862290Y3594025D01*
X862790Y3594692D01*
X863490Y3595092D01*
X864190D01*
X864890Y3594825D01*
X865490Y3594159D01*
G01X871790Y3586825D02*
X871590Y3586959D01*
Y3587225D01*
X871790Y3587359D01*
X871990Y3587225D01*
Y3586959D01*
X871790Y3586825D01*
G01X-50110Y3605425D02*
X-49410Y3606359D01*
X-48810Y3606892D01*
X-48010Y3607159D01*
X-47310Y3606892D01*
X-46810Y3606359D01*
X-46410Y3605559D01*
X-46310Y3604625D01*
X-46410Y3603825D01*
X-46810Y3603025D01*
X-47410Y3602359D01*
X-48110Y3602092D01*
X-48910Y3602359D01*
X-49610Y3603158D01*
X-50010Y3604359D01*
X-50110Y3605692D01*
X-49910Y3607425D01*
X-49610Y3608359D01*
X-49110Y3609292D01*
X-48410Y3609959D01*
X-47710Y3610092D01*
X-47010Y3609825D01*
X-46510Y3609159D01*
G01X-40210Y3601825D02*
X-40410Y3601959D01*
Y3602225D01*
X-40210Y3602359D01*
X-40010Y3602225D01*
Y3601959D01*
X-40210Y3601825D01*
G01X-32210Y3602092D02*
Y3610092D01*
X-33410Y3608492D01*
G01Y3602092D02*
X-31010D01*
G01X-17410Y3610092D02*
X-15010D01*
G01X-16210D02*
Y3602092D01*
G01X-17410D02*
X-15010D01*
G01X-10510D02*
Y3610092D01*
X-5910Y3602092D01*
Y3610092D01*
G01X-2310Y3603158D02*
X-1510Y3602492D01*
X-610Y3602092D01*
X190D01*
X990Y3602492D01*
X1590Y3603158D01*
X1890Y3604092D01*
X1690Y3605025D01*
X1190Y3605825D01*
X290Y3606359D01*
X-910Y3606625D01*
X-1610Y3607159D01*
X-1910Y3608092D01*
X-1710Y3609025D01*
X-1210Y3609692D01*
X-510Y3610092D01*
X190D01*
X890Y3609825D01*
X1490Y3609159D01*
G01X6590Y3610092D02*
X8990D01*
G01X7790D02*
Y3602092D01*
G01X6590D02*
X8990D01*
G01X13590D02*
Y3610092D01*
X15590D01*
X16390Y3609692D01*
X16990Y3609159D01*
X17490Y3608359D01*
X17890Y3607425D01*
X17990Y3606092D01*
X17890Y3604759D01*
X17490Y3603825D01*
X16990Y3603025D01*
X16390Y3602492D01*
X15590Y3602092D01*
X13590D01*
G01X25790D02*
X21790D01*
Y3610092D01*
X25790D01*
G01X24190Y3606225D02*
X21790D01*
G01X40590Y3606359D02*
X40990Y3606759D01*
X41290Y3607425D01*
X41490Y3608359D01*
X41290Y3609159D01*
X40890Y3609692D01*
X40190Y3610092D01*
X37490D01*
Y3602092D01*
X40790D01*
X41490Y3602625D01*
X41890Y3603425D01*
X42090Y3604359D01*
X41890Y3605292D01*
X41290Y3606092D01*
X40590Y3606359D01*
X37490D01*
G01X47790Y3602092D02*
X46990Y3602225D01*
X46290Y3602759D01*
X45690Y3603559D01*
X45290Y3604492D01*
X45090Y3605559D01*
Y3606625D01*
X45290Y3607692D01*
X45690Y3608625D01*
X46290Y3609425D01*
X46990Y3609959D01*
X47790Y3610092D01*
X48590Y3609959D01*
X49290Y3609425D01*
X49890Y3608625D01*
X50290Y3607692D01*
X50490Y3606625D01*
Y3605559D01*
X50290Y3604492D01*
X49890Y3603559D01*
X49290Y3602759D01*
X48590Y3602225D01*
X47790Y3602092D01*
G01X53290D02*
X55790Y3610092D01*
X58290Y3602092D01*
G01X57390Y3604892D02*
X54190D01*
G01X61790Y3602092D02*
Y3610092D01*
X64290D01*
X65090Y3609692D01*
X65590Y3609159D01*
X65790Y3608092D01*
X65590Y3607025D01*
X64990Y3606359D01*
X64290Y3605959D01*
X61790D01*
G01X64290D02*
X65790Y3602092D01*
G01X69590D02*
Y3610092D01*
X71590D01*
X72390Y3609692D01*
X72990Y3609159D01*
X73490Y3608359D01*
X73890Y3607425D01*
X73990Y3606092D01*
X73890Y3604759D01*
X73490Y3603825D01*
X72990Y3603025D01*
X72390Y3602492D01*
X71590Y3602092D01*
X69590D01*
G01X87790D02*
X86990Y3602225D01*
X86290Y3602759D01*
X85690Y3603559D01*
X85290Y3604492D01*
X85090Y3605559D01*
Y3606625D01*
X85290Y3607692D01*
X85690Y3608625D01*
X86290Y3609425D01*
X86990Y3609959D01*
X87790Y3610092D01*
X88590Y3609959D01*
X89290Y3609425D01*
X89890Y3608625D01*
X90290Y3607692D01*
X90490Y3606625D01*
Y3605559D01*
X90290Y3604492D01*
X89890Y3603559D01*
X89290Y3602759D01*
X88590Y3602225D01*
X87790Y3602092D01*
G01X93590Y3610092D02*
Y3604359D01*
X93990Y3603158D01*
X94790Y3602359D01*
X95790Y3602092D01*
X96790Y3602359D01*
X97590Y3603158D01*
X97990Y3604359D01*
Y3610092D01*
G01X103790D02*
Y3602092D01*
G01X101490Y3610092D02*
X106090D01*
G01X109790D02*
Y3602092D01*
X113790D01*
G01X118590Y3610092D02*
X120990D01*
G01X119790D02*
Y3602092D01*
G01X118590D02*
X120990D01*
G01X125490D02*
Y3610092D01*
X130090Y3602092D01*
Y3610092D01*
G01X137790Y3602092D02*
X133790D01*
Y3610092D01*
X137790D01*
G01X136190Y3606225D02*
X133790D01*
G01X149590Y3602092D02*
Y3610092D01*
X151590D01*
X152390Y3609692D01*
X152990Y3609159D01*
X153490Y3608359D01*
X153890Y3607425D01*
X153990Y3606092D01*
X153890Y3604759D01*
X153490Y3603825D01*
X152990Y3603025D01*
X152390Y3602492D01*
X151590Y3602092D01*
X149590D01*
G01X157590Y3610092D02*
Y3604359D01*
X157990Y3603158D01*
X158790Y3602359D01*
X159790Y3602092D01*
X160790Y3602359D01*
X161590Y3603158D01*
X161990Y3604359D01*
Y3610092D01*
G01X165190Y3602092D02*
Y3610092D01*
X167790Y3603425D01*
X170390Y3610092D01*
Y3602092D01*
G01X173190D02*
Y3610092D01*
X175790Y3603425D01*
X178390Y3610092D01*
Y3602092D01*
G01X183790D02*
Y3605692D01*
X181790Y3610092D01*
G01X185790D02*
X183790Y3605692D01*
G01X197790Y3602092D02*
Y3610092D01*
X200190D01*
X200990Y3609692D01*
X201590Y3608759D01*
X201790Y3607692D01*
X201590Y3606625D01*
X201090Y3605825D01*
X200190Y3605425D01*
X197790D01*
G01X205290Y3602092D02*
X207790Y3610092D01*
X210290Y3602092D01*
G01X209390Y3604892D02*
X206190D01*
G01X213590Y3602092D02*
Y3610092D01*
X215590D01*
X216390Y3609692D01*
X216990Y3609159D01*
X217490Y3608359D01*
X217890Y3607425D01*
X217990Y3606092D01*
X217890Y3604759D01*
X217490Y3603825D01*
X216990Y3603025D01*
X216390Y3602492D01*
X215590Y3602092D01*
X213590D01*
G01X229590D02*
Y3610092D01*
X231590D01*
X232390Y3609692D01*
X232990Y3609159D01*
X233490Y3608359D01*
X233890Y3607425D01*
X233990Y3606092D01*
X233890Y3604759D01*
X233490Y3603825D01*
X232990Y3603025D01*
X232390Y3602492D01*
X231590Y3602092D01*
X229590D01*
G01X241790D02*
X237790D01*
Y3610092D01*
X241790D01*
G01X240190Y3606225D02*
X237790D01*
G01X245690Y3603158D02*
X246490Y3602492D01*
X247390Y3602092D01*
X248190D01*
X248990Y3602492D01*
X249590Y3603158D01*
X249890Y3604092D01*
X249690Y3605025D01*
X249190Y3605825D01*
X248290Y3606359D01*
X247090Y3606625D01*
X246390Y3607159D01*
X246090Y3608092D01*
X246290Y3609025D01*
X246790Y3609692D01*
X247490Y3610092D01*
X248190D01*
X248890Y3609825D01*
X249490Y3609159D01*
G01X254590Y3610092D02*
X256990D01*
G01X255790D02*
Y3602092D01*
G01X254590D02*
X256990D01*
G01X264390Y3606092D02*
X266390D01*
Y3603692D01*
X265790Y3602892D01*
X265090Y3602359D01*
X264090Y3602092D01*
X263090Y3602359D01*
X262390Y3602892D01*
X261790Y3603692D01*
X261390Y3604625D01*
X261190Y3605692D01*
Y3606625D01*
X261390Y3607425D01*
X261790Y3608359D01*
X262390Y3609159D01*
X262990Y3609692D01*
X263790Y3610092D01*
X264490D01*
X265290Y3609825D01*
X265890Y3609292D01*
G01X269490Y3602092D02*
Y3610092D01*
X274090Y3602092D01*
Y3610092D01*
G01X286590D02*
X288990D01*
G01X287790D02*
Y3602092D01*
G01X286590D02*
X288990D01*
G01X293490D02*
Y3610092D01*
X298090Y3602092D01*
Y3610092D01*
G01X309690Y3603158D02*
X310490Y3602492D01*
X311390Y3602092D01*
X312190D01*
X312990Y3602492D01*
X313590Y3603158D01*
X313890Y3604092D01*
X313690Y3605025D01*
X313190Y3605825D01*
X312290Y3606359D01*
X311090Y3606625D01*
X310390Y3607159D01*
X310090Y3608092D01*
X310290Y3609025D01*
X310790Y3609692D01*
X311490Y3610092D01*
X312190D01*
X312890Y3609825D01*
X313490Y3609159D01*
G01X319790Y3602092D02*
X318990Y3602225D01*
X318290Y3602759D01*
X317690Y3603559D01*
X317290Y3604492D01*
X317090Y3605559D01*
Y3606625D01*
X317290Y3607692D01*
X317690Y3608625D01*
X318290Y3609425D01*
X318990Y3609959D01*
X319790Y3610092D01*
X320590Y3609959D01*
X321290Y3609425D01*
X321890Y3608625D01*
X322290Y3607692D01*
X322490Y3606625D01*
Y3605559D01*
X322290Y3604492D01*
X321890Y3603559D01*
X321290Y3602759D01*
X320590Y3602225D01*
X319790Y3602092D01*
G01X320590Y3604225D02*
X321790Y3602092D01*
G01X325590Y3610092D02*
Y3604359D01*
X325990Y3603158D01*
X326790Y3602359D01*
X327790Y3602092D01*
X328790Y3602359D01*
X329590Y3603158D01*
X329990Y3604359D01*
Y3610092D01*
G01X333290Y3602092D02*
X335790Y3610092D01*
X338290Y3602092D01*
G01X337390Y3604892D02*
X334190D01*
G01X341790Y3602092D02*
Y3610092D01*
X344290D01*
X345090Y3609692D01*
X345590Y3609159D01*
X345790Y3608092D01*
X345590Y3607025D01*
X344990Y3606359D01*
X344290Y3605959D01*
X341790D01*
G01X344290D02*
X345790Y3602092D01*
G01X353790D02*
X349790D01*
Y3610092D01*
X353790D01*
G01X352190Y3606225D02*
X349790D01*
G01X365690Y3603158D02*
X366490Y3602492D01*
X367390Y3602092D01*
X368190D01*
X368990Y3602492D01*
X369590Y3603158D01*
X369890Y3604092D01*
X369690Y3605025D01*
X369190Y3605825D01*
X368290Y3606359D01*
X367090Y3606625D01*
X366390Y3607159D01*
X366090Y3608092D01*
X366290Y3609025D01*
X366790Y3609692D01*
X367490Y3610092D01*
X368190D01*
X368890Y3609825D01*
X369490Y3609159D01*
G01X373690Y3602092D02*
Y3610092D01*
G01X377890D02*
Y3602092D01*
G01Y3606092D02*
X373690D01*
G01X381290Y3602092D02*
X383790Y3610092D01*
X386290Y3602092D01*
G01X385390Y3604892D02*
X382190D01*
G01X389790Y3602092D02*
Y3610092D01*
X392190D01*
X392990Y3609692D01*
X393590Y3608759D01*
X393790Y3607692D01*
X393590Y3606625D01*
X393090Y3605825D01*
X392190Y3605425D01*
X389790D01*
G01X401790Y3602092D02*
X397790D01*
Y3610092D01*
X401790D01*
G01X400190Y3606225D02*
X397790D01*
G01X406490Y3604759D02*
X409090D01*
G01X421690Y3603158D02*
X422490Y3602492D01*
X423390Y3602092D01*
X424190D01*
X424990Y3602492D01*
X425590Y3603158D01*
X425890Y3604092D01*
X425690Y3605025D01*
X425190Y3605825D01*
X424290Y3606359D01*
X423090Y3606625D01*
X422390Y3607159D01*
X422090Y3608092D01*
X422290Y3609025D01*
X422790Y3609692D01*
X423490Y3610092D01*
X424190D01*
X424890Y3609825D01*
X425490Y3609159D01*
G01X429690Y3602092D02*
Y3610092D01*
G01X433890D02*
Y3602092D01*
G01Y3606092D02*
X429690D01*
G01X437290Y3602092D02*
X439790Y3610092D01*
X442290Y3602092D01*
G01X441390Y3604892D02*
X438190D01*
G01X445790Y3602092D02*
Y3610092D01*
X448190D01*
X448990Y3609692D01*
X449590Y3608759D01*
X449790Y3607692D01*
X449590Y3606625D01*
X449090Y3605825D01*
X448190Y3605425D01*
X445790D01*
G01X457790Y3602092D02*
X453790D01*
Y3610092D01*
X457790D01*
G01X456190Y3606225D02*
X453790D01*
G01X469690Y3603158D02*
X470490Y3602492D01*
X471390Y3602092D01*
X472190D01*
X472990Y3602492D01*
X473590Y3603158D01*
X473890Y3604092D01*
X473690Y3605025D01*
X473190Y3605825D01*
X472290Y3606359D01*
X471090Y3606625D01*
X470390Y3607159D01*
X470090Y3608092D01*
X470290Y3609025D01*
X470790Y3609692D01*
X471490Y3610092D01*
X472190D01*
X472890Y3609825D01*
X473490Y3609159D01*
G01X478590Y3610092D02*
X480990D01*
G01X479790D02*
Y3602092D01*
G01X478590D02*
X480990D01*
G01X485890Y3610092D02*
X489690D01*
X485890Y3602092D01*
X489690D01*
G01X497790D02*
X493790D01*
Y3610092D01*
X497790D01*
G01X496190Y3606225D02*
X493790D01*
G01X509590Y3603292D02*
X510190Y3602625D01*
X510890Y3602225D01*
X511790Y3602092D01*
X512690Y3602359D01*
X513390Y3602892D01*
X513890Y3603825D01*
X513990Y3604892D01*
X513790Y3605959D01*
X513290Y3606625D01*
X512590Y3607159D01*
X511890Y3607292D01*
X511190Y3607159D01*
X510290Y3606625D01*
X510590Y3610092D01*
X513290D01*
G01X519790D02*
X518990Y3609825D01*
X518390Y3609159D01*
X517990Y3608359D01*
X517690Y3607292D01*
X517590Y3606092D01*
X517690Y3604892D01*
X517990Y3603825D01*
X518390Y3603025D01*
X518990Y3602359D01*
X519790Y3602092D01*
X520590Y3602359D01*
X521190Y3603025D01*
X521590Y3603825D01*
X521890Y3604892D01*
X521990Y3606092D01*
X521890Y3607292D01*
X521590Y3608359D01*
X521190Y3609159D01*
X520590Y3609825D01*
X519790Y3610092D01*
G01X525190Y3602092D02*
Y3610092D01*
X527790Y3603425D01*
X530390Y3610092D01*
Y3602092D01*
G01X534590Y3610092D02*
X536990D01*
G01X535790D02*
Y3602092D01*
G01X534590D02*
X536990D01*
G01X541790Y3610092D02*
Y3602092D01*
X545790D01*
G01X549690Y3603158D02*
X550490Y3602492D01*
X551390Y3602092D01*
X552190D01*
X552990Y3602492D01*
X553590Y3603158D01*
X553890Y3604092D01*
X553690Y3605025D01*
X553190Y3605825D01*
X552290Y3606359D01*
X551090Y3606625D01*
X550390Y3607159D01*
X550090Y3608092D01*
X550290Y3609025D01*
X550790Y3609692D01*
X551490Y3610092D01*
X552190D01*
X552890Y3609825D01*
X553490Y3609159D01*
G01X559590Y3600625D02*
X559990Y3602359D01*
G01X573790Y3602092D02*
Y3610092D01*
X576190D01*
X576990Y3609692D01*
X577590Y3608759D01*
X577790Y3607692D01*
X577590Y3606625D01*
X577090Y3605825D01*
X576190Y3605425D01*
X573790D01*
G01X582590Y3610092D02*
X584990D01*
G01X583790D02*
Y3602092D01*
G01X582590D02*
X584990D01*
G01X591790Y3610092D02*
Y3602092D01*
G01X589490Y3610092D02*
X594090D01*
G01X601990Y3609425D02*
X601390Y3609825D01*
X600690Y3610092D01*
X599890D01*
X598990Y3609692D01*
X598290Y3609025D01*
X597790Y3608225D01*
X597390Y3606892D01*
X597290Y3605692D01*
X597490Y3604492D01*
X597790Y3603692D01*
X598390Y3602892D01*
X599090Y3602359D01*
X599790Y3602092D01*
X600490D01*
X601190Y3602359D01*
X601790Y3602759D01*
X602290Y3603292D01*
G01X605690Y3602092D02*
Y3610092D01*
G01X609890D02*
Y3602092D01*
G01Y3606092D02*
X605690D01*
G01X623290Y3599425D02*
X622290Y3600759D01*
X621790Y3602092D01*
Y3607425D01*
X622290Y3608759D01*
X623290Y3610092D01*
G01X629690Y3603158D02*
X630490Y3602492D01*
X631390Y3602092D01*
X632190D01*
X632990Y3602492D01*
X633590Y3603158D01*
X633890Y3604092D01*
X633690Y3605025D01*
X633190Y3605825D01*
X632290Y3606359D01*
X631090Y3606625D01*
X630390Y3607159D01*
X630090Y3608092D01*
X630290Y3609025D01*
X630790Y3609692D01*
X631490Y3610092D01*
X632190D01*
X632890Y3609825D01*
X633490Y3609159D01*
G01X637690Y3602092D02*
Y3610092D01*
G01X641890D02*
Y3602092D01*
G01Y3606092D02*
X637690D01*
G01X645290Y3602092D02*
X647790Y3610092D01*
X650290Y3602092D01*
G01X649390Y3604892D02*
X646190D01*
G01X653790Y3602092D02*
Y3610092D01*
X656190D01*
X656990Y3609692D01*
X657590Y3608759D01*
X657790Y3607692D01*
X657590Y3606625D01*
X657090Y3605825D01*
X656190Y3605425D01*
X653790D01*
G01X665790Y3602092D02*
X661790D01*
Y3610092D01*
X665790D01*
G01X664190Y3606225D02*
X661790D01*
G01X681990Y3609425D02*
X681390Y3609825D01*
X680690Y3610092D01*
X679890D01*
X678990Y3609692D01*
X678290Y3609025D01*
X677790Y3608225D01*
X677390Y3606892D01*
X677290Y3605692D01*
X677490Y3604492D01*
X677790Y3603692D01*
X678390Y3602892D01*
X679090Y3602359D01*
X679790Y3602092D01*
X680490D01*
X681190Y3602359D01*
X681790Y3602759D01*
X682290Y3603292D01*
G01X689790Y3602092D02*
X685790D01*
Y3610092D01*
X689790D01*
G01X688190Y3606225D02*
X685790D01*
G01X693490Y3602092D02*
Y3610092D01*
X698090Y3602092D01*
Y3610092D01*
G01X703790D02*
Y3602092D01*
G01X701490Y3610092D02*
X706090D01*
G01X713790Y3602092D02*
X709790D01*
Y3610092D01*
X713790D01*
G01X712190Y3606225D02*
X709790D01*
G01X717790Y3602092D02*
Y3610092D01*
X720290D01*
X721090Y3609692D01*
X721590Y3609159D01*
X721790Y3608092D01*
X721590Y3607025D01*
X720990Y3606359D01*
X720290Y3605959D01*
X717790D01*
G01X720290D02*
X721790Y3602092D01*
G01X735790Y3610092D02*
Y3602092D01*
G01X733490Y3610092D02*
X738090D01*
G01X743790Y3602092D02*
X742990Y3602225D01*
X742290Y3602759D01*
X741690Y3603559D01*
X741290Y3604492D01*
X741090Y3605559D01*
Y3606625D01*
X741290Y3607692D01*
X741690Y3608625D01*
X742290Y3609425D01*
X742990Y3609959D01*
X743790Y3610092D01*
X744590Y3609959D01*
X745290Y3609425D01*
X745890Y3608625D01*
X746290Y3607692D01*
X746490Y3606625D01*
Y3605559D01*
X746290Y3604492D01*
X745890Y3603559D01*
X745290Y3602759D01*
X744590Y3602225D01*
X743790Y3602092D01*
G01X761990Y3609425D02*
X761390Y3609825D01*
X760690Y3610092D01*
X759890D01*
X758990Y3609692D01*
X758290Y3609025D01*
X757790Y3608225D01*
X757390Y3606892D01*
X757290Y3605692D01*
X757490Y3604492D01*
X757790Y3603692D01*
X758390Y3602892D01*
X759090Y3602359D01*
X759790Y3602092D01*
X760490D01*
X761190Y3602359D01*
X761790Y3602759D01*
X762290Y3603292D01*
G01X769790Y3602092D02*
X765790D01*
Y3610092D01*
X769790D01*
G01X768190Y3606225D02*
X765790D01*
G01X773490Y3602092D02*
Y3610092D01*
X778090Y3602092D01*
Y3610092D01*
G01X783790D02*
Y3602092D01*
G01X781490Y3610092D02*
X786090D01*
G01X793790Y3602092D02*
X789790D01*
Y3610092D01*
X793790D01*
G01X792190Y3606225D02*
X789790D01*
G01X797790Y3602092D02*
Y3610092D01*
X800290D01*
X801090Y3609692D01*
X801590Y3609159D01*
X801790Y3608092D01*
X801590Y3607025D01*
X800990Y3606359D01*
X800290Y3605959D01*
X797790D01*
G01X800290D02*
X801790Y3602092D01*
G01X808290Y3599425D02*
X809290Y3600759D01*
X809790Y3602092D01*
Y3607425D01*
X809290Y3608759D01*
X808290Y3610092D01*
G01X815790Y3601825D02*
X815590Y3601959D01*
Y3602225D01*
X815790Y3602359D01*
X815990Y3602225D01*
Y3601959D01*
X815790Y3601825D01*
G01Y3605425D02*
X815590Y3605559D01*
Y3605825D01*
X815790Y3605959D01*
X815990Y3605825D01*
Y3605559D01*
X815790Y3605425D01*
G01X831790Y3602092D02*
Y3610092D01*
X830590Y3608492D01*
G01Y3602092D02*
X832990D01*
G01X839790Y3610092D02*
X838990Y3609825D01*
X838390Y3609159D01*
X837990Y3608359D01*
X837690Y3607292D01*
X837590Y3606092D01*
X837690Y3604892D01*
X837990Y3603825D01*
X838390Y3603025D01*
X838990Y3602359D01*
X839790Y3602092D01*
X840590Y3602359D01*
X841190Y3603025D01*
X841590Y3603825D01*
X841890Y3604892D01*
X841990Y3606092D01*
X841890Y3607292D01*
X841590Y3608359D01*
X841190Y3609159D01*
X840590Y3609825D01*
X839790Y3610092D01*
G01X847790D02*
X846990Y3609825D01*
X846390Y3609159D01*
X845990Y3608359D01*
X845690Y3607292D01*
X845590Y3606092D01*
X845690Y3604892D01*
X845990Y3603825D01*
X846390Y3603025D01*
X846990Y3602359D01*
X847790Y3602092D01*
X848590Y3602359D01*
X849190Y3603025D01*
X849590Y3603825D01*
X849890Y3604892D01*
X849990Y3606092D01*
X849890Y3607292D01*
X849590Y3608359D01*
X849190Y3609159D01*
X848590Y3609825D01*
X847790Y3610092D01*
G01X853190Y3602092D02*
Y3610092D01*
X855790Y3603425D01*
X858390Y3610092D01*
Y3602092D01*
G01X862590Y3610092D02*
X864990D01*
G01X863790D02*
Y3602092D01*
G01X862590D02*
X864990D01*
G01X869790Y3610092D02*
Y3602092D01*
X873790D01*
G01X877690Y3603158D02*
X878490Y3602492D01*
X879390Y3602092D01*
X880190D01*
X880990Y3602492D01*
X881590Y3603158D01*
X881890Y3604092D01*
X881690Y3605025D01*
X881190Y3605825D01*
X880290Y3606359D01*
X879090Y3606625D01*
X878390Y3607159D01*
X878090Y3608092D01*
X878290Y3609025D01*
X878790Y3609692D01*
X879490Y3610092D01*
X880190D01*
X880890Y3609825D01*
X881490Y3609159D01*
G01X887790Y3601825D02*
X887590Y3601959D01*
Y3602225D01*
X887790Y3602359D01*
X887990Y3602225D01*
Y3601959D01*
X887790Y3601825D01*
G01X901590Y3602092D02*
Y3610092D01*
X903590D01*
X904390Y3609692D01*
X904990Y3609159D01*
X905490Y3608359D01*
X905890Y3607425D01*
X905990Y3606092D01*
X905890Y3604759D01*
X905490Y3603825D01*
X904990Y3603025D01*
X904390Y3602492D01*
X903590Y3602092D01*
X901590D01*
G01X909790D02*
Y3610092D01*
X912290D01*
X913090Y3609692D01*
X913590Y3609159D01*
X913790Y3608092D01*
X913590Y3607025D01*
X912990Y3606359D01*
X912290Y3605959D01*
X909790D01*
G01X912290D02*
X913790Y3602092D01*
G01X918590Y3610092D02*
X920990D01*
G01X919790D02*
Y3602092D01*
G01X918590D02*
X920990D01*
G01X925790Y3610092D02*
Y3602092D01*
X929790D01*
G01X933790Y3610092D02*
Y3602092D01*
X937790D01*
G01X941990Y3601825D02*
X945590Y3610092D01*
G01X949890Y3602092D02*
Y3610092D01*
X953690D01*
G01X952290Y3606225D02*
X949890D01*
G01X961790Y3602092D02*
X957790D01*
Y3610092D01*
X961790D01*
G01X960190Y3606225D02*
X957790D01*
G01X965290Y3602092D02*
X967790Y3610092D01*
X970290Y3602092D01*
G01X969390Y3604892D02*
X966190D01*
G01X975790Y3610092D02*
Y3602092D01*
G01X973490Y3610092D02*
X978090D01*
G01X981590D02*
Y3604359D01*
X981990Y3603158D01*
X982790Y3602359D01*
X983790Y3602092D01*
X984790Y3602359D01*
X985590Y3603158D01*
X985990Y3604359D01*
Y3610092D01*
G01X989790Y3602092D02*
Y3610092D01*
X992290D01*
X993090Y3609692D01*
X993590Y3609159D01*
X993790Y3608092D01*
X993590Y3607025D01*
X992990Y3606359D01*
X992290Y3605959D01*
X989790D01*
G01X992290D02*
X993790Y3602092D01*
G01X1001790D02*
X997790D01*
Y3610092D01*
X1001790D01*
G01X1000190Y3606225D02*
X997790D01*
G01X1005990Y3601825D02*
X1009590Y3610092D01*
G01X1013790Y3602092D02*
Y3610092D01*
X1016290D01*
X1017090Y3609692D01*
X1017590Y3609159D01*
X1017790Y3608092D01*
X1017590Y3607025D01*
X1016990Y3606359D01*
X1016290Y3605959D01*
X1013790D01*
G01X1016290D02*
X1017790Y3602092D01*
G01X1023790D02*
X1022990Y3602225D01*
X1022290Y3602759D01*
X1021690Y3603559D01*
X1021290Y3604492D01*
X1021090Y3605559D01*
Y3606625D01*
X1021290Y3607692D01*
X1021690Y3608625D01*
X1022290Y3609425D01*
X1022990Y3609959D01*
X1023790Y3610092D01*
X1024590Y3609959D01*
X1025290Y3609425D01*
X1025890Y3608625D01*
X1026290Y3607692D01*
X1026490Y3606625D01*
Y3605559D01*
X1026290Y3604492D01*
X1025890Y3603559D01*
X1025290Y3602759D01*
X1024590Y3602225D01*
X1023790Y3602092D01*
G01X1029590Y3610092D02*
Y3604359D01*
X1029990Y3603158D01*
X1030790Y3602359D01*
X1031790Y3602092D01*
X1032790Y3602359D01*
X1033590Y3603158D01*
X1033990Y3604359D01*
Y3610092D01*
G01X1039790D02*
Y3602092D01*
G01X1037490Y3610092D02*
X1042090D01*
G01X1049790Y3602092D02*
X1045790D01*
Y3610092D01*
X1049790D01*
G01X1048190Y3606225D02*
X1045790D01*
G01X1053990Y3601825D02*
X1057590Y3610092D01*
G01X1061790Y3602092D02*
Y3610092D01*
X1064190D01*
X1064990Y3609692D01*
X1065590Y3608759D01*
X1065790Y3607692D01*
X1065590Y3606625D01*
X1065090Y3605825D01*
X1064190Y3605425D01*
X1061790D01*
G01X1069790Y3602092D02*
Y3610092D01*
X1072290D01*
X1073090Y3609692D01*
X1073590Y3609159D01*
X1073790Y3608092D01*
X1073590Y3607025D01*
X1072990Y3606359D01*
X1072290Y3605959D01*
X1069790D01*
G01X1072290D02*
X1073790Y3602092D01*
G01X1079790D02*
X1078990Y3602225D01*
X1078290Y3602759D01*
X1077690Y3603559D01*
X1077290Y3604492D01*
X1077090Y3605559D01*
Y3606625D01*
X1077290Y3607692D01*
X1077690Y3608625D01*
X1078290Y3609425D01*
X1078990Y3609959D01*
X1079790Y3610092D01*
X1080590Y3609959D01*
X1081290Y3609425D01*
X1081890Y3608625D01*
X1082290Y3607692D01*
X1082490Y3606625D01*
Y3605559D01*
X1082290Y3604492D01*
X1081890Y3603559D01*
X1081290Y3602759D01*
X1080590Y3602225D01*
X1079790Y3602092D01*
G01X1085890D02*
Y3610092D01*
X1089690D01*
G01X1088290Y3606225D02*
X1085890D01*
G01X1094590Y3610092D02*
X1096990D01*
G01X1095790D02*
Y3602092D01*
G01X1094590D02*
X1096990D01*
G01X1101790Y3610092D02*
Y3602092D01*
X1105790D01*
G01X1113790D02*
X1109790D01*
Y3610092D01*
X1113790D01*
G01X1112190Y3606225D02*
X1109790D01*
G01X1125690Y3603158D02*
X1126490Y3602492D01*
X1127390Y3602092D01*
X1128190D01*
X1128990Y3602492D01*
X1129590Y3603158D01*
X1129890Y3604092D01*
X1129690Y3605025D01*
X1129190Y3605825D01*
X1128290Y3606359D01*
X1127090Y3606625D01*
X1126390Y3607159D01*
X1126090Y3608092D01*
X1126290Y3609025D01*
X1126790Y3609692D01*
X1127490Y3610092D01*
X1128190D01*
X1128890Y3609825D01*
X1129490Y3609159D01*
G01X1133790Y3602092D02*
Y3610092D01*
X1136190D01*
X1136990Y3609692D01*
X1137590Y3608759D01*
X1137790Y3607692D01*
X1137590Y3606625D01*
X1137090Y3605825D01*
X1136190Y3605425D01*
X1133790D01*
G01X1141290Y3602092D02*
X1143790Y3610092D01*
X1146290Y3602092D01*
G01X1145390Y3604892D02*
X1142190D01*
G01X1153990Y3609425D02*
X1153390Y3609825D01*
X1152690Y3610092D01*
X1151890D01*
X1150990Y3609692D01*
X1150290Y3609025D01*
X1149790Y3608225D01*
X1149390Y3606892D01*
X1149290Y3605692D01*
X1149490Y3604492D01*
X1149790Y3603692D01*
X1150390Y3602892D01*
X1151090Y3602359D01*
X1151790Y3602092D01*
X1152490D01*
X1153190Y3602359D01*
X1153790Y3602759D01*
X1154290Y3603292D01*
G01X1158590Y3610092D02*
X1160990D01*
G01X1159790D02*
Y3602092D01*
G01X1158590D02*
X1160990D01*
G01X1165490D02*
Y3610092D01*
X1170090Y3602092D01*
Y3610092D01*
G01X1176390Y3606092D02*
X1178390D01*
Y3603692D01*
X1177790Y3602892D01*
X1177090Y3602359D01*
X1176090Y3602092D01*
X1175090Y3602359D01*
X1174390Y3602892D01*
X1173790Y3603692D01*
X1173390Y3604625D01*
X1173190Y3605692D01*
Y3606625D01*
X1173390Y3607425D01*
X1173790Y3608359D01*
X1174390Y3609159D01*
X1174990Y3609692D01*
X1175790Y3610092D01*
X1176490D01*
X1177290Y3609825D01*
X1177890Y3609292D01*
G01X1189290Y3602092D02*
X1191790Y3610092D01*
X1194290Y3602092D01*
G01X1193390Y3604892D02*
X1190190D01*
G01X1197790Y3610092D02*
Y3602092D01*
X1201790D01*
G01X1205790Y3610092D02*
Y3602092D01*
X1209790D01*
G01X1221590Y3610092D02*
Y3604359D01*
X1221990Y3603158D01*
X1222790Y3602359D01*
X1223790Y3602092D01*
X1224790Y3602359D01*
X1225590Y3603158D01*
X1225990Y3604359D01*
Y3610092D01*
G01X1229690Y3603158D02*
X1230490Y3602492D01*
X1231390Y3602092D01*
X1232190D01*
X1232990Y3602492D01*
X1233590Y3603158D01*
X1233890Y3604092D01*
X1233690Y3605025D01*
X1233190Y3605825D01*
X1232290Y3606359D01*
X1231090Y3606625D01*
X1230390Y3607159D01*
X1230090Y3608092D01*
X1230290Y3609025D01*
X1230790Y3609692D01*
X1231490Y3610092D01*
X1232190D01*
X1232890Y3609825D01*
X1233490Y3609159D01*
G01X1238590Y3610092D02*
X1240990D01*
G01X1239790D02*
Y3602092D01*
G01X1238590D02*
X1240990D01*
G01X1245490D02*
Y3610092D01*
X1250090Y3602092D01*
Y3610092D01*
G01X1256390Y3606092D02*
X1258390D01*
Y3603692D01*
X1257790Y3602892D01*
X1257090Y3602359D01*
X1256090Y3602092D01*
X1255090Y3602359D01*
X1254390Y3602892D01*
X1253790Y3603692D01*
X1253390Y3604625D01*
X1253190Y3605692D01*
Y3606625D01*
X1253390Y3607425D01*
X1253790Y3608359D01*
X1254390Y3609159D01*
X1254990Y3609692D01*
X1255790Y3610092D01*
X1256490D01*
X1257290Y3609825D01*
X1257890Y3609292D01*
G01X1271790Y3602092D02*
Y3610092D01*
X1270590Y3608492D01*
G01Y3602092D02*
X1272990D01*
G01X1279790Y3610092D02*
X1278990Y3609825D01*
X1278390Y3609159D01*
X1277990Y3608359D01*
X1277690Y3607292D01*
X1277590Y3606092D01*
X1277690Y3604892D01*
X1277990Y3603825D01*
X1278390Y3603025D01*
X1278990Y3602359D01*
X1279790Y3602092D01*
X1280590Y3602359D01*
X1281190Y3603025D01*
X1281590Y3603825D01*
X1281890Y3604892D01*
X1281990Y3606092D01*
X1281890Y3607292D01*
X1281590Y3608359D01*
X1281190Y3609159D01*
X1280590Y3609825D01*
X1279790Y3610092D01*
G01X1287790D02*
X1286990Y3609825D01*
X1286390Y3609159D01*
X1285990Y3608359D01*
X1285690Y3607292D01*
X1285590Y3606092D01*
X1285690Y3604892D01*
X1285990Y3603825D01*
X1286390Y3603025D01*
X1286990Y3602359D01*
X1287790Y3602092D01*
X1288590Y3602359D01*
X1289190Y3603025D01*
X1289590Y3603825D01*
X1289890Y3604892D01*
X1289990Y3606092D01*
X1289890Y3607292D01*
X1289590Y3608359D01*
X1289190Y3609159D01*
X1288590Y3609825D01*
X1287790Y3610092D01*
G01X1293190Y3602092D02*
Y3610092D01*
X1295790Y3603425D01*
X1298390Y3610092D01*
Y3602092D01*
G01X1302590Y3610092D02*
X1304990D01*
G01X1303790D02*
Y3602092D01*
G01X1302590D02*
X1304990D01*
G01X1309790Y3610092D02*
Y3602092D01*
X1313790D01*
G01X1317690Y3603158D02*
X1318490Y3602492D01*
X1319390Y3602092D01*
X1320190D01*
X1320990Y3602492D01*
X1321590Y3603158D01*
X1321890Y3604092D01*
X1321690Y3605025D01*
X1321190Y3605825D01*
X1320290Y3606359D01*
X1319090Y3606625D01*
X1318390Y3607159D01*
X1318090Y3608092D01*
X1318290Y3609025D01*
X1318790Y3609692D01*
X1319490Y3610092D01*
X1320190D01*
X1320890Y3609825D01*
X1321490Y3609159D01*
G01X1327790Y3601825D02*
X1327590Y3601959D01*
Y3602225D01*
X1327790Y3602359D01*
X1327990Y3602225D01*
Y3601959D01*
X1327790Y3601825D01*
G01X1349790Y3610092D02*
Y3602092D01*
X1353790D01*
G01X1357290D02*
X1359790Y3610092D01*
X1362290Y3602092D01*
G01X1361390Y3604892D02*
X1358190D01*
G01X1368590Y3606359D02*
X1368990Y3606759D01*
X1369290Y3607425D01*
X1369490Y3608359D01*
X1369290Y3609159D01*
X1368890Y3609692D01*
X1368190Y3610092D01*
X1365490D01*
Y3602092D01*
X1368790D01*
X1369490Y3602625D01*
X1369890Y3603425D01*
X1370090Y3604359D01*
X1369890Y3605292D01*
X1369290Y3606092D01*
X1368590Y3606359D01*
X1365490D01*
G01X1377790Y3602092D02*
X1373790D01*
Y3610092D01*
X1377790D01*
G01X1376190Y3606225D02*
X1373790D01*
G01X1381790Y3610092D02*
Y3602092D01*
X1385790D01*
G01X1397290D02*
X1399790Y3610092D01*
X1402290Y3602092D01*
G01X1401390Y3604892D02*
X1398190D01*
G01X1405790Y3602092D02*
Y3610092D01*
X1408290D01*
X1409090Y3609692D01*
X1409590Y3609159D01*
X1409790Y3608092D01*
X1409590Y3607025D01*
X1408990Y3606359D01*
X1408290Y3605959D01*
X1405790D01*
G01X1408290D02*
X1409790Y3602092D01*
G01X1417790D02*
X1413790D01*
Y3610092D01*
X1417790D01*
G01X1416190Y3606225D02*
X1413790D01*
G01X1421290Y3602092D02*
X1423790Y3610092D01*
X1426290Y3602092D01*
G01X1425390Y3604892D02*
X1422190D01*
G01X1437490Y3602092D02*
Y3610092D01*
X1442090Y3602092D01*
Y3610092D01*
G01X1447790Y3602092D02*
X1446990Y3602225D01*
X1446290Y3602759D01*
X1445690Y3603559D01*
X1445290Y3604492D01*
X1445090Y3605559D01*
Y3606625D01*
X1445290Y3607692D01*
X1445690Y3608625D01*
X1446290Y3609425D01*
X1446990Y3609959D01*
X1447790Y3610092D01*
X1448590Y3609959D01*
X1449290Y3609425D01*
X1449890Y3608625D01*
X1450290Y3607692D01*
X1450490Y3606625D01*
Y3605559D01*
X1450290Y3604492D01*
X1449890Y3603559D01*
X1449290Y3602759D01*
X1448590Y3602225D01*
X1447790Y3602092D01*
G01X1461290D02*
X1463790Y3610092D01*
X1466290Y3602092D01*
G01X1465390Y3604892D02*
X1462190D01*
G01X1469590Y3602092D02*
Y3610092D01*
X1471590D01*
X1472390Y3609692D01*
X1472990Y3609159D01*
X1473490Y3608359D01*
X1473890Y3607425D01*
X1473990Y3606092D01*
X1473890Y3604759D01*
X1473490Y3603825D01*
X1472990Y3603025D01*
X1472390Y3602492D01*
X1471590Y3602092D01*
X1469590D01*
G01X1477590D02*
Y3610092D01*
X1479590D01*
X1480390Y3609692D01*
X1480990Y3609159D01*
X1481490Y3608359D01*
X1481890Y3607425D01*
X1481990Y3606092D01*
X1481890Y3604759D01*
X1481490Y3603825D01*
X1480990Y3603025D01*
X1480390Y3602492D01*
X1479590Y3602092D01*
X1477590D01*
G01X1493590D02*
Y3610092D01*
X1495590D01*
X1496390Y3609692D01*
X1496990Y3609159D01*
X1497490Y3608359D01*
X1497890Y3607425D01*
X1497990Y3606092D01*
X1497890Y3604759D01*
X1497490Y3603825D01*
X1496990Y3603025D01*
X1496390Y3602492D01*
X1495590Y3602092D01*
X1493590D01*
G01X1501590Y3610092D02*
Y3604359D01*
X1501990Y3603158D01*
X1502790Y3602359D01*
X1503790Y3602092D01*
X1504790Y3602359D01*
X1505590Y3603158D01*
X1505990Y3604359D01*
Y3610092D01*
G01X1509190Y3602092D02*
Y3610092D01*
X1511790Y3603425D01*
X1514390Y3610092D01*
Y3602092D01*
G01X1517190D02*
Y3610092D01*
X1519790Y3603425D01*
X1522390Y3610092D01*
Y3602092D01*
G01X1527790D02*
Y3605692D01*
X1525790Y3610092D01*
G01X1529790D02*
X1527790Y3605692D01*
G01X1541790Y3602092D02*
Y3610092D01*
X1544190D01*
X1544990Y3609692D01*
X1545590Y3608759D01*
X1545790Y3607692D01*
X1545590Y3606625D01*
X1545090Y3605825D01*
X1544190Y3605425D01*
X1541790D01*
G01X1549290Y3602092D02*
X1551790Y3610092D01*
X1554290Y3602092D01*
G01X1553390Y3604892D02*
X1550190D01*
G01X1557590Y3602092D02*
Y3610092D01*
X1559590D01*
X1560390Y3609692D01*
X1560990Y3609159D01*
X1561490Y3608359D01*
X1561890Y3607425D01*
X1561990Y3606092D01*
X1561890Y3604759D01*
X1561490Y3603825D01*
X1560990Y3603025D01*
X1560390Y3602492D01*
X1559590Y3602092D01*
X1557590D01*
G01X1567790Y3601825D02*
X1567590Y3601959D01*
Y3602225D01*
X1567790Y3602359D01*
X1567990Y3602225D01*
Y3601959D01*
X1567790Y3601825D01*
G01X-50410Y3663292D02*
X-49810Y3662625D01*
X-49110Y3662225D01*
X-48210Y3662092D01*
X-47310Y3662359D01*
X-46610Y3662892D01*
X-46110Y3663825D01*
X-46010Y3664892D01*
X-46210Y3665959D01*
X-46710Y3666625D01*
X-47410Y3667159D01*
X-48110Y3667292D01*
X-48810Y3667159D01*
X-49710Y3666625D01*
X-49410Y3670092D01*
X-46710D01*
G01X-40210Y3661825D02*
X-40410Y3661959D01*
Y3662225D01*
X-40210Y3662359D01*
X-40010Y3662225D01*
Y3661959D01*
X-40210Y3661825D01*
G01X-34210Y3662092D02*
Y3670092D01*
X-31810D01*
X-31010Y3669692D01*
X-30410Y3668759D01*
X-30210Y3667692D01*
X-30410Y3666625D01*
X-30910Y3665825D01*
X-31810Y3665425D01*
X-34210D01*
G01X-22210Y3662092D02*
X-26210D01*
Y3670092D01*
X-22210D01*
G01X-23810Y3666225D02*
X-26210D01*
G01X-14210Y3662092D02*
X-18210D01*
Y3670092D01*
X-14210D01*
G01X-15810Y3666225D02*
X-18210D01*
G01X-10210Y3670092D02*
Y3662092D01*
X-6210D01*
G01X-1410Y3670092D02*
X990D01*
G01X-210D02*
Y3662092D01*
G01X-1410D02*
X990D01*
G01X5490D02*
Y3670092D01*
X10090Y3662092D01*
Y3670092D01*
G01X16390Y3666092D02*
X18390D01*
Y3663692D01*
X17790Y3662892D01*
X17090Y3662359D01*
X16090Y3662092D01*
X15090Y3662359D01*
X14390Y3662892D01*
X13790Y3663692D01*
X13390Y3664625D01*
X13190Y3665692D01*
Y3666625D01*
X13390Y3667425D01*
X13790Y3668359D01*
X14390Y3669159D01*
X14990Y3669692D01*
X15790Y3670092D01*
X16490D01*
X17290Y3669825D01*
X17890Y3669292D01*
G01X29690Y3663158D02*
X30490Y3662492D01*
X31390Y3662092D01*
X32190D01*
X32990Y3662492D01*
X33590Y3663158D01*
X33890Y3664092D01*
X33690Y3665025D01*
X33190Y3665825D01*
X32290Y3666359D01*
X31090Y3666625D01*
X30390Y3667159D01*
X30090Y3668092D01*
X30290Y3669025D01*
X30790Y3669692D01*
X31490Y3670092D01*
X32190D01*
X32890Y3669825D01*
X33490Y3669159D01*
G01X39790Y3670092D02*
Y3662092D01*
G01X37490Y3670092D02*
X42090D01*
G01X45790Y3662092D02*
Y3670092D01*
X48290D01*
X49090Y3669692D01*
X49590Y3669159D01*
X49790Y3668092D01*
X49590Y3667025D01*
X48990Y3666359D01*
X48290Y3665959D01*
X45790D01*
G01X48290D02*
X49790Y3662092D01*
G01X57790D02*
X53790D01*
Y3670092D01*
X57790D01*
G01X56190Y3666225D02*
X53790D01*
G01X61490Y3662092D02*
Y3670092D01*
X66090Y3662092D01*
Y3670092D01*
G01X72390Y3666092D02*
X74390D01*
Y3663692D01*
X73790Y3662892D01*
X73090Y3662359D01*
X72090Y3662092D01*
X71090Y3662359D01*
X70390Y3662892D01*
X69790Y3663692D01*
X69390Y3664625D01*
X69190Y3665692D01*
Y3666625D01*
X69390Y3667425D01*
X69790Y3668359D01*
X70390Y3669159D01*
X70990Y3669692D01*
X71790Y3670092D01*
X72490D01*
X73290Y3669825D01*
X73890Y3669292D01*
G01X79790Y3670092D02*
Y3662092D01*
G01X77490Y3670092D02*
X82090D01*
G01X85690Y3662092D02*
Y3670092D01*
G01X89890D02*
Y3662092D01*
G01Y3666092D02*
X85690D01*
G01X101290Y3662092D02*
X103790Y3670092D01*
X106290Y3662092D01*
G01X105390Y3664892D02*
X102190D01*
G01X109490Y3662092D02*
Y3670092D01*
X114090Y3662092D01*
Y3670092D01*
G01X117590Y3662092D02*
Y3670092D01*
X119590D01*
X120390Y3669692D01*
X120990Y3669159D01*
X121490Y3668359D01*
X121890Y3667425D01*
X121990Y3666092D01*
X121890Y3664759D01*
X121490Y3663825D01*
X120990Y3663025D01*
X120390Y3662492D01*
X119590Y3662092D01*
X117590D01*
G01X136590Y3666359D02*
X136990Y3666759D01*
X137290Y3667425D01*
X137490Y3668359D01*
X137290Y3669159D01*
X136890Y3669692D01*
X136190Y3670092D01*
X133490D01*
Y3662092D01*
X136790D01*
X137490Y3662625D01*
X137890Y3663425D01*
X138090Y3664359D01*
X137890Y3665292D01*
X137290Y3666092D01*
X136590Y3666359D01*
X133490D01*
G01X144390Y3666092D02*
X146390D01*
Y3663692D01*
X145790Y3662892D01*
X145090Y3662359D01*
X144090Y3662092D01*
X143090Y3662359D01*
X142390Y3662892D01*
X141790Y3663692D01*
X141390Y3664625D01*
X141190Y3665692D01*
Y3666625D01*
X141390Y3667425D01*
X141790Y3668359D01*
X142390Y3669159D01*
X142990Y3669692D01*
X143790Y3670092D01*
X144490D01*
X145290Y3669825D01*
X145890Y3669292D01*
G01X149290Y3662092D02*
X151790Y3670092D01*
X154290Y3662092D01*
G01X153390Y3664892D02*
X150190D01*
G01X165790Y3662092D02*
Y3670092D01*
X168190D01*
X168990Y3669692D01*
X169590Y3668759D01*
X169790Y3667692D01*
X169590Y3666625D01*
X169090Y3665825D01*
X168190Y3665425D01*
X165790D01*
G01X173290Y3662092D02*
X175790Y3670092D01*
X178290Y3662092D01*
G01X177390Y3664892D02*
X174190D01*
G01X181590Y3662092D02*
Y3670092D01*
X183590D01*
X184390Y3669692D01*
X184990Y3669159D01*
X185490Y3668359D01*
X185890Y3667425D01*
X185990Y3666092D01*
X185890Y3664759D01*
X185490Y3663825D01*
X184990Y3663025D01*
X184390Y3662492D01*
X183590Y3662092D01*
X181590D01*
G01X189690Y3663158D02*
X190490Y3662492D01*
X191390Y3662092D01*
X192190D01*
X192990Y3662492D01*
X193590Y3663158D01*
X193890Y3664092D01*
X193690Y3665025D01*
X193190Y3665825D01*
X192290Y3666359D01*
X191090Y3666625D01*
X190390Y3667159D01*
X190090Y3668092D01*
X190290Y3669025D01*
X190790Y3669692D01*
X191490Y3670092D01*
X192190D01*
X192890Y3669825D01*
X193490Y3669159D01*
G01X205290Y3662092D02*
X207790Y3670092D01*
X210290Y3662092D01*
G01X209390Y3664892D02*
X206190D01*
G01X213590Y3662092D02*
Y3670092D01*
X215590D01*
X216390Y3669692D01*
X216990Y3669159D01*
X217490Y3668359D01*
X217890Y3667425D01*
X217990Y3666092D01*
X217890Y3664759D01*
X217490Y3663825D01*
X216990Y3663025D01*
X216390Y3662492D01*
X215590Y3662092D01*
X213590D01*
G01X221690D02*
Y3670092D01*
G01X225890D02*
Y3662092D01*
G01Y3666092D02*
X221690D01*
G01X233790Y3662092D02*
X229790D01*
Y3670092D01*
X233790D01*
G01X232190Y3666225D02*
X229790D01*
G01X237690Y3663158D02*
X238490Y3662492D01*
X239390Y3662092D01*
X240190D01*
X240990Y3662492D01*
X241590Y3663158D01*
X241890Y3664092D01*
X241690Y3665025D01*
X241190Y3665825D01*
X240290Y3666359D01*
X239090Y3666625D01*
X238390Y3667159D01*
X238090Y3668092D01*
X238290Y3669025D01*
X238790Y3669692D01*
X239490Y3670092D01*
X240190D01*
X240890Y3669825D01*
X241490Y3669159D01*
G01X246590Y3670092D02*
X248990D01*
G01X247790D02*
Y3662092D01*
G01X246590D02*
X248990D01*
G01X255790D02*
X254990Y3662225D01*
X254290Y3662759D01*
X253690Y3663559D01*
X253290Y3664492D01*
X253090Y3665559D01*
Y3666625D01*
X253290Y3667692D01*
X253690Y3668625D01*
X254290Y3669425D01*
X254990Y3669959D01*
X255790Y3670092D01*
X256590Y3669959D01*
X257290Y3669425D01*
X257890Y3668625D01*
X258290Y3667692D01*
X258490Y3666625D01*
Y3665559D01*
X258290Y3664492D01*
X257890Y3663559D01*
X257290Y3662759D01*
X256590Y3662225D01*
X255790Y3662092D01*
G01X261490D02*
Y3670092D01*
X266090Y3662092D01*
Y3670092D01*
G01X279790D02*
Y3662092D01*
G01X277490Y3670092D02*
X282090D01*
G01X289790Y3662092D02*
X285790D01*
Y3670092D01*
X289790D01*
G01X288190Y3666225D02*
X285790D01*
G01X293690Y3663158D02*
X294490Y3662492D01*
X295390Y3662092D01*
X296190D01*
X296990Y3662492D01*
X297590Y3663158D01*
X297890Y3664092D01*
X297690Y3665025D01*
X297190Y3665825D01*
X296290Y3666359D01*
X295090Y3666625D01*
X294390Y3667159D01*
X294090Y3668092D01*
X294290Y3669025D01*
X294790Y3669692D01*
X295490Y3670092D01*
X296190D01*
X296890Y3669825D01*
X297490Y3669159D01*
G01X303790Y3670092D02*
Y3662092D01*
G01X301490Y3670092D02*
X306090D01*
G01X317790Y3662092D02*
Y3670092D01*
X320190D01*
X320990Y3669692D01*
X321590Y3668759D01*
X321790Y3667692D01*
X321590Y3666625D01*
X321090Y3665825D01*
X320190Y3665425D01*
X317790D01*
G01X325290Y3662092D02*
X327790Y3670092D01*
X330290Y3662092D01*
G01X329390Y3664892D02*
X326190D01*
G01X335790Y3670092D02*
Y3662092D01*
G01X333490Y3670092D02*
X338090D01*
G01X343790D02*
Y3662092D01*
G01X341490Y3670092D02*
X346090D01*
G01X353790Y3662092D02*
X349790D01*
Y3670092D01*
X353790D01*
G01X352190Y3666225D02*
X349790D01*
G01X357790Y3662092D02*
Y3670092D01*
X360290D01*
X361090Y3669692D01*
X361590Y3669159D01*
X361790Y3668092D01*
X361590Y3667025D01*
X360990Y3666359D01*
X360290Y3665959D01*
X357790D01*
G01X360290D02*
X361790Y3662092D01*
G01X365490D02*
Y3670092D01*
X370090Y3662092D01*
Y3670092D01*
G01X373690Y3663158D02*
X374490Y3662492D01*
X375390Y3662092D01*
X376190D01*
X376990Y3662492D01*
X377590Y3663158D01*
X377890Y3664092D01*
X377690Y3665025D01*
X377190Y3665825D01*
X376290Y3666359D01*
X375090Y3666625D01*
X374390Y3667159D01*
X374090Y3668092D01*
X374290Y3669025D01*
X374790Y3669692D01*
X375490Y3670092D01*
X376190D01*
X376890Y3669825D01*
X377490Y3669159D01*
G01X383790Y3661825D02*
X383590Y3661959D01*
Y3662225D01*
X383790Y3662359D01*
X383990Y3662225D01*
Y3661959D01*
X383790Y3661825D01*
G01X-47010Y3737092D02*
Y3745092D01*
X-50710Y3739359D01*
X-45710D01*
G01X-40210Y3736825D02*
X-40410Y3736959D01*
Y3737225D01*
X-40210Y3737359D01*
X-40010Y3737225D01*
Y3736959D01*
X-40210Y3736825D01*
G01X-30010Y3744425D02*
X-30610Y3744825D01*
X-31310Y3745092D01*
X-32110D01*
X-33010Y3744692D01*
X-33710Y3744025D01*
X-34210Y3743225D01*
X-34610Y3741892D01*
X-34710Y3740692D01*
X-34510Y3739492D01*
X-34210Y3738692D01*
X-33610Y3737892D01*
X-32910Y3737359D01*
X-32210Y3737092D01*
X-31510D01*
X-30810Y3737359D01*
X-30210Y3737759D01*
X-29710Y3738292D01*
G01X-24210Y3737092D02*
X-25010Y3737225D01*
X-25710Y3737759D01*
X-26310Y3738559D01*
X-26710Y3739492D01*
X-26910Y3740559D01*
Y3741625D01*
X-26710Y3742692D01*
X-26310Y3743625D01*
X-25710Y3744425D01*
X-25010Y3744959D01*
X-24210Y3745092D01*
X-23410Y3744959D01*
X-22710Y3744425D01*
X-22110Y3743625D01*
X-21710Y3742692D01*
X-21510Y3741625D01*
Y3740559D01*
X-21710Y3739492D01*
X-22110Y3738559D01*
X-22710Y3737759D01*
X-23410Y3737225D01*
X-24210Y3737092D01*
G01X-18510D02*
Y3745092D01*
X-13910Y3737092D01*
Y3745092D01*
G01X-8210D02*
Y3737092D01*
G01X-10510Y3745092D02*
X-5910D01*
G01X-2210Y3737092D02*
Y3745092D01*
X290D01*
X1090Y3744692D01*
X1590Y3744159D01*
X1790Y3743092D01*
X1590Y3742025D01*
X990Y3741359D01*
X290Y3740959D01*
X-2210D01*
G01X290D02*
X1790Y3737092D01*
G01X7790D02*
X6990Y3737225D01*
X6290Y3737759D01*
X5690Y3738559D01*
X5290Y3739492D01*
X5090Y3740559D01*
Y3741625D01*
X5290Y3742692D01*
X5690Y3743625D01*
X6290Y3744425D01*
X6990Y3744959D01*
X7790Y3745092D01*
X8590Y3744959D01*
X9290Y3744425D01*
X9890Y3743625D01*
X10290Y3742692D01*
X10490Y3741625D01*
Y3740559D01*
X10290Y3739492D01*
X9890Y3738559D01*
X9290Y3737759D01*
X8590Y3737225D01*
X7790Y3737092D01*
G01X13790Y3745092D02*
Y3737092D01*
X17790D01*
G01X21790Y3745092D02*
Y3737092D01*
X25790D01*
G01X33790D02*
X29790D01*
Y3745092D01*
X33790D01*
G01X32190Y3741225D02*
X29790D01*
G01X37590Y3737092D02*
Y3745092D01*
X39590D01*
X40390Y3744692D01*
X40990Y3744159D01*
X41490Y3743359D01*
X41890Y3742425D01*
X41990Y3741092D01*
X41890Y3739759D01*
X41490Y3738825D01*
X40990Y3738025D01*
X40390Y3737492D01*
X39590Y3737092D01*
X37590D01*
G01X54590Y3745092D02*
X56990D01*
G01X55790D02*
Y3737092D01*
G01X54590D02*
X56990D01*
G01X61190D02*
Y3745092D01*
X63790Y3738425D01*
X66390Y3745092D01*
Y3737092D01*
G01X69790D02*
Y3745092D01*
X72190D01*
X72990Y3744692D01*
X73590Y3743759D01*
X73790Y3742692D01*
X73590Y3741625D01*
X73090Y3740825D01*
X72190Y3740425D01*
X69790D01*
G01X81790Y3737092D02*
X77790D01*
Y3745092D01*
X81790D01*
G01X80190Y3741225D02*
X77790D01*
G01X85590Y3737092D02*
Y3745092D01*
X87590D01*
X88390Y3744692D01*
X88990Y3744159D01*
X89490Y3743359D01*
X89890Y3742425D01*
X89990Y3741092D01*
X89890Y3739759D01*
X89490Y3738825D01*
X88990Y3738025D01*
X88390Y3737492D01*
X87590Y3737092D01*
X85590D01*
G01X93290D02*
X95790Y3745092D01*
X98290Y3737092D01*
G01X97390Y3739892D02*
X94190D01*
G01X101490Y3737092D02*
Y3745092D01*
X106090Y3737092D01*
Y3745092D01*
G01X113990Y3744425D02*
X113390Y3744825D01*
X112690Y3745092D01*
X111890D01*
X110990Y3744692D01*
X110290Y3744025D01*
X109790Y3743225D01*
X109390Y3741892D01*
X109290Y3740692D01*
X109490Y3739492D01*
X109790Y3738692D01*
X110390Y3737892D01*
X111090Y3737359D01*
X111790Y3737092D01*
X112490D01*
X113190Y3737359D01*
X113790Y3737759D01*
X114290Y3738292D01*
G01X121790Y3737092D02*
X117790D01*
Y3745092D01*
X121790D01*
G01X120190Y3741225D02*
X117790D01*
G01X136590Y3741359D02*
X136990Y3741759D01*
X137290Y3742425D01*
X137490Y3743359D01*
X137290Y3744159D01*
X136890Y3744692D01*
X136190Y3745092D01*
X133490D01*
Y3737092D01*
X136790D01*
X137490Y3737625D01*
X137890Y3738425D01*
X138090Y3739359D01*
X137890Y3740292D01*
X137290Y3741092D01*
X136590Y3741359D01*
X133490D01*
G01X143790Y3737092D02*
X142990Y3737225D01*
X142290Y3737759D01*
X141690Y3738559D01*
X141290Y3739492D01*
X141090Y3740559D01*
Y3741625D01*
X141290Y3742692D01*
X141690Y3743625D01*
X142290Y3744425D01*
X142990Y3744959D01*
X143790Y3745092D01*
X144590Y3744959D01*
X145290Y3744425D01*
X145890Y3743625D01*
X146290Y3742692D01*
X146490Y3741625D01*
Y3740559D01*
X146290Y3739492D01*
X145890Y3738559D01*
X145290Y3737759D01*
X144590Y3737225D01*
X143790Y3737092D01*
G01X149290D02*
X151790Y3745092D01*
X154290Y3737092D01*
G01X153390Y3739892D02*
X150190D01*
G01X157790Y3737092D02*
Y3745092D01*
X160290D01*
X161090Y3744692D01*
X161590Y3744159D01*
X161790Y3743092D01*
X161590Y3742025D01*
X160990Y3741359D01*
X160290Y3740959D01*
X157790D01*
G01X160290D02*
X161790Y3737092D01*
G01X165590D02*
Y3745092D01*
X167590D01*
X168390Y3744692D01*
X168990Y3744159D01*
X169490Y3743359D01*
X169890Y3742425D01*
X169990Y3741092D01*
X169890Y3739759D01*
X169490Y3738825D01*
X168990Y3738025D01*
X168390Y3737492D01*
X167590Y3737092D01*
X165590D01*
G01X175790Y3736825D02*
X175590Y3736959D01*
Y3737225D01*
X175790Y3737359D01*
X175990Y3737225D01*
Y3736959D01*
X175790Y3736825D01*
G01X189690Y3738158D02*
X190490Y3737492D01*
X191390Y3737092D01*
X192190D01*
X192990Y3737492D01*
X193590Y3738158D01*
X193890Y3739092D01*
X193690Y3740025D01*
X193190Y3740825D01*
X192290Y3741359D01*
X191090Y3741625D01*
X190390Y3742159D01*
X190090Y3743092D01*
X190290Y3744025D01*
X190790Y3744692D01*
X191490Y3745092D01*
X192190D01*
X192890Y3744825D01*
X193490Y3744159D01*
G01X201790Y3737092D02*
X197790D01*
Y3745092D01*
X201790D01*
G01X200190Y3741225D02*
X197790D01*
G01X209790Y3737092D02*
X205790D01*
Y3745092D01*
X209790D01*
G01X208190Y3741225D02*
X205790D01*
G01X221790Y3745092D02*
Y3737092D01*
X225790D01*
G01X229290D02*
X231790Y3745092D01*
X234290Y3737092D01*
G01X233390Y3739892D02*
X230190D01*
G01X239790Y3737092D02*
Y3740692D01*
X237790Y3745092D01*
G01X241790D02*
X239790Y3740692D01*
G01X249790Y3737092D02*
X245790D01*
Y3745092D01*
X249790D01*
G01X248190Y3741225D02*
X245790D01*
G01X253790Y3737092D02*
Y3745092D01*
X256290D01*
X257090Y3744692D01*
X257590Y3744159D01*
X257790Y3743092D01*
X257590Y3742025D01*
X256990Y3741359D01*
X256290Y3740959D01*
X253790D01*
G01X256290D02*
X257790Y3737092D01*
G01X269690Y3738158D02*
X270490Y3737492D01*
X271390Y3737092D01*
X272190D01*
X272990Y3737492D01*
X273590Y3738158D01*
X273890Y3739092D01*
X273690Y3740025D01*
X273190Y3740825D01*
X272290Y3741359D01*
X271090Y3741625D01*
X270390Y3742159D01*
X270090Y3743092D01*
X270290Y3744025D01*
X270790Y3744692D01*
X271490Y3745092D01*
X272190D01*
X272890Y3744825D01*
X273490Y3744159D01*
G01X279790Y3745092D02*
Y3737092D01*
G01X277490Y3745092D02*
X282090D01*
G01X285290Y3737092D02*
X287790Y3745092D01*
X290290Y3737092D01*
G01X289390Y3739892D02*
X286190D01*
G01X297990Y3744425D02*
X297390Y3744825D01*
X296690Y3745092D01*
X295890D01*
X294990Y3744692D01*
X294290Y3744025D01*
X293790Y3743225D01*
X293390Y3741892D01*
X293290Y3740692D01*
X293490Y3739492D01*
X293790Y3738692D01*
X294390Y3737892D01*
X295090Y3737359D01*
X295790Y3737092D01*
X296490D01*
X297190Y3737359D01*
X297790Y3737759D01*
X298290Y3738292D01*
G01X301590Y3737092D02*
Y3745092D01*
G01X305390D02*
X301590Y3740158D01*
G01X305990Y3737092D02*
X303290Y3742425D01*
G01X309590Y3745092D02*
Y3739359D01*
X309990Y3738158D01*
X310790Y3737359D01*
X311790Y3737092D01*
X312790Y3737359D01*
X313590Y3738158D01*
X313990Y3739359D01*
Y3745092D01*
G01X317790Y3737092D02*
Y3745092D01*
X320190D01*
X320990Y3744692D01*
X321590Y3743759D01*
X321790Y3742692D01*
X321590Y3741625D01*
X321090Y3740825D01*
X320190Y3740425D01*
X317790D01*
G01X333290Y3737092D02*
X335790Y3745092D01*
X338290Y3737092D01*
G01X337390Y3739892D02*
X334190D01*
G01X341490Y3737092D02*
Y3745092D01*
X346090Y3737092D01*
Y3745092D01*
G01X349590Y3737092D02*
Y3745092D01*
X351590D01*
X352390Y3744692D01*
X352990Y3744159D01*
X353490Y3743359D01*
X353890Y3742425D01*
X353990Y3741092D01*
X353890Y3739759D01*
X353490Y3738825D01*
X352990Y3738025D01*
X352390Y3737492D01*
X351590Y3737092D01*
X349590D01*
G01X366590Y3745092D02*
X368990D01*
G01X367790D02*
Y3737092D01*
G01X366590D02*
X368990D01*
G01X373190D02*
Y3745092D01*
X375790Y3738425D01*
X378390Y3745092D01*
Y3737092D01*
G01X381790D02*
Y3745092D01*
X384190D01*
X384990Y3744692D01*
X385590Y3743759D01*
X385790Y3742692D01*
X385590Y3741625D01*
X385090Y3740825D01*
X384190Y3740425D01*
X381790D01*
G01X393790Y3737092D02*
X389790D01*
Y3745092D01*
X393790D01*
G01X392190Y3741225D02*
X389790D01*
G01X397590Y3737092D02*
Y3745092D01*
X399590D01*
X400390Y3744692D01*
X400990Y3744159D01*
X401490Y3743359D01*
X401890Y3742425D01*
X401990Y3741092D01*
X401890Y3739759D01*
X401490Y3738825D01*
X400990Y3738025D01*
X400390Y3737492D01*
X399590Y3737092D01*
X397590D01*
G01X405290D02*
X407790Y3745092D01*
X410290Y3737092D01*
G01X409390Y3739892D02*
X406190D01*
G01X413490Y3737092D02*
Y3745092D01*
X418090Y3737092D01*
Y3745092D01*
G01X425990Y3744425D02*
X425390Y3744825D01*
X424690Y3745092D01*
X423890D01*
X422990Y3744692D01*
X422290Y3744025D01*
X421790Y3743225D01*
X421390Y3741892D01*
X421290Y3740692D01*
X421490Y3739492D01*
X421790Y3738692D01*
X422390Y3737892D01*
X423090Y3737359D01*
X423790Y3737092D01*
X424490D01*
X425190Y3737359D01*
X425790Y3737759D01*
X426290Y3738292D01*
G01X433790Y3737092D02*
X429790D01*
Y3745092D01*
X433790D01*
G01X432190Y3741225D02*
X429790D01*
G01X-29610Y3756092D02*
X-27610D01*
Y3753692D01*
X-28210Y3752892D01*
X-28910Y3752359D01*
X-29910Y3752092D01*
X-30910Y3752359D01*
X-31610Y3752892D01*
X-32210Y3753692D01*
X-32610Y3754625D01*
X-32810Y3755692D01*
Y3756625D01*
X-32610Y3757425D01*
X-32210Y3758359D01*
X-31610Y3759159D01*
X-31010Y3759692D01*
X-30210Y3760092D01*
X-29510D01*
X-28710Y3759825D01*
X-28110Y3759292D01*
G01X-22210Y3751825D02*
X-22410Y3751959D01*
Y3752225D01*
X-22210Y3752359D01*
X-22010Y3752225D01*
Y3751959D01*
X-22210Y3751825D01*
G01X-16510Y3752092D02*
Y3760092D01*
X-11910Y3752092D01*
Y3760092D01*
G01X-4210Y3752092D02*
X-8210D01*
Y3760092D01*
X-4210D01*
G01X-5810Y3756225D02*
X-8210D01*
G01X3790Y3752092D02*
X-210D01*
Y3760092D01*
X3790D01*
G01X2190Y3756225D02*
X-210D01*
G01X7590Y3752092D02*
Y3760092D01*
X9590D01*
X10390Y3759692D01*
X10990Y3759159D01*
X11490Y3758359D01*
X11890Y3757425D01*
X11990Y3756092D01*
X11890Y3754759D01*
X11490Y3753825D01*
X10990Y3753025D01*
X10390Y3752492D01*
X9590Y3752092D01*
X7590D01*
G01X23590Y3760092D02*
Y3754359D01*
X23990Y3753158D01*
X24790Y3752359D01*
X25790Y3752092D01*
X26790Y3752359D01*
X27590Y3753158D01*
X27990Y3754359D01*
Y3760092D01*
G01X31790D02*
Y3752092D01*
X35790D01*
G01X47190D02*
Y3760092D01*
X49790Y3753425D01*
X52390Y3760092D01*
Y3752092D01*
G01X55290D02*
X57790Y3760092D01*
X60290Y3752092D01*
G01X59390Y3754892D02*
X56190D01*
G01X63790Y3752092D02*
Y3760092D01*
X66290D01*
X67090Y3759692D01*
X67590Y3759159D01*
X67790Y3758092D01*
X67590Y3757025D01*
X66990Y3756359D01*
X66290Y3755959D01*
X63790D01*
G01X66290D02*
X67790Y3752092D01*
G01X71590D02*
Y3760092D01*
G01X75390D02*
X71590Y3755158D01*
G01X75990Y3752092D02*
X73290Y3757425D01*
G01X87290Y3752092D02*
X89790Y3760092D01*
X92290Y3752092D01*
G01X91390Y3754892D02*
X88190D01*
G01X95490Y3752092D02*
Y3760092D01*
X100090Y3752092D01*
Y3760092D01*
G01X103590Y3752092D02*
Y3760092D01*
X105590D01*
X106390Y3759692D01*
X106990Y3759159D01*
X107490Y3758359D01*
X107890Y3757425D01*
X107990Y3756092D01*
X107890Y3754759D01*
X107490Y3753825D01*
X106990Y3753025D01*
X106390Y3752492D01*
X105590Y3752092D01*
X103590D01*
G01X119590Y3760092D02*
Y3754359D01*
X119990Y3753158D01*
X120790Y3752359D01*
X121790Y3752092D01*
X122790Y3752359D01*
X123590Y3753158D01*
X123990Y3754359D01*
Y3760092D01*
G01X127790D02*
Y3752092D01*
X131790D01*
G01X143890D02*
Y3760092D01*
X147690D01*
G01X146290Y3756225D02*
X143890D01*
G01X152590Y3760092D02*
X154990D01*
G01X153790D02*
Y3752092D01*
G01X152590D02*
X154990D01*
G01X159790Y3760092D02*
Y3752092D01*
X163790D01*
G01X171790D02*
X167790D01*
Y3760092D01*
X171790D01*
G01X170190Y3756225D02*
X167790D01*
G01X183490Y3752092D02*
Y3760092D01*
X188090Y3752092D01*
Y3760092D01*
G01X191590D02*
Y3754359D01*
X191990Y3753158D01*
X192790Y3752359D01*
X193790Y3752092D01*
X194790Y3752359D01*
X195590Y3753158D01*
X195990Y3754359D01*
Y3760092D01*
G01X199190Y3752092D02*
Y3760092D01*
X201790Y3753425D01*
X204390Y3760092D01*
Y3752092D01*
G01X210590Y3756359D02*
X210990Y3756759D01*
X211290Y3757425D01*
X211490Y3758359D01*
X211290Y3759159D01*
X210890Y3759692D01*
X210190Y3760092D01*
X207490D01*
Y3752092D01*
X210790D01*
X211490Y3752625D01*
X211890Y3753425D01*
X212090Y3754359D01*
X211890Y3755292D01*
X211290Y3756092D01*
X210590Y3756359D01*
X207490D01*
G01X219790Y3752092D02*
X215790D01*
Y3760092D01*
X219790D01*
G01X218190Y3756225D02*
X215790D01*
G01X223790Y3752092D02*
Y3760092D01*
X226290D01*
X227090Y3759692D01*
X227590Y3759159D01*
X227790Y3758092D01*
X227590Y3757025D01*
X226990Y3756359D01*
X226290Y3755959D01*
X223790D01*
G01X226290D02*
X227790Y3752092D01*
G01X241790D02*
X241190Y3752225D01*
X240590Y3752759D01*
X240190Y3753692D01*
X239990Y3754759D01*
X240190Y3755825D01*
X240590Y3756759D01*
X241190Y3757292D01*
X241790Y3757425D01*
X242390Y3757292D01*
X242990Y3756759D01*
X243390Y3755825D01*
X243490Y3754759D01*
X243390Y3753692D01*
X242990Y3752759D01*
X242390Y3752225D01*
X241790Y3752092D01*
G01X248090D02*
Y3757425D01*
G01Y3756092D02*
X248490Y3756759D01*
X249090Y3757292D01*
X249890Y3757425D01*
X250590Y3757292D01*
X251190Y3756759D01*
X251490Y3755825D01*
Y3752092D01*
G01X263690Y3753158D02*
X264490Y3752492D01*
X265390Y3752092D01*
X266190D01*
X266990Y3752492D01*
X267590Y3753158D01*
X267890Y3754092D01*
X267690Y3755025D01*
X267190Y3755825D01*
X266290Y3756359D01*
X265090Y3756625D01*
X264390Y3757159D01*
X264090Y3758092D01*
X264290Y3759025D01*
X264790Y3759692D01*
X265490Y3760092D01*
X266190D01*
X266890Y3759825D01*
X267490Y3759159D01*
G01X272590Y3760092D02*
X274990D01*
G01X273790D02*
Y3752092D01*
G01X272590D02*
X274990D01*
G01X279790Y3760092D02*
Y3752092D01*
X283790D01*
G01X287590D02*
Y3760092D01*
G01X291390D02*
X287590Y3755158D01*
G01X291990Y3752092D02*
X289290Y3757425D01*
G01X295690Y3753158D02*
X296490Y3752492D01*
X297390Y3752092D01*
X298190D01*
X298990Y3752492D01*
X299590Y3753158D01*
X299890Y3754092D01*
X299690Y3755025D01*
X299190Y3755825D01*
X298290Y3756359D01*
X297090Y3756625D01*
X296390Y3757159D01*
X296090Y3758092D01*
X296290Y3759025D01*
X296790Y3759692D01*
X297490Y3760092D01*
X298190D01*
X298890Y3759825D01*
X299490Y3759159D01*
G01X307990Y3759425D02*
X307390Y3759825D01*
X306690Y3760092D01*
X305890D01*
X304990Y3759692D01*
X304290Y3759025D01*
X303790Y3758225D01*
X303390Y3756892D01*
X303290Y3755692D01*
X303490Y3754492D01*
X303790Y3753692D01*
X304390Y3752892D01*
X305090Y3752359D01*
X305790Y3752092D01*
X306490D01*
X307190Y3752359D01*
X307790Y3752759D01*
X308290Y3753292D01*
G01X311790Y3752092D02*
Y3760092D01*
X314290D01*
X315090Y3759692D01*
X315590Y3759159D01*
X315790Y3758092D01*
X315590Y3757025D01*
X314990Y3756359D01*
X314290Y3755959D01*
X311790D01*
G01X314290D02*
X315790Y3752092D01*
G01X323790D02*
X319790D01*
Y3760092D01*
X323790D01*
G01X322190Y3756225D02*
X319790D01*
G01X331790Y3752092D02*
X327790D01*
Y3760092D01*
X331790D01*
G01X330190Y3756225D02*
X327790D01*
G01X335490Y3752092D02*
Y3760092D01*
X340090Y3752092D01*
Y3760092D01*
G01X353790D02*
Y3752092D01*
G01X351490Y3760092D02*
X356090D01*
G01X361790Y3752092D02*
X360990Y3752225D01*
X360290Y3752759D01*
X359690Y3753559D01*
X359290Y3754492D01*
X359090Y3755559D01*
Y3756625D01*
X359290Y3757692D01*
X359690Y3758625D01*
X360290Y3759425D01*
X360990Y3759959D01*
X361790Y3760092D01*
X362590Y3759959D01*
X363290Y3759425D01*
X363890Y3758625D01*
X364290Y3757692D01*
X364490Y3756625D01*
Y3755559D01*
X364290Y3754492D01*
X363890Y3753559D01*
X363290Y3752759D01*
X362590Y3752225D01*
X361790Y3752092D01*
G01X367790D02*
Y3760092D01*
X370190D01*
X370990Y3759692D01*
X371590Y3758759D01*
X371790Y3757692D01*
X371590Y3756625D01*
X371090Y3755825D01*
X370190Y3755425D01*
X367790D01*
G01X383690Y3753158D02*
X384490Y3752492D01*
X385390Y3752092D01*
X386190D01*
X386990Y3752492D01*
X387590Y3753158D01*
X387890Y3754092D01*
X387690Y3755025D01*
X387190Y3755825D01*
X386290Y3756359D01*
X385090Y3756625D01*
X384390Y3757159D01*
X384090Y3758092D01*
X384290Y3759025D01*
X384790Y3759692D01*
X385490Y3760092D01*
X386190D01*
X386890Y3759825D01*
X387490Y3759159D01*
G01X392590Y3760092D02*
X394990D01*
G01X393790D02*
Y3752092D01*
G01X392590D02*
X394990D01*
G01X399590D02*
Y3760092D01*
X401590D01*
X402390Y3759692D01*
X402990Y3759159D01*
X403490Y3758359D01*
X403890Y3757425D01*
X403990Y3756092D01*
X403890Y3754759D01*
X403490Y3753825D01*
X402990Y3753025D01*
X402390Y3752492D01*
X401590Y3752092D01*
X399590D01*
G01X411790D02*
X407790D01*
Y3760092D01*
X411790D01*
G01X410190Y3756225D02*
X407790D01*
G01X-28210Y3782092D02*
X-32210D01*
Y3790092D01*
X-28210D01*
G01X-29810Y3786225D02*
X-32210D01*
G01X-22210Y3781825D02*
X-22410Y3781959D01*
Y3782225D01*
X-22210Y3782359D01*
X-22010Y3782225D01*
Y3781959D01*
X-22210Y3781825D01*
G01X-16210Y3782092D02*
Y3790092D01*
X-13810D01*
X-13010Y3789692D01*
X-12410Y3788759D01*
X-12210Y3787692D01*
X-12410Y3786625D01*
X-12910Y3785825D01*
X-13810Y3785425D01*
X-16210D01*
G01X-8210Y3782092D02*
Y3790092D01*
X-5710D01*
X-4910Y3789692D01*
X-4410Y3789159D01*
X-4210Y3788092D01*
X-4410Y3787025D01*
X-5010Y3786359D01*
X-5710Y3785959D01*
X-8210D01*
G01X-5710D02*
X-4210Y3782092D01*
G01X1790D02*
X990Y3782225D01*
X290Y3782759D01*
X-310Y3783559D01*
X-710Y3784492D01*
X-910Y3785559D01*
Y3786625D01*
X-710Y3787692D01*
X-310Y3788625D01*
X290Y3789425D01*
X990Y3789959D01*
X1790Y3790092D01*
X2590Y3789959D01*
X3290Y3789425D01*
X3890Y3788625D01*
X4290Y3787692D01*
X4490Y3786625D01*
Y3785559D01*
X4290Y3784492D01*
X3890Y3783559D01*
X3290Y3782759D01*
X2590Y3782225D01*
X1790Y3782092D01*
G01X7290Y3790092D02*
X9790Y3782092D01*
X12290Y3790092D01*
G01X16590D02*
X18990D01*
G01X17790D02*
Y3782092D01*
G01X16590D02*
X18990D01*
G01X23590D02*
Y3790092D01*
X25590D01*
X26390Y3789692D01*
X26990Y3789159D01*
X27490Y3788359D01*
X27890Y3787425D01*
X27990Y3786092D01*
X27890Y3784759D01*
X27490Y3783825D01*
X26990Y3783025D01*
X26390Y3782492D01*
X25590Y3782092D01*
X23590D01*
G01X35790D02*
X31790D01*
Y3790092D01*
X35790D01*
G01X34190Y3786225D02*
X31790D01*
G01X47790Y3782092D02*
Y3790092D01*
X50190D01*
X50990Y3789692D01*
X51590Y3788759D01*
X51790Y3787692D01*
X51590Y3786625D01*
X51090Y3785825D01*
X50190Y3785425D01*
X47790D01*
G01X59990Y3789425D02*
X59390Y3789825D01*
X58690Y3790092D01*
X57890D01*
X56990Y3789692D01*
X56290Y3789025D01*
X55790Y3788225D01*
X55390Y3786892D01*
X55290Y3785692D01*
X55490Y3784492D01*
X55790Y3783692D01*
X56390Y3782892D01*
X57090Y3782359D01*
X57790Y3782092D01*
X58490D01*
X59190Y3782359D01*
X59790Y3782759D01*
X60290Y3783292D01*
G01X66590Y3786359D02*
X66990Y3786759D01*
X67290Y3787425D01*
X67490Y3788359D01*
X67290Y3789159D01*
X66890Y3789692D01*
X66190Y3790092D01*
X63490D01*
Y3782092D01*
X66790D01*
X67490Y3782625D01*
X67890Y3783425D01*
X68090Y3784359D01*
X67890Y3785292D01*
X67290Y3786092D01*
X66590Y3786359D01*
X63490D01*
G01X79890Y3782092D02*
Y3790092D01*
X83690D01*
G01X82290Y3786225D02*
X79890D01*
G01X88590Y3790092D02*
X90990D01*
G01X89790D02*
Y3782092D01*
G01X88590D02*
X90990D01*
G01X95790Y3790092D02*
Y3782092D01*
X99790D01*
G01X103190D02*
Y3790092D01*
X105790Y3783425D01*
X108390Y3790092D01*
Y3782092D01*
G01X-32110Y3767092D02*
Y3775092D01*
X-28310D01*
G01X-29710Y3771225D02*
X-32110D01*
G01X-22210Y3766825D02*
X-22410Y3766959D01*
Y3767225D01*
X-22210Y3767359D01*
X-22010Y3767225D01*
Y3766959D01*
X-22210Y3766825D01*
G01X-16510Y3767092D02*
Y3775092D01*
X-11910Y3767092D01*
Y3775092D01*
G01X-4210Y3767092D02*
X-8210D01*
Y3775092D01*
X-4210D01*
G01X-5810Y3771225D02*
X-8210D01*
G01X3790Y3767092D02*
X-210D01*
Y3775092D01*
X3790D01*
G01X2190Y3771225D02*
X-210D01*
G01X7590Y3767092D02*
Y3775092D01*
X9590D01*
X10390Y3774692D01*
X10990Y3774159D01*
X11490Y3773359D01*
X11890Y3772425D01*
X11990Y3771092D01*
X11890Y3769759D01*
X11490Y3768825D01*
X10990Y3768025D01*
X10390Y3767492D01*
X9590Y3767092D01*
X7590D01*
G01X23790D02*
Y3775092D01*
X26190D01*
X26990Y3774692D01*
X27590Y3773759D01*
X27790Y3772692D01*
X27590Y3771625D01*
X27090Y3770825D01*
X26190Y3770425D01*
X23790D01*
G01X35990Y3774425D02*
X35390Y3774825D01*
X34690Y3775092D01*
X33890D01*
X32990Y3774692D01*
X32290Y3774025D01*
X31790Y3773225D01*
X31390Y3771892D01*
X31290Y3770692D01*
X31490Y3769492D01*
X31790Y3768692D01*
X32390Y3767892D01*
X33090Y3767359D01*
X33790Y3767092D01*
X34490D01*
X35190Y3767359D01*
X35790Y3767759D01*
X36290Y3768292D01*
G01X42590Y3771359D02*
X42990Y3771759D01*
X43290Y3772425D01*
X43490Y3773359D01*
X43290Y3774159D01*
X42890Y3774692D01*
X42190Y3775092D01*
X39490D01*
Y3767092D01*
X42790D01*
X43490Y3767625D01*
X43890Y3768425D01*
X44090Y3769359D01*
X43890Y3770292D01*
X43290Y3771092D01*
X42590Y3771359D01*
X39490D01*
G01X55190Y3767092D02*
Y3775092D01*
X57790Y3768425D01*
X60390Y3775092D01*
Y3767092D01*
G01X63290D02*
X65790Y3775092D01*
X68290Y3767092D01*
G01X67390Y3769892D02*
X64190D01*
G01X71590Y3767092D02*
Y3775092D01*
G01X75390D02*
X71590Y3770158D01*
G01X75990Y3767092D02*
X73290Y3772425D01*
G01X83790Y3767092D02*
X79790D01*
Y3775092D01*
X83790D01*
G01X82190Y3771225D02*
X79790D01*
G01X87790Y3767092D02*
Y3775092D01*
X90290D01*
X91090Y3774692D01*
X91590Y3774159D01*
X91790Y3773092D01*
X91590Y3772025D01*
X90990Y3771359D01*
X90290Y3770959D01*
X87790D01*
G01X90290D02*
X91790Y3767092D01*
G01X103790Y3775092D02*
Y3767092D01*
X107790D01*
G01X113790D02*
X112990Y3767225D01*
X112290Y3767759D01*
X111690Y3768559D01*
X111290Y3769492D01*
X111090Y3770559D01*
Y3771625D01*
X111290Y3772692D01*
X111690Y3773625D01*
X112290Y3774425D01*
X112990Y3774959D01*
X113790Y3775092D01*
X114590Y3774959D01*
X115290Y3774425D01*
X115890Y3773625D01*
X116290Y3772692D01*
X116490Y3771625D01*
Y3770559D01*
X116290Y3769492D01*
X115890Y3768559D01*
X115290Y3767759D01*
X114590Y3767225D01*
X113790Y3767092D01*
G01X122390Y3771092D02*
X124390D01*
Y3768692D01*
X123790Y3767892D01*
X123090Y3767359D01*
X122090Y3767092D01*
X121090Y3767359D01*
X120390Y3767892D01*
X119790Y3768692D01*
X119390Y3769625D01*
X119190Y3770692D01*
Y3771625D01*
X119390Y3772425D01*
X119790Y3773359D01*
X120390Y3774159D01*
X120990Y3774692D01*
X121790Y3775092D01*
X122490D01*
X123290Y3774825D01*
X123890Y3774292D01*
G01X129790Y3767092D02*
X128990Y3767225D01*
X128290Y3767759D01*
X127690Y3768559D01*
X127290Y3769492D01*
X127090Y3770559D01*
Y3771625D01*
X127290Y3772692D01*
X127690Y3773625D01*
X128290Y3774425D01*
X128990Y3774959D01*
X129790Y3775092D01*
X130590Y3774959D01*
X131290Y3774425D01*
X131890Y3773625D01*
X132290Y3772692D01*
X132490Y3771625D01*
Y3770559D01*
X132290Y3769492D01*
X131890Y3768559D01*
X131290Y3767759D01*
X130590Y3767225D01*
X129790Y3767092D01*
G01X143290D02*
X145790Y3775092D01*
X148290Y3767092D01*
G01X147390Y3769892D02*
X144190D01*
G01X151490Y3767092D02*
Y3775092D01*
X156090Y3767092D01*
Y3775092D01*
G01X159590Y3767092D02*
Y3775092D01*
X161590D01*
X162390Y3774692D01*
X162990Y3774159D01*
X163490Y3773359D01*
X163890Y3772425D01*
X163990Y3771092D01*
X163890Y3769759D01*
X163490Y3768825D01*
X162990Y3768025D01*
X162390Y3767492D01*
X161590Y3767092D01*
X159590D01*
G01X175590D02*
Y3775092D01*
X177590D01*
X178390Y3774692D01*
X178990Y3774159D01*
X179490Y3773359D01*
X179890Y3772425D01*
X179990Y3771092D01*
X179890Y3769759D01*
X179490Y3768825D01*
X178990Y3768025D01*
X178390Y3767492D01*
X177590Y3767092D01*
X175590D01*
G01X183290D02*
X185790Y3775092D01*
X188290Y3767092D01*
G01X187390Y3769892D02*
X184190D01*
G01X193790Y3775092D02*
Y3767092D01*
G01X191490Y3775092D02*
X196090D01*
G01X203790Y3767092D02*
X199790D01*
Y3775092D01*
X203790D01*
G01X202190Y3771225D02*
X199790D01*
G01X219990Y3774425D02*
X219390Y3774825D01*
X218690Y3775092D01*
X217890D01*
X216990Y3774692D01*
X216290Y3774025D01*
X215790Y3773225D01*
X215390Y3771892D01*
X215290Y3770692D01*
X215490Y3769492D01*
X215790Y3768692D01*
X216390Y3767892D01*
X217090Y3767359D01*
X217790Y3767092D01*
X218490D01*
X219190Y3767359D01*
X219790Y3767759D01*
X220290Y3768292D01*
G01X225790Y3767092D02*
X224990Y3767225D01*
X224290Y3767759D01*
X223690Y3768559D01*
X223290Y3769492D01*
X223090Y3770559D01*
Y3771625D01*
X223290Y3772692D01*
X223690Y3773625D01*
X224290Y3774425D01*
X224990Y3774959D01*
X225790Y3775092D01*
X226590Y3774959D01*
X227290Y3774425D01*
X227890Y3773625D01*
X228290Y3772692D01*
X228490Y3771625D01*
Y3770559D01*
X228290Y3769492D01*
X227890Y3768559D01*
X227290Y3767759D01*
X226590Y3767225D01*
X225790Y3767092D01*
G01X231590D02*
Y3775092D01*
X233590D01*
X234390Y3774692D01*
X234990Y3774159D01*
X235490Y3773359D01*
X235890Y3772425D01*
X235990Y3771092D01*
X235890Y3769759D01*
X235490Y3768825D01*
X234990Y3768025D01*
X234390Y3767492D01*
X233590Y3767092D01*
X231590D01*
G01X243790D02*
X239790D01*
Y3775092D01*
X243790D01*
G01X242190Y3771225D02*
X239790D01*
G01X257290Y3764425D02*
X256290Y3765759D01*
X255790Y3767092D01*
Y3772425D01*
X256290Y3773759D01*
X257290Y3775092D01*
G01X262790D02*
X264190Y3767092D01*
X265790Y3775092D01*
X267390Y3767092D01*
X268790Y3775092D01*
G01X270790D02*
X272190Y3767092D01*
X273790Y3775092D01*
X275390Y3767092D01*
X276790Y3775092D01*
G01X281790Y3767092D02*
Y3770692D01*
X279790Y3775092D01*
G01X283790D02*
X281790Y3770692D01*
G01X289790Y3767092D02*
Y3770692D01*
X287790Y3775092D01*
G01X291790D02*
X289790Y3770692D01*
G01X298290Y3764425D02*
X299290Y3765759D01*
X299790Y3767092D01*
Y3772425D01*
X299290Y3773759D01*
X298290Y3775092D01*
G01X313790Y3767092D02*
X313190Y3767225D01*
X312590Y3767759D01*
X312190Y3768692D01*
X311990Y3769759D01*
X312190Y3770825D01*
X312590Y3771759D01*
X313190Y3772292D01*
X313790Y3772425D01*
X314390Y3772292D01*
X314990Y3771759D01*
X315390Y3770825D01*
X315490Y3769759D01*
X315390Y3768692D01*
X314990Y3767759D01*
X314390Y3767225D01*
X313790Y3767092D01*
G01X320090D02*
Y3772425D01*
G01Y3771092D02*
X320490Y3771759D01*
X321090Y3772292D01*
X321890Y3772425D01*
X322590Y3772292D01*
X323190Y3771759D01*
X323490Y3770825D01*
Y3767092D01*
G01X335690Y3768158D02*
X336490Y3767492D01*
X337390Y3767092D01*
X338190D01*
X338990Y3767492D01*
X339590Y3768158D01*
X339890Y3769092D01*
X339690Y3770025D01*
X339190Y3770825D01*
X338290Y3771359D01*
X337090Y3771625D01*
X336390Y3772159D01*
X336090Y3773092D01*
X336290Y3774025D01*
X336790Y3774692D01*
X337490Y3775092D01*
X338190D01*
X338890Y3774825D01*
X339490Y3774159D01*
G01X344590Y3775092D02*
X346990D01*
G01X345790D02*
Y3767092D01*
G01X344590D02*
X346990D01*
G01X351790Y3775092D02*
Y3767092D01*
X355790D01*
G01X359590D02*
Y3775092D01*
G01X363390D02*
X359590Y3770158D01*
G01X363990Y3767092D02*
X361290Y3772425D01*
G01X367690Y3768158D02*
X368490Y3767492D01*
X369390Y3767092D01*
X370190D01*
X370990Y3767492D01*
X371590Y3768158D01*
X371890Y3769092D01*
X371690Y3770025D01*
X371190Y3770825D01*
X370290Y3771359D01*
X369090Y3771625D01*
X368390Y3772159D01*
X368090Y3773092D01*
X368290Y3774025D01*
X368790Y3774692D01*
X369490Y3775092D01*
X370190D01*
X370890Y3774825D01*
X371490Y3774159D01*
G01X379990Y3774425D02*
X379390Y3774825D01*
X378690Y3775092D01*
X377890D01*
X376990Y3774692D01*
X376290Y3774025D01*
X375790Y3773225D01*
X375390Y3771892D01*
X375290Y3770692D01*
X375490Y3769492D01*
X375790Y3768692D01*
X376390Y3767892D01*
X377090Y3767359D01*
X377790Y3767092D01*
X378490D01*
X379190Y3767359D01*
X379790Y3767759D01*
X380290Y3768292D01*
G01X383790Y3767092D02*
Y3775092D01*
X386290D01*
X387090Y3774692D01*
X387590Y3774159D01*
X387790Y3773092D01*
X387590Y3772025D01*
X386990Y3771359D01*
X386290Y3770959D01*
X383790D01*
G01X386290D02*
X387790Y3767092D01*
G01X395790D02*
X391790D01*
Y3775092D01*
X395790D01*
G01X394190Y3771225D02*
X391790D01*
G01X403790Y3767092D02*
X399790D01*
Y3775092D01*
X403790D01*
G01X402190Y3771225D02*
X399790D01*
G01X407490Y3767092D02*
Y3775092D01*
X412090Y3767092D01*
Y3775092D01*
G01X425790D02*
Y3767092D01*
G01X423490Y3775092D02*
X428090D01*
G01X433790Y3767092D02*
X432990Y3767225D01*
X432290Y3767759D01*
X431690Y3768559D01*
X431290Y3769492D01*
X431090Y3770559D01*
Y3771625D01*
X431290Y3772692D01*
X431690Y3773625D01*
X432290Y3774425D01*
X432990Y3774959D01*
X433790Y3775092D01*
X434590Y3774959D01*
X435290Y3774425D01*
X435890Y3773625D01*
X436290Y3772692D01*
X436490Y3771625D01*
Y3770559D01*
X436290Y3769492D01*
X435890Y3768559D01*
X435290Y3767759D01*
X434590Y3767225D01*
X433790Y3767092D01*
G01X439790D02*
Y3775092D01*
X442190D01*
X442990Y3774692D01*
X443590Y3773759D01*
X443790Y3772692D01*
X443590Y3771625D01*
X443090Y3770825D01*
X442190Y3770425D01*
X439790D01*
G01X455690Y3768158D02*
X456490Y3767492D01*
X457390Y3767092D01*
X458190D01*
X458990Y3767492D01*
X459590Y3768158D01*
X459890Y3769092D01*
X459690Y3770025D01*
X459190Y3770825D01*
X458290Y3771359D01*
X457090Y3771625D01*
X456390Y3772159D01*
X456090Y3773092D01*
X456290Y3774025D01*
X456790Y3774692D01*
X457490Y3775092D01*
X458190D01*
X458890Y3774825D01*
X459490Y3774159D01*
G01X464590Y3775092D02*
X466990D01*
G01X465790D02*
Y3767092D01*
G01X464590D02*
X466990D01*
G01X471590D02*
Y3775092D01*
X473590D01*
X474390Y3774692D01*
X474990Y3774159D01*
X475490Y3773359D01*
X475890Y3772425D01*
X475990Y3771092D01*
X475890Y3769759D01*
X475490Y3768825D01*
X474990Y3768025D01*
X474390Y3767492D01*
X473590Y3767092D01*
X471590D01*
G01X483790D02*
X479790D01*
Y3775092D01*
X483790D01*
G01X482190Y3771225D02*
X479790D01*
G01X500790Y3764425D02*
X495790Y3772425D01*
Y3773759D01*
X496790Y3775092D01*
X497790D01*
X498790Y3773759D01*
Y3772425D01*
X497790Y3771092D01*
X495790Y3769759D01*
X494790Y3768425D01*
Y3765759D01*
X495790Y3764425D01*
X498790D01*
X500790Y3767092D01*
G01X514590Y3771359D02*
X514990Y3771759D01*
X515290Y3772425D01*
X515490Y3773359D01*
X515290Y3774159D01*
X514890Y3774692D01*
X514190Y3775092D01*
X511490D01*
Y3767092D01*
X514790D01*
X515490Y3767625D01*
X515890Y3768425D01*
X516090Y3769359D01*
X515890Y3770292D01*
X515290Y3771092D01*
X514590Y3771359D01*
X511490D01*
G01X519790Y3767092D02*
Y3775092D01*
X522290D01*
X523090Y3774692D01*
X523590Y3774159D01*
X523790Y3773092D01*
X523590Y3772025D01*
X522990Y3771359D01*
X522290Y3770959D01*
X519790D01*
G01X522290D02*
X523790Y3767092D01*
G01X531790D02*
X527790D01*
Y3775092D01*
X531790D01*
G01X530190Y3771225D02*
X527790D01*
G01X535290Y3767092D02*
X537790Y3775092D01*
X540290Y3767092D01*
G01X539390Y3769892D02*
X536190D01*
G01X543590Y3767092D02*
Y3775092D01*
G01X547390D02*
X543590Y3770158D01*
G01X547990Y3767092D02*
X545290Y3772425D01*
G01X551290Y3767092D02*
X553790Y3775092D01*
X556290Y3767092D01*
G01X555390Y3769892D02*
X552190D01*
G01X558790Y3775092D02*
X560190Y3767092D01*
X561790Y3775092D01*
X563390Y3767092D01*
X564790Y3775092D01*
G01X567290Y3767092D02*
X569790Y3775092D01*
X572290Y3767092D01*
G01X571390Y3769892D02*
X568190D01*
G01X577790Y3767092D02*
Y3770692D01*
X575790Y3775092D01*
G01X579790D02*
X577790Y3770692D01*
G01X-32410Y3797092D02*
Y3805092D01*
X-30410D01*
X-29610Y3804692D01*
X-29010Y3804159D01*
X-28510Y3803359D01*
X-28110Y3802425D01*
X-28010Y3801092D01*
X-28110Y3799759D01*
X-28510Y3798825D01*
X-29010Y3798025D01*
X-29610Y3797492D01*
X-30410Y3797092D01*
X-32410D01*
G01X-22210Y3796825D02*
X-22410Y3796959D01*
Y3797225D01*
X-22210Y3797359D01*
X-22010Y3797225D01*
Y3796959D01*
X-22210Y3796825D01*
G01X-16210Y3797092D02*
Y3805092D01*
X-13810D01*
X-13010Y3804692D01*
X-12410Y3803759D01*
X-12210Y3802692D01*
X-12410Y3801625D01*
X-12910Y3800825D01*
X-13810Y3800425D01*
X-16210D01*
G01X-8210Y3797092D02*
Y3805092D01*
X-5710D01*
X-4910Y3804692D01*
X-4410Y3804159D01*
X-4210Y3803092D01*
X-4410Y3802025D01*
X-5010Y3801359D01*
X-5710Y3800959D01*
X-8210D01*
G01X-5710D02*
X-4210Y3797092D01*
G01X1790D02*
X990Y3797225D01*
X290Y3797759D01*
X-310Y3798559D01*
X-710Y3799492D01*
X-910Y3800559D01*
Y3801625D01*
X-710Y3802692D01*
X-310Y3803625D01*
X290Y3804425D01*
X990Y3804959D01*
X1790Y3805092D01*
X2590Y3804959D01*
X3290Y3804425D01*
X3890Y3803625D01*
X4290Y3802692D01*
X4490Y3801625D01*
Y3800559D01*
X4290Y3799492D01*
X3890Y3798559D01*
X3290Y3797759D01*
X2590Y3797225D01*
X1790Y3797092D01*
G01X7290Y3805092D02*
X9790Y3797092D01*
X12290Y3805092D01*
G01X16590D02*
X18990D01*
G01X17790D02*
Y3797092D01*
G01X16590D02*
X18990D01*
G01X23590D02*
Y3805092D01*
X25590D01*
X26390Y3804692D01*
X26990Y3804159D01*
X27490Y3803359D01*
X27890Y3802425D01*
X27990Y3801092D01*
X27890Y3799759D01*
X27490Y3798825D01*
X26990Y3798025D01*
X26390Y3797492D01*
X25590Y3797092D01*
X23590D01*
G01X35790D02*
X31790D01*
Y3805092D01*
X35790D01*
G01X34190Y3801225D02*
X31790D01*
G01X48590Y3805092D02*
X50990D01*
G01X49790D02*
Y3797092D01*
G01X48590D02*
X50990D01*
G01X55190D02*
Y3805092D01*
X57790Y3798425D01*
X60390Y3805092D01*
Y3797092D01*
G01X63790D02*
Y3805092D01*
X66190D01*
X66990Y3804692D01*
X67590Y3803759D01*
X67790Y3802692D01*
X67590Y3801625D01*
X67090Y3800825D01*
X66190Y3800425D01*
X63790D01*
G01X75790Y3797092D02*
X71790D01*
Y3805092D01*
X75790D01*
G01X74190Y3801225D02*
X71790D01*
G01X79590Y3797092D02*
Y3805092D01*
X81590D01*
X82390Y3804692D01*
X82990Y3804159D01*
X83490Y3803359D01*
X83890Y3802425D01*
X83990Y3801092D01*
X83890Y3799759D01*
X83490Y3798825D01*
X82990Y3798025D01*
X82390Y3797492D01*
X81590Y3797092D01*
X79590D01*
G01X87290D02*
X89790Y3805092D01*
X92290Y3797092D01*
G01X91390Y3799892D02*
X88190D01*
G01X95490Y3797092D02*
Y3805092D01*
X100090Y3797092D01*
Y3805092D01*
G01X107990Y3804425D02*
X107390Y3804825D01*
X106690Y3805092D01*
X105890D01*
X104990Y3804692D01*
X104290Y3804025D01*
X103790Y3803225D01*
X103390Y3801892D01*
X103290Y3800692D01*
X103490Y3799492D01*
X103790Y3798692D01*
X104390Y3797892D01*
X105090Y3797359D01*
X105790Y3797092D01*
X106490D01*
X107190Y3797359D01*
X107790Y3797759D01*
X108290Y3798292D01*
G01X115790Y3797092D02*
X111790D01*
Y3805092D01*
X115790D01*
G01X114190Y3801225D02*
X111790D01*
G01X131990Y3804425D02*
X131390Y3804825D01*
X130690Y3805092D01*
X129890D01*
X128990Y3804692D01*
X128290Y3804025D01*
X127790Y3803225D01*
X127390Y3801892D01*
X127290Y3800692D01*
X127490Y3799492D01*
X127790Y3798692D01*
X128390Y3797892D01*
X129090Y3797359D01*
X129790Y3797092D01*
X130490D01*
X131190Y3797359D01*
X131790Y3797759D01*
X132290Y3798292D01*
G01X137790Y3797092D02*
X136990Y3797225D01*
X136290Y3797759D01*
X135690Y3798559D01*
X135290Y3799492D01*
X135090Y3800559D01*
Y3801625D01*
X135290Y3802692D01*
X135690Y3803625D01*
X136290Y3804425D01*
X136990Y3804959D01*
X137790Y3805092D01*
X138590Y3804959D01*
X139290Y3804425D01*
X139890Y3803625D01*
X140290Y3802692D01*
X140490Y3801625D01*
Y3800559D01*
X140290Y3799492D01*
X139890Y3798559D01*
X139290Y3797759D01*
X138590Y3797225D01*
X137790Y3797092D01*
G01X143590Y3805092D02*
Y3799359D01*
X143990Y3798158D01*
X144790Y3797359D01*
X145790Y3797092D01*
X146790Y3797359D01*
X147590Y3798158D01*
X147990Y3799359D01*
Y3805092D01*
G01X151790Y3797092D02*
Y3805092D01*
X154190D01*
X154990Y3804692D01*
X155590Y3803759D01*
X155790Y3802692D01*
X155590Y3801625D01*
X155090Y3800825D01*
X154190Y3800425D01*
X151790D01*
G01X161790Y3797092D02*
X160990Y3797225D01*
X160290Y3797759D01*
X159690Y3798559D01*
X159290Y3799492D01*
X159090Y3800559D01*
Y3801625D01*
X159290Y3802692D01*
X159690Y3803625D01*
X160290Y3804425D01*
X160990Y3804959D01*
X161790Y3805092D01*
X162590Y3804959D01*
X163290Y3804425D01*
X163890Y3803625D01*
X164290Y3802692D01*
X164490Y3801625D01*
Y3800559D01*
X164290Y3799492D01*
X163890Y3798559D01*
X163290Y3797759D01*
X162590Y3797225D01*
X161790Y3797092D01*
G01X167490D02*
Y3805092D01*
X172090Y3797092D01*
Y3805092D01*
G01X183290Y3797092D02*
X185790Y3805092D01*
X188290Y3797092D01*
G01X187390Y3799892D02*
X184190D01*
G01X191490Y3797092D02*
Y3805092D01*
X196090Y3797092D01*
Y3805092D01*
G01X199590Y3797092D02*
Y3805092D01*
X201590D01*
X202390Y3804692D01*
X202990Y3804159D01*
X203490Y3803359D01*
X203890Y3802425D01*
X203990Y3801092D01*
X203890Y3799759D01*
X203490Y3798825D01*
X202990Y3798025D01*
X202390Y3797492D01*
X201590Y3797092D01*
X199590D01*
G01X215190D02*
Y3805092D01*
X217790Y3798425D01*
X220390Y3805092D01*
Y3797092D01*
G01X227790D02*
X223790D01*
Y3805092D01*
X227790D01*
G01X226190Y3801225D02*
X223790D01*
G01X231290Y3797092D02*
X233790Y3805092D01*
X236290Y3797092D01*
G01X235390Y3799892D02*
X232190D01*
G01X239690Y3798158D02*
X240490Y3797492D01*
X241390Y3797092D01*
X242190D01*
X242990Y3797492D01*
X243590Y3798158D01*
X243890Y3799092D01*
X243690Y3800025D01*
X243190Y3800825D01*
X242290Y3801359D01*
X241090Y3801625D01*
X240390Y3802159D01*
X240090Y3803092D01*
X240290Y3804025D01*
X240790Y3804692D01*
X241490Y3805092D01*
X242190D01*
X242890Y3804825D01*
X243490Y3804159D01*
G01X247590Y3805092D02*
Y3799359D01*
X247990Y3798158D01*
X248790Y3797359D01*
X249790Y3797092D01*
X250790Y3797359D01*
X251590Y3798158D01*
X251990Y3799359D01*
Y3805092D01*
G01X255790Y3797092D02*
Y3805092D01*
X258290D01*
X259090Y3804692D01*
X259590Y3804159D01*
X259790Y3803092D01*
X259590Y3802025D01*
X258990Y3801359D01*
X258290Y3800959D01*
X255790D01*
G01X258290D02*
X259790Y3797092D01*
G01X267790D02*
X263790D01*
Y3805092D01*
X267790D01*
G01X266190Y3801225D02*
X263790D01*
G01X271190Y3797092D02*
Y3805092D01*
X273790Y3798425D01*
X276390Y3805092D01*
Y3797092D01*
G01X283790D02*
X279790D01*
Y3805092D01*
X283790D01*
G01X282190Y3801225D02*
X279790D01*
G01X287490Y3797092D02*
Y3805092D01*
X292090Y3797092D01*
Y3805092D01*
G01X297790D02*
Y3797092D01*
G01X295490Y3805092D02*
X300090D01*
G01X311790Y3797092D02*
Y3805092D01*
X314290D01*
X315090Y3804692D01*
X315590Y3804159D01*
X315790Y3803092D01*
X315590Y3802025D01*
X314990Y3801359D01*
X314290Y3800959D01*
X311790D01*
G01X314290D02*
X315790Y3797092D01*
G01X323790D02*
X319790D01*
Y3805092D01*
X323790D01*
G01X322190Y3801225D02*
X319790D01*
G01X327790Y3797092D02*
Y3805092D01*
X330190D01*
X330990Y3804692D01*
X331590Y3803759D01*
X331790Y3802692D01*
X331590Y3801625D01*
X331090Y3800825D01*
X330190Y3800425D01*
X327790D01*
G01X337790Y3797092D02*
X336990Y3797225D01*
X336290Y3797759D01*
X335690Y3798559D01*
X335290Y3799492D01*
X335090Y3800559D01*
Y3801625D01*
X335290Y3802692D01*
X335690Y3803625D01*
X336290Y3804425D01*
X336990Y3804959D01*
X337790Y3805092D01*
X338590Y3804959D01*
X339290Y3804425D01*
X339890Y3803625D01*
X340290Y3802692D01*
X340490Y3801625D01*
Y3800559D01*
X340290Y3799492D01*
X339890Y3798559D01*
X339290Y3797759D01*
X338590Y3797225D01*
X337790Y3797092D01*
G01X343790D02*
Y3805092D01*
X346290D01*
X347090Y3804692D01*
X347590Y3804159D01*
X347790Y3803092D01*
X347590Y3802025D01*
X346990Y3801359D01*
X346290Y3800959D01*
X343790D01*
G01X346290D02*
X347790Y3797092D01*
G01X353790Y3805092D02*
Y3797092D01*
G01X351490Y3805092D02*
X356090D01*
G01X-28010Y3819425D02*
X-28610Y3819825D01*
X-29310Y3820092D01*
X-30110D01*
X-31010Y3819692D01*
X-31710Y3819025D01*
X-32210Y3818225D01*
X-32610Y3816892D01*
X-32710Y3815692D01*
X-32510Y3814492D01*
X-32210Y3813692D01*
X-31610Y3812892D01*
X-30910Y3812359D01*
X-30210Y3812092D01*
X-29510D01*
X-28810Y3812359D01*
X-28210Y3812759D01*
X-27710Y3813292D01*
G01X-22210Y3811825D02*
X-22410Y3811959D01*
Y3812225D01*
X-22210Y3812359D01*
X-22010Y3812225D01*
Y3811959D01*
X-22210Y3811825D01*
G01X-16510Y3812092D02*
Y3820092D01*
X-11910Y3812092D01*
Y3820092D01*
G01X-6210Y3812092D02*
X-7010Y3812225D01*
X-7710Y3812759D01*
X-8310Y3813559D01*
X-8710Y3814492D01*
X-8910Y3815559D01*
Y3816625D01*
X-8710Y3817692D01*
X-8310Y3818625D01*
X-7710Y3819425D01*
X-7010Y3819959D01*
X-6210Y3820092D01*
X-5410Y3819959D01*
X-4710Y3819425D01*
X-4110Y3818625D01*
X-3710Y3817692D01*
X-3510Y3816625D01*
Y3815559D01*
X-3710Y3814492D01*
X-4110Y3813559D01*
X-4710Y3812759D01*
X-5410Y3812225D01*
X-6210Y3812092D01*
G01X7490D02*
Y3820092D01*
X12090Y3812092D01*
Y3820092D01*
G01X19790Y3812092D02*
X15790D01*
Y3820092D01*
X19790D01*
G01X18190Y3816225D02*
X15790D01*
G01X27790Y3812092D02*
X23790D01*
Y3820092D01*
X27790D01*
G01X26190Y3816225D02*
X23790D01*
G01X31590Y3812092D02*
Y3820092D01*
X33590D01*
X34390Y3819692D01*
X34990Y3819159D01*
X35490Y3818359D01*
X35890Y3817425D01*
X35990Y3816092D01*
X35890Y3814759D01*
X35490Y3813825D01*
X34990Y3813025D01*
X34390Y3812492D01*
X33590Y3812092D01*
X31590D01*
G01X49790Y3820092D02*
Y3812092D01*
G01X47490Y3820092D02*
X52090D01*
G01X57790Y3812092D02*
X56990Y3812225D01*
X56290Y3812759D01*
X55690Y3813559D01*
X55290Y3814492D01*
X55090Y3815559D01*
Y3816625D01*
X55290Y3817692D01*
X55690Y3818625D01*
X56290Y3819425D01*
X56990Y3819959D01*
X57790Y3820092D01*
X58590Y3819959D01*
X59290Y3819425D01*
X59890Y3818625D01*
X60290Y3817692D01*
X60490Y3816625D01*
Y3815559D01*
X60290Y3814492D01*
X59890Y3813559D01*
X59290Y3812759D01*
X58590Y3812225D01*
X57790Y3812092D01*
G01X71790D02*
Y3820092D01*
X74190D01*
X74990Y3819692D01*
X75590Y3818759D01*
X75790Y3817692D01*
X75590Y3816625D01*
X75090Y3815825D01*
X74190Y3815425D01*
X71790D01*
G01X79790Y3820092D02*
Y3812092D01*
X83790D01*
G01X87590Y3820092D02*
Y3814359D01*
X87990Y3813158D01*
X88790Y3812359D01*
X89790Y3812092D01*
X90790Y3812359D01*
X91590Y3813158D01*
X91990Y3814359D01*
Y3820092D01*
G01X98390Y3816092D02*
X100390D01*
Y3813692D01*
X99790Y3812892D01*
X99090Y3812359D01*
X98090Y3812092D01*
X97090Y3812359D01*
X96390Y3812892D01*
X95790Y3813692D01*
X95390Y3814625D01*
X95190Y3815692D01*
Y3816625D01*
X95390Y3817425D01*
X95790Y3818359D01*
X96390Y3819159D01*
X96990Y3819692D01*
X97790Y3820092D01*
X98490D01*
X99290Y3819825D01*
X99890Y3819292D01*
G01X113790Y3812092D02*
X114490Y3812225D01*
X115290Y3812625D01*
X115790Y3813292D01*
X115990Y3814225D01*
X115790Y3815158D01*
X115190Y3815959D01*
X114290Y3816359D01*
X113290D01*
X112690Y3816625D01*
X112190Y3817292D01*
X111990Y3818225D01*
X112290Y3819159D01*
X112990Y3819825D01*
X113790Y3820092D01*
X114590Y3819825D01*
X115290Y3819159D01*
X115590Y3818225D01*
X115390Y3817292D01*
X114890Y3816625D01*
X114290Y3816359D01*
X113290D01*
X112390Y3815959D01*
X111790Y3815158D01*
X111590Y3814225D01*
X111790Y3813292D01*
X112290Y3812625D01*
X113090Y3812225D01*
X113790Y3812092D01*
G01X127690D02*
Y3820092D01*
G01X131890D02*
Y3812092D01*
G01Y3816092D02*
X127690D01*
G01X137790Y3812092D02*
X136990Y3812225D01*
X136290Y3812759D01*
X135690Y3813559D01*
X135290Y3814492D01*
X135090Y3815559D01*
Y3816625D01*
X135290Y3817692D01*
X135690Y3818625D01*
X136290Y3819425D01*
X136990Y3819959D01*
X137790Y3820092D01*
X138590Y3819959D01*
X139290Y3819425D01*
X139890Y3818625D01*
X140290Y3817692D01*
X140490Y3816625D01*
Y3815559D01*
X140290Y3814492D01*
X139890Y3813559D01*
X139290Y3812759D01*
X138590Y3812225D01*
X137790Y3812092D01*
G01X143790Y3820092D02*
Y3812092D01*
X147790D01*
G01X155790D02*
X151790D01*
Y3820092D01*
X155790D01*
G01X154190Y3816225D02*
X151790D01*
G01X159690Y3813158D02*
X160490Y3812492D01*
X161390Y3812092D01*
X162190D01*
X162990Y3812492D01*
X163590Y3813158D01*
X163890Y3814092D01*
X163690Y3815025D01*
X163190Y3815825D01*
X162290Y3816359D01*
X161090Y3816625D01*
X160390Y3817159D01*
X160090Y3818092D01*
X160290Y3819025D01*
X160790Y3819692D01*
X161490Y3820092D01*
X162190D01*
X162890Y3819825D01*
X163490Y3819159D01*
G01X175690Y3813158D02*
X176490Y3812492D01*
X177390Y3812092D01*
X178190D01*
X178990Y3812492D01*
X179590Y3813158D01*
X179890Y3814092D01*
X179690Y3815025D01*
X179190Y3815825D01*
X178290Y3816359D01*
X177090Y3816625D01*
X176390Y3817159D01*
X176090Y3818092D01*
X176290Y3819025D01*
X176790Y3819692D01*
X177490Y3820092D01*
X178190D01*
X178890Y3819825D01*
X179490Y3819159D01*
G01X183590Y3820092D02*
Y3814359D01*
X183990Y3813158D01*
X184790Y3812359D01*
X185790Y3812092D01*
X186790Y3812359D01*
X187590Y3813158D01*
X187990Y3814359D01*
Y3820092D01*
G01X191790Y3812092D02*
Y3820092D01*
X194290D01*
X195090Y3819692D01*
X195590Y3819159D01*
X195790Y3818092D01*
X195590Y3817025D01*
X194990Y3816359D01*
X194290Y3815959D01*
X191790D01*
G01X194290D02*
X195790Y3812092D01*
G01X199790D02*
Y3820092D01*
X202290D01*
X203090Y3819692D01*
X203590Y3819159D01*
X203790Y3818092D01*
X203590Y3817025D01*
X202990Y3816359D01*
X202290Y3815959D01*
X199790D01*
G01X202290D02*
X203790Y3812092D01*
G01X209790D02*
X208990Y3812225D01*
X208290Y3812759D01*
X207690Y3813559D01*
X207290Y3814492D01*
X207090Y3815559D01*
Y3816625D01*
X207290Y3817692D01*
X207690Y3818625D01*
X208290Y3819425D01*
X208990Y3819959D01*
X209790Y3820092D01*
X210590Y3819959D01*
X211290Y3819425D01*
X211890Y3818625D01*
X212290Y3817692D01*
X212490Y3816625D01*
Y3815559D01*
X212290Y3814492D01*
X211890Y3813559D01*
X211290Y3812759D01*
X210590Y3812225D01*
X209790Y3812092D01*
G01X215590Y3820092D02*
Y3814359D01*
X215990Y3813158D01*
X216790Y3812359D01*
X217790Y3812092D01*
X218790Y3812359D01*
X219590Y3813158D01*
X219990Y3814359D01*
Y3820092D01*
G01X223490Y3812092D02*
Y3820092D01*
X228090Y3812092D01*
Y3820092D01*
G01X231590Y3812092D02*
Y3820092D01*
X233590D01*
X234390Y3819692D01*
X234990Y3819159D01*
X235490Y3818359D01*
X235890Y3817425D01*
X235990Y3816092D01*
X235890Y3814759D01*
X235490Y3813825D01*
X234990Y3813025D01*
X234390Y3812492D01*
X233590Y3812092D01*
X231590D01*
G01X240590Y3820092D02*
X242990D01*
G01X241790D02*
Y3812092D01*
G01X240590D02*
X242990D01*
G01X247490D02*
Y3820092D01*
X252090Y3812092D01*
Y3820092D01*
G01X258390Y3816092D02*
X260390D01*
Y3813692D01*
X259790Y3812892D01*
X259090Y3812359D01*
X258090Y3812092D01*
X257090Y3812359D01*
X256390Y3812892D01*
X255790Y3813692D01*
X255390Y3814625D01*
X255190Y3815692D01*
Y3816625D01*
X255390Y3817425D01*
X255790Y3818359D01*
X256390Y3819159D01*
X256990Y3819692D01*
X257790Y3820092D01*
X258490D01*
X259290Y3819825D01*
X259890Y3819292D01*
G01X271690Y3813158D02*
X272490Y3812492D01*
X273390Y3812092D01*
X274190D01*
X274990Y3812492D01*
X275590Y3813158D01*
X275890Y3814092D01*
X275690Y3815025D01*
X275190Y3815825D01*
X274290Y3816359D01*
X273090Y3816625D01*
X272390Y3817159D01*
X272090Y3818092D01*
X272290Y3819025D01*
X272790Y3819692D01*
X273490Y3820092D01*
X274190D01*
X274890Y3819825D01*
X275490Y3819159D01*
G01X283990Y3819425D02*
X283390Y3819825D01*
X282690Y3820092D01*
X281890D01*
X280990Y3819692D01*
X280290Y3819025D01*
X279790Y3818225D01*
X279390Y3816892D01*
X279290Y3815692D01*
X279490Y3814492D01*
X279790Y3813692D01*
X280390Y3812892D01*
X281090Y3812359D01*
X281790Y3812092D01*
X282490D01*
X283190Y3812359D01*
X283790Y3812759D01*
X284290Y3813292D01*
G01X287790Y3812092D02*
Y3820092D01*
X290290D01*
X291090Y3819692D01*
X291590Y3819159D01*
X291790Y3818092D01*
X291590Y3817025D01*
X290990Y3816359D01*
X290290Y3815959D01*
X287790D01*
G01X290290D02*
X291790Y3812092D01*
G01X299790D02*
X295790D01*
Y3820092D01*
X299790D01*
G01X298190Y3816225D02*
X295790D01*
G01X302790Y3820092D02*
X304190Y3812092D01*
X305790Y3820092D01*
X307390Y3812092D01*
X308790Y3820092D01*
G01X313790Y3811825D02*
X313590Y3811959D01*
Y3812225D01*
X313790Y3812359D01*
X313990Y3812225D01*
Y3811959D01*
X313790Y3811825D01*
G01X321290Y3809425D02*
X320290Y3810759D01*
X319790Y3812092D01*
Y3817425D01*
X320290Y3818759D01*
X321290Y3820092D01*
G01X327790Y3812092D02*
Y3820092D01*
X330190D01*
X330990Y3819692D01*
X331590Y3818759D01*
X331790Y3817692D01*
X331590Y3816625D01*
X331090Y3815825D01*
X330190Y3815425D01*
X327790D01*
G01X335790Y3820092D02*
Y3812092D01*
X339790D01*
G01X347790D02*
X343790D01*
Y3820092D01*
X347790D01*
G01X346190Y3816225D02*
X343790D01*
G01X351290Y3812092D02*
X353790Y3820092D01*
X356290Y3812092D01*
G01X355390Y3814892D02*
X352190D01*
G01X359690Y3813158D02*
X360490Y3812492D01*
X361390Y3812092D01*
X362190D01*
X362990Y3812492D01*
X363590Y3813158D01*
X363890Y3814092D01*
X363690Y3815025D01*
X363190Y3815825D01*
X362290Y3816359D01*
X361090Y3816625D01*
X360390Y3817159D01*
X360090Y3818092D01*
X360290Y3819025D01*
X360790Y3819692D01*
X361490Y3820092D01*
X362190D01*
X362890Y3819825D01*
X363490Y3819159D01*
G01X371790Y3812092D02*
X367790D01*
Y3820092D01*
X371790D01*
G01X370190Y3816225D02*
X367790D01*
G01X384590Y3820092D02*
X386990D01*
G01X385790D02*
Y3812092D01*
G01X384590D02*
X386990D01*
G01X394390Y3816092D02*
X396390D01*
Y3813692D01*
X395790Y3812892D01*
X395090Y3812359D01*
X394090Y3812092D01*
X393090Y3812359D01*
X392390Y3812892D01*
X391790Y3813692D01*
X391390Y3814625D01*
X391190Y3815692D01*
Y3816625D01*
X391390Y3817425D01*
X391790Y3818359D01*
X392390Y3819159D01*
X392990Y3819692D01*
X393790Y3820092D01*
X394490D01*
X395290Y3819825D01*
X395890Y3819292D01*
G01X399490Y3812092D02*
Y3820092D01*
X404090Y3812092D01*
Y3820092D01*
G01X409790Y3812092D02*
X408990Y3812225D01*
X408290Y3812759D01*
X407690Y3813559D01*
X407290Y3814492D01*
X407090Y3815559D01*
Y3816625D01*
X407290Y3817692D01*
X407690Y3818625D01*
X408290Y3819425D01*
X408990Y3819959D01*
X409790Y3820092D01*
X410590Y3819959D01*
X411290Y3819425D01*
X411890Y3818625D01*
X412290Y3817692D01*
X412490Y3816625D01*
Y3815559D01*
X412290Y3814492D01*
X411890Y3813559D01*
X411290Y3812759D01*
X410590Y3812225D01*
X409790Y3812092D01*
G01X415790D02*
Y3820092D01*
X418290D01*
X419090Y3819692D01*
X419590Y3819159D01*
X419790Y3818092D01*
X419590Y3817025D01*
X418990Y3816359D01*
X418290Y3815959D01*
X415790D01*
G01X418290D02*
X419790Y3812092D01*
G01X427790D02*
X423790D01*
Y3820092D01*
X427790D01*
G01X426190Y3816225D02*
X423790D01*
G01X441790Y3820092D02*
Y3812092D01*
G01X439490Y3820092D02*
X444090D01*
G01X447690Y3812092D02*
Y3820092D01*
G01X451890D02*
Y3812092D01*
G01Y3816092D02*
X447690D01*
G01X456590Y3820092D02*
X458990D01*
G01X457790D02*
Y3812092D01*
G01X456590D02*
X458990D01*
G01X463690Y3813158D02*
X464490Y3812492D01*
X465390Y3812092D01*
X466190D01*
X466990Y3812492D01*
X467590Y3813158D01*
X467890Y3814092D01*
X467690Y3815025D01*
X467190Y3815825D01*
X466290Y3816359D01*
X465090Y3816625D01*
X464390Y3817159D01*
X464090Y3818092D01*
X464290Y3819025D01*
X464790Y3819692D01*
X465490Y3820092D01*
X466190D01*
X466890Y3819825D01*
X467490Y3819159D01*
G01X480590Y3820092D02*
X482990D01*
G01X481790D02*
Y3812092D01*
G01X480590D02*
X482990D01*
G01X487890D02*
Y3820092D01*
X491690D01*
G01X490290Y3816225D02*
X487890D01*
G01X503490Y3812092D02*
Y3820092D01*
X508090Y3812092D01*
Y3820092D01*
G01X513790Y3812092D02*
X512990Y3812225D01*
X512290Y3812759D01*
X511690Y3813559D01*
X511290Y3814492D01*
X511090Y3815559D01*
Y3816625D01*
X511290Y3817692D01*
X511690Y3818625D01*
X512290Y3819425D01*
X512990Y3819959D01*
X513790Y3820092D01*
X514590Y3819959D01*
X515290Y3819425D01*
X515890Y3818625D01*
X516290Y3817692D01*
X516490Y3816625D01*
Y3815559D01*
X516290Y3814492D01*
X515890Y3813559D01*
X515290Y3812759D01*
X514590Y3812225D01*
X513790Y3812092D01*
G01X529790Y3820092D02*
Y3812092D01*
G01X527490Y3820092D02*
X532090D01*
G01X535690Y3812092D02*
Y3820092D01*
G01X539890D02*
Y3812092D01*
G01Y3816092D02*
X535690D01*
G01X544590Y3820092D02*
X546990D01*
G01X545790D02*
Y3812092D01*
G01X544590D02*
X546990D01*
G01X551690Y3813158D02*
X552490Y3812492D01*
X553390Y3812092D01*
X554190D01*
X554990Y3812492D01*
X555590Y3813158D01*
X555890Y3814092D01*
X555690Y3815025D01*
X555190Y3815825D01*
X554290Y3816359D01*
X553090Y3816625D01*
X552390Y3817159D01*
X552090Y3818092D01*
X552290Y3819025D01*
X552790Y3819692D01*
X553490Y3820092D01*
X554190D01*
X554890Y3819825D01*
X555490Y3819159D01*
G01X568590Y3820092D02*
X570990D01*
G01X569790D02*
Y3812092D01*
G01X568590D02*
X570990D01*
G01X577790Y3820092D02*
Y3812092D01*
G01X575490Y3820092D02*
X580090D01*
G01X587790Y3812092D02*
X583790D01*
Y3820092D01*
X587790D01*
G01X586190Y3816225D02*
X583790D01*
G01X591190Y3812092D02*
Y3820092D01*
X593790Y3813425D01*
X596390Y3820092D01*
Y3812092D01*
G01X608590Y3820092D02*
X610990D01*
G01X609790D02*
Y3812092D01*
G01X608590D02*
X610990D01*
G01X615490D02*
Y3820092D01*
X620090Y3812092D01*
Y3820092D01*
G01X634590Y3816359D02*
X634990Y3816759D01*
X635290Y3817425D01*
X635490Y3818359D01*
X635290Y3819159D01*
X634890Y3819692D01*
X634190Y3820092D01*
X631490D01*
Y3812092D01*
X634790D01*
X635490Y3812625D01*
X635890Y3813425D01*
X636090Y3814359D01*
X635890Y3815292D01*
X635290Y3816092D01*
X634590Y3816359D01*
X631490D01*
G01X641790Y3812092D02*
X640990Y3812225D01*
X640290Y3812759D01*
X639690Y3813559D01*
X639290Y3814492D01*
X639090Y3815559D01*
Y3816625D01*
X639290Y3817692D01*
X639690Y3818625D01*
X640290Y3819425D01*
X640990Y3819959D01*
X641790Y3820092D01*
X642590Y3819959D01*
X643290Y3819425D01*
X643890Y3818625D01*
X644290Y3817692D01*
X644490Y3816625D01*
Y3815559D01*
X644290Y3814492D01*
X643890Y3813559D01*
X643290Y3812759D01*
X642590Y3812225D01*
X641790Y3812092D01*
G01X647290D02*
X649790Y3820092D01*
X652290Y3812092D01*
G01X651390Y3814892D02*
X648190D01*
G01X655790Y3812092D02*
Y3820092D01*
X658290D01*
X659090Y3819692D01*
X659590Y3819159D01*
X659790Y3818092D01*
X659590Y3817025D01*
X658990Y3816359D01*
X658290Y3815959D01*
X655790D01*
G01X658290D02*
X659790Y3812092D01*
G01X663590D02*
Y3820092D01*
X665590D01*
X666390Y3819692D01*
X666990Y3819159D01*
X667490Y3818359D01*
X667890Y3817425D01*
X667990Y3816092D01*
X667890Y3814759D01*
X667490Y3813825D01*
X666990Y3813025D01*
X666390Y3812492D01*
X665590Y3812092D01*
X663590D01*
G01X679890D02*
Y3820092D01*
X683690D01*
G01X682290Y3816225D02*
X679890D01*
G01X688590Y3820092D02*
X690990D01*
G01X689790D02*
Y3812092D01*
G01X688590D02*
X690990D01*
G01X695790Y3820092D02*
Y3812092D01*
X699790D01*
G01X707790D02*
X703790D01*
Y3820092D01*
X707790D01*
G01X706190Y3816225D02*
X703790D01*
G01X714290Y3809425D02*
X715290Y3810759D01*
X715790Y3812092D01*
Y3817425D01*
X715290Y3818759D01*
X714290Y3820092D01*
G01X-29410Y3831359D02*
X-29010Y3831759D01*
X-28710Y3832425D01*
X-28510Y3833359D01*
X-28710Y3834159D01*
X-29110Y3834692D01*
X-29810Y3835092D01*
X-32510D01*
Y3827092D01*
X-29210D01*
X-28510Y3827625D01*
X-28110Y3828425D01*
X-27910Y3829359D01*
X-28110Y3830292D01*
X-28710Y3831092D01*
X-29410Y3831359D01*
X-32510D01*
G01X-22210Y3826825D02*
X-22410Y3826959D01*
Y3827225D01*
X-22210Y3827359D01*
X-22010Y3827225D01*
Y3826959D01*
X-22210Y3826825D01*
G01X-16710Y3827092D02*
X-14210Y3835092D01*
X-11710Y3827092D01*
G01X-12610Y3829892D02*
X-15810D01*
G01X-8210Y3835092D02*
Y3827092D01*
X-4210D01*
G01X-210Y3835092D02*
Y3827092D01*
X3790D01*
G01X15290Y3835092D02*
X17790Y3827092D01*
X20290Y3835092D01*
G01X24590D02*
X26990D01*
G01X25790D02*
Y3827092D01*
G01X24590D02*
X26990D01*
G01X31290D02*
X33790Y3835092D01*
X36290Y3827092D01*
G01X35390Y3829892D02*
X32190D01*
G01X39690Y3828158D02*
X40490Y3827492D01*
X41390Y3827092D01*
X42190D01*
X42990Y3827492D01*
X43590Y3828158D01*
X43890Y3829092D01*
X43690Y3830025D01*
X43190Y3830825D01*
X42290Y3831359D01*
X41090Y3831625D01*
X40390Y3832159D01*
X40090Y3833092D01*
X40290Y3834025D01*
X40790Y3834692D01*
X41490Y3835092D01*
X42190D01*
X42890Y3834825D01*
X43490Y3834159D01*
G01X55790Y3827092D02*
Y3835092D01*
X58190D01*
X58990Y3834692D01*
X59590Y3833759D01*
X59790Y3832692D01*
X59590Y3831625D01*
X59090Y3830825D01*
X58190Y3830425D01*
X55790D01*
G01X63790Y3835092D02*
Y3827092D01*
X67790D01*
G01X71590Y3835092D02*
Y3829359D01*
X71990Y3828158D01*
X72790Y3827359D01*
X73790Y3827092D01*
X74790Y3827359D01*
X75590Y3828158D01*
X75990Y3829359D01*
Y3835092D01*
G01X82390Y3831092D02*
X84390D01*
Y3828692D01*
X83790Y3827892D01*
X83090Y3827359D01*
X82090Y3827092D01*
X81090Y3827359D01*
X80390Y3827892D01*
X79790Y3828692D01*
X79390Y3829625D01*
X79190Y3830692D01*
Y3831625D01*
X79390Y3832425D01*
X79790Y3833359D01*
X80390Y3834159D01*
X80990Y3834692D01*
X81790Y3835092D01*
X82490D01*
X83290Y3834825D01*
X83890Y3834292D01*
G01X90390Y3831092D02*
X92390D01*
Y3828692D01*
X91790Y3827892D01*
X91090Y3827359D01*
X90090Y3827092D01*
X89090Y3827359D01*
X88390Y3827892D01*
X87790Y3828692D01*
X87390Y3829625D01*
X87190Y3830692D01*
Y3831625D01*
X87390Y3832425D01*
X87790Y3833359D01*
X88390Y3834159D01*
X88990Y3834692D01*
X89790Y3835092D01*
X90490D01*
X91290Y3834825D01*
X91890Y3834292D01*
G01X99790Y3827092D02*
X95790D01*
Y3835092D01*
X99790D01*
G01X98190Y3831225D02*
X95790D01*
G01X103590Y3827092D02*
Y3835092D01*
X105590D01*
X106390Y3834692D01*
X106990Y3834159D01*
X107490Y3833359D01*
X107890Y3832425D01*
X107990Y3831092D01*
X107890Y3829759D01*
X107490Y3828825D01*
X106990Y3828025D01*
X106390Y3827492D01*
X105590Y3827092D01*
X103590D01*
G01X123790D02*
X119790D01*
Y3835092D01*
X123790D01*
G01X122190Y3831225D02*
X119790D01*
G01X127690Y3827092D02*
X131890Y3835092D01*
G01X127690D02*
X131890Y3827092D01*
G01X139990Y3834425D02*
X139390Y3834825D01*
X138690Y3835092D01*
X137890D01*
X136990Y3834692D01*
X136290Y3834025D01*
X135790Y3833225D01*
X135390Y3831892D01*
X135290Y3830692D01*
X135490Y3829492D01*
X135790Y3828692D01*
X136390Y3827892D01*
X137090Y3827359D01*
X137790Y3827092D01*
X138490D01*
X139190Y3827359D01*
X139790Y3827759D01*
X140290Y3828292D01*
G01X147790Y3827092D02*
X143790D01*
Y3835092D01*
X147790D01*
G01X146190Y3831225D02*
X143790D01*
G01X151790Y3827092D02*
Y3835092D01*
X154190D01*
X154990Y3834692D01*
X155590Y3833759D01*
X155790Y3832692D01*
X155590Y3831625D01*
X155090Y3830825D01*
X154190Y3830425D01*
X151790D01*
G01X161790Y3835092D02*
Y3827092D01*
G01X159490Y3835092D02*
X164090D01*
G01X175890Y3827092D02*
Y3835092D01*
X179690D01*
G01X178290Y3831225D02*
X175890D01*
G01X185790Y3827092D02*
X184990Y3827225D01*
X184290Y3827759D01*
X183690Y3828559D01*
X183290Y3829492D01*
X183090Y3830559D01*
Y3831625D01*
X183290Y3832692D01*
X183690Y3833625D01*
X184290Y3834425D01*
X184990Y3834959D01*
X185790Y3835092D01*
X186590Y3834959D01*
X187290Y3834425D01*
X187890Y3833625D01*
X188290Y3832692D01*
X188490Y3831625D01*
Y3830559D01*
X188290Y3829492D01*
X187890Y3828559D01*
X187290Y3827759D01*
X186590Y3827225D01*
X185790Y3827092D01*
G01X191790D02*
Y3835092D01*
X194290D01*
X195090Y3834692D01*
X195590Y3834159D01*
X195790Y3833092D01*
X195590Y3832025D01*
X194990Y3831359D01*
X194290Y3830959D01*
X191790D01*
G01X194290D02*
X195790Y3827092D01*
G01X-32710Y3842092D02*
X-30210Y3850092D01*
X-27710Y3842092D01*
G01X-28610Y3844892D02*
X-31810D01*
G01X-22210Y3841825D02*
X-22410Y3841959D01*
Y3842225D01*
X-22210Y3842359D01*
X-22010Y3842225D01*
Y3841959D01*
X-22210Y3841825D01*
G01X-16710Y3850092D02*
X-14210Y3842092D01*
X-11710Y3850092D01*
G01X-7410D02*
X-5010D01*
G01X-6210D02*
Y3842092D01*
G01X-7410D02*
X-5010D01*
G01X-710D02*
X1790Y3850092D01*
X4290Y3842092D01*
G01X3390Y3844892D02*
X190D01*
G01X17790Y3850092D02*
Y3842092D01*
G01X15490Y3850092D02*
X20090D01*
G01X27790Y3842092D02*
X23790D01*
Y3850092D01*
X27790D01*
G01X26190Y3846225D02*
X23790D01*
G01X31290Y3842092D02*
X33790Y3850092D01*
X36290Y3842092D01*
G01X35390Y3844892D02*
X32190D01*
G01X39790Y3842092D02*
Y3850092D01*
X42290D01*
X43090Y3849692D01*
X43590Y3849159D01*
X43790Y3848092D01*
X43590Y3847025D01*
X42990Y3846359D01*
X42290Y3845959D01*
X39790D01*
G01X42290D02*
X43790Y3842092D01*
G01X55590D02*
Y3850092D01*
X57590D01*
X58390Y3849692D01*
X58990Y3849159D01*
X59490Y3848359D01*
X59890Y3847425D01*
X59990Y3846092D01*
X59890Y3844759D01*
X59490Y3843825D01*
X58990Y3843025D01*
X58390Y3842492D01*
X57590Y3842092D01*
X55590D01*
G01X63790D02*
Y3850092D01*
X66290D01*
X67090Y3849692D01*
X67590Y3849159D01*
X67790Y3848092D01*
X67590Y3847025D01*
X66990Y3846359D01*
X66290Y3845959D01*
X63790D01*
G01X66290D02*
X67790Y3842092D01*
G01X73790D02*
X72990Y3842225D01*
X72290Y3842759D01*
X71690Y3843559D01*
X71290Y3844492D01*
X71090Y3845559D01*
Y3846625D01*
X71290Y3847692D01*
X71690Y3848625D01*
X72290Y3849425D01*
X72990Y3849959D01*
X73790Y3850092D01*
X74590Y3849959D01*
X75290Y3849425D01*
X75890Y3848625D01*
X76290Y3847692D01*
X76490Y3846625D01*
Y3845559D01*
X76290Y3844492D01*
X75890Y3843559D01*
X75290Y3842759D01*
X74590Y3842225D01*
X73790Y3842092D01*
G01X79790D02*
Y3850092D01*
X82190D01*
X82990Y3849692D01*
X83590Y3848759D01*
X83790Y3847692D01*
X83590Y3846625D01*
X83090Y3845825D01*
X82190Y3845425D01*
X79790D01*
G01X97290Y3839425D02*
X96290Y3840759D01*
X95790Y3842092D01*
Y3847425D01*
X96290Y3848759D01*
X97290Y3850092D01*
G01X103890Y3842092D02*
Y3850092D01*
X107690D01*
G01X106290Y3846225D02*
X103890D01*
G01X113790Y3842092D02*
X112990Y3842225D01*
X112290Y3842759D01*
X111690Y3843559D01*
X111290Y3844492D01*
X111090Y3845559D01*
Y3846625D01*
X111290Y3847692D01*
X111690Y3848625D01*
X112290Y3849425D01*
X112990Y3849959D01*
X113790Y3850092D01*
X114590Y3849959D01*
X115290Y3849425D01*
X115890Y3848625D01*
X116290Y3847692D01*
X116490Y3846625D01*
Y3845559D01*
X116290Y3844492D01*
X115890Y3843559D01*
X115290Y3842759D01*
X114590Y3842225D01*
X113790Y3842092D01*
G01X119790D02*
Y3850092D01*
X122290D01*
X123090Y3849692D01*
X123590Y3849159D01*
X123790Y3848092D01*
X123590Y3847025D01*
X122990Y3846359D01*
X122290Y3845959D01*
X119790D01*
G01X122290D02*
X123790Y3842092D01*
G01X135290D02*
X137790Y3850092D01*
X140290Y3842092D01*
G01X139390Y3844892D02*
X136190D01*
G01X143790Y3850092D02*
Y3842092D01*
X147790D01*
G01X151790Y3850092D02*
Y3842092D01*
X155790D01*
G01X167290Y3850092D02*
X169790Y3842092D01*
X172290Y3850092D01*
G01X176590D02*
X178990D01*
G01X177790D02*
Y3842092D01*
G01X176590D02*
X178990D01*
G01X183290D02*
X185790Y3850092D01*
X188290Y3842092D01*
G01X187390Y3844892D02*
X184190D01*
G01X191690Y3843158D02*
X192490Y3842492D01*
X193390Y3842092D01*
X194190D01*
X194990Y3842492D01*
X195590Y3843158D01*
X195890Y3844092D01*
X195690Y3845025D01*
X195190Y3845825D01*
X194290Y3846359D01*
X193090Y3846625D01*
X192390Y3847159D01*
X192090Y3848092D01*
X192290Y3849025D01*
X192790Y3849692D01*
X193490Y3850092D01*
X194190D01*
X194890Y3849825D01*
X195490Y3849159D01*
G01X207290Y3842092D02*
X209790Y3850092D01*
X212290Y3842092D01*
G01X211390Y3844892D02*
X208190D01*
G01X215490Y3842092D02*
Y3850092D01*
X220090Y3842092D01*
Y3850092D01*
G01X223590Y3842092D02*
Y3850092D01*
X225590D01*
X226390Y3849692D01*
X226990Y3849159D01*
X227490Y3848359D01*
X227890Y3847425D01*
X227990Y3846092D01*
X227890Y3844759D01*
X227490Y3843825D01*
X226990Y3843025D01*
X226390Y3842492D01*
X225590Y3842092D01*
X223590D01*
G01X239790D02*
Y3850092D01*
X242190D01*
X242990Y3849692D01*
X243590Y3848759D01*
X243790Y3847692D01*
X243590Y3846625D01*
X243090Y3845825D01*
X242190Y3845425D01*
X239790D01*
G01X248590Y3850092D02*
X250990D01*
G01X249790D02*
Y3842092D01*
G01X248590D02*
X250990D01*
G01X255490D02*
Y3850092D01*
X260090Y3842092D01*
Y3850092D01*
G01X263690Y3843158D02*
X264490Y3842492D01*
X265390Y3842092D01*
X266190D01*
X266990Y3842492D01*
X267590Y3843158D01*
X267890Y3844092D01*
X267690Y3845025D01*
X267190Y3845825D01*
X266290Y3846359D01*
X265090Y3846625D01*
X264390Y3847159D01*
X264090Y3848092D01*
X264290Y3849025D01*
X264790Y3849692D01*
X265490Y3850092D01*
X266190D01*
X266890Y3849825D01*
X267490Y3849159D01*
G01X274290Y3839425D02*
X275290Y3840759D01*
X275790Y3842092D01*
Y3847425D01*
X275290Y3848759D01*
X274290Y3850092D01*
G01X281790Y3841825D02*
X281590Y3841959D01*
Y3842225D01*
X281790Y3842359D01*
X281990Y3842225D01*
Y3841959D01*
X281790Y3841825D01*
G01X-50410Y3858692D02*
X-49810Y3857759D01*
X-49010Y3857225D01*
X-48110Y3857092D01*
X-47310Y3857225D01*
X-46510Y3857892D01*
X-46010Y3858692D01*
X-45910Y3859492D01*
X-46110Y3860425D01*
X-46810Y3861092D01*
X-47510Y3861359D01*
X-48410D01*
G01X-47510D02*
X-46910Y3861759D01*
X-46410Y3862425D01*
X-46210Y3863225D01*
X-46410Y3864025D01*
X-46910Y3864692D01*
X-47810Y3865092D01*
X-48710Y3864959D01*
X-49610Y3864425D01*
G01X-40210Y3856825D02*
X-40410Y3856959D01*
Y3857225D01*
X-40210Y3857359D01*
X-40010Y3857225D01*
Y3856959D01*
X-40210Y3856825D01*
G01X-34210Y3857092D02*
Y3865092D01*
X-31810D01*
X-31010Y3864692D01*
X-30410Y3863759D01*
X-30210Y3862692D01*
X-30410Y3861625D01*
X-30910Y3860825D01*
X-31810Y3860425D01*
X-34210D01*
G01X-22010Y3864425D02*
X-22610Y3864825D01*
X-23310Y3865092D01*
X-24110D01*
X-25010Y3864692D01*
X-25710Y3864025D01*
X-26210Y3863225D01*
X-26610Y3861892D01*
X-26710Y3860692D01*
X-26510Y3859492D01*
X-26210Y3858692D01*
X-25610Y3857892D01*
X-24910Y3857359D01*
X-24210Y3857092D01*
X-23510D01*
X-22810Y3857359D01*
X-22210Y3857759D01*
X-21710Y3858292D01*
G01X-15410Y3861359D02*
X-15010Y3861759D01*
X-14710Y3862425D01*
X-14510Y3863359D01*
X-14710Y3864159D01*
X-15110Y3864692D01*
X-15810Y3865092D01*
X-18510D01*
Y3857092D01*
X-15210D01*
X-14510Y3857625D01*
X-14110Y3858425D01*
X-13910Y3859359D01*
X-14110Y3860292D01*
X-14710Y3861092D01*
X-15410Y3861359D01*
X-18510D01*
G01X-2210Y3857092D02*
Y3865092D01*
X190D01*
X990Y3864692D01*
X1590Y3863759D01*
X1790Y3862692D01*
X1590Y3861625D01*
X1090Y3860825D01*
X190Y3860425D01*
X-2210D01*
G01X5790Y3857092D02*
Y3865092D01*
X8290D01*
X9090Y3864692D01*
X9590Y3864159D01*
X9790Y3863092D01*
X9590Y3862025D01*
X8990Y3861359D01*
X8290Y3860959D01*
X5790D01*
G01X8290D02*
X9790Y3857092D01*
G01X15790D02*
X14990Y3857225D01*
X14290Y3857759D01*
X13690Y3858559D01*
X13290Y3859492D01*
X13090Y3860559D01*
Y3861625D01*
X13290Y3862692D01*
X13690Y3863625D01*
X14290Y3864425D01*
X14990Y3864959D01*
X15790Y3865092D01*
X16590Y3864959D01*
X17290Y3864425D01*
X17890Y3863625D01*
X18290Y3862692D01*
X18490Y3861625D01*
Y3860559D01*
X18290Y3859492D01*
X17890Y3858559D01*
X17290Y3857759D01*
X16590Y3857225D01*
X15790Y3857092D01*
G01X25990Y3864425D02*
X25390Y3864825D01*
X24690Y3865092D01*
X23890D01*
X22990Y3864692D01*
X22290Y3864025D01*
X21790Y3863225D01*
X21390Y3861892D01*
X21290Y3860692D01*
X21490Y3859492D01*
X21790Y3858692D01*
X22390Y3857892D01*
X23090Y3857359D01*
X23790Y3857092D01*
X24490D01*
X25190Y3857359D01*
X25790Y3857759D01*
X26290Y3858292D01*
G01X33790Y3857092D02*
X29790D01*
Y3865092D01*
X33790D01*
G01X32190Y3861225D02*
X29790D01*
G01X37690Y3858158D02*
X38490Y3857492D01*
X39390Y3857092D01*
X40190D01*
X40990Y3857492D01*
X41590Y3858158D01*
X41890Y3859092D01*
X41690Y3860025D01*
X41190Y3860825D01*
X40290Y3861359D01*
X39090Y3861625D01*
X38390Y3862159D01*
X38090Y3863092D01*
X38290Y3864025D01*
X38790Y3864692D01*
X39490Y3865092D01*
X40190D01*
X40890Y3864825D01*
X41490Y3864159D01*
G01X45690Y3858158D02*
X46490Y3857492D01*
X47390Y3857092D01*
X48190D01*
X48990Y3857492D01*
X49590Y3858158D01*
X49890Y3859092D01*
X49690Y3860025D01*
X49190Y3860825D01*
X48290Y3861359D01*
X47090Y3861625D01*
X46390Y3862159D01*
X46090Y3863092D01*
X46290Y3864025D01*
X46790Y3864692D01*
X47490Y3865092D01*
X48190D01*
X48890Y3864825D01*
X49490Y3864159D01*
G01X55790Y3856825D02*
X55590Y3856959D01*
Y3857225D01*
X55790Y3857359D01*
X55990Y3857225D01*
Y3856959D01*
X55790Y3856825D01*
G01Y3860425D02*
X55590Y3860559D01*
Y3860825D01*
X55790Y3860959D01*
X55990Y3860825D01*
Y3860559D01*
X55790Y3860425D01*
G01X-50110Y3878759D02*
X-49510Y3879559D01*
X-48810Y3879959D01*
X-48010Y3880092D01*
X-47010Y3879825D01*
X-46310Y3879159D01*
X-46110Y3878359D01*
X-46210Y3877558D01*
X-46610Y3876892D01*
X-48610Y3875559D01*
X-49510Y3874625D01*
X-50110Y3873292D01*
X-50310Y3872092D01*
X-46110D01*
G01X-40210Y3871825D02*
X-40410Y3871959D01*
Y3872225D01*
X-40210Y3872359D01*
X-40010Y3872225D01*
Y3871959D01*
X-40210Y3871825D01*
G01X-34110Y3872092D02*
Y3880092D01*
X-30310D01*
G01X-31710Y3876225D02*
X-34110D01*
G01X-26710Y3872092D02*
X-24210Y3880092D01*
X-21710Y3872092D01*
G01X-22610Y3874892D02*
X-25810D01*
G01X-15410Y3876359D02*
X-15010Y3876759D01*
X-14710Y3877425D01*
X-14510Y3878359D01*
X-14710Y3879159D01*
X-15110Y3879692D01*
X-15810Y3880092D01*
X-18510D01*
Y3872092D01*
X-15210D01*
X-14510Y3872625D01*
X-14110Y3873425D01*
X-13910Y3874359D01*
X-14110Y3875292D01*
X-14710Y3876092D01*
X-15410Y3876359D01*
X-18510D01*
G01X-10210Y3872092D02*
Y3880092D01*
X-7710D01*
X-6910Y3879692D01*
X-6410Y3879159D01*
X-6210Y3878092D01*
X-6410Y3877025D01*
X-7010Y3876359D01*
X-7710Y3875959D01*
X-10210D01*
G01X-7710D02*
X-6210Y3872092D01*
G01X-1410Y3880092D02*
X990D01*
G01X-210D02*
Y3872092D01*
G01X-1410D02*
X990D01*
G01X9990Y3879425D02*
X9390Y3879825D01*
X8690Y3880092D01*
X7890D01*
X6990Y3879692D01*
X6290Y3879025D01*
X5790Y3878225D01*
X5390Y3876892D01*
X5290Y3875692D01*
X5490Y3874492D01*
X5790Y3873692D01*
X6390Y3872892D01*
X7090Y3872359D01*
X7790Y3872092D01*
X8490D01*
X9190Y3872359D01*
X9790Y3872759D01*
X10290Y3873292D01*
G01X13290Y3872092D02*
X15790Y3880092D01*
X18290Y3872092D01*
G01X17390Y3874892D02*
X14190D01*
G01X23790Y3880092D02*
Y3872092D01*
G01X21490Y3880092D02*
X26090D01*
G01X33790Y3872092D02*
X29790D01*
Y3880092D01*
X33790D01*
G01X32190Y3876225D02*
X29790D01*
G01X45790Y3872092D02*
Y3880092D01*
X48190D01*
X48990Y3879692D01*
X49590Y3878759D01*
X49790Y3877692D01*
X49590Y3876625D01*
X49090Y3875825D01*
X48190Y3875425D01*
X45790D01*
G01X57790Y3872092D02*
X53790D01*
Y3880092D01*
X57790D01*
G01X56190Y3876225D02*
X53790D01*
G01X61790Y3872092D02*
Y3880092D01*
X64290D01*
X65090Y3879692D01*
X65590Y3879159D01*
X65790Y3878092D01*
X65590Y3877025D01*
X64990Y3876359D01*
X64290Y3875959D01*
X61790D01*
G01X64290D02*
X65790Y3872092D01*
G01X79790D02*
X78990Y3872225D01*
X78290Y3872759D01*
X77690Y3873559D01*
X77290Y3874492D01*
X77090Y3875559D01*
Y3876625D01*
X77290Y3877692D01*
X77690Y3878625D01*
X78290Y3879425D01*
X78990Y3879959D01*
X79790Y3880092D01*
X80590Y3879959D01*
X81290Y3879425D01*
X81890Y3878625D01*
X82290Y3877692D01*
X82490Y3876625D01*
Y3875559D01*
X82290Y3874492D01*
X81890Y3873559D01*
X81290Y3872759D01*
X80590Y3872225D01*
X79790Y3872092D01*
G01X80590Y3874225D02*
X81790Y3872092D01*
G01X85590Y3880092D02*
Y3874359D01*
X85990Y3873158D01*
X86790Y3872359D01*
X87790Y3872092D01*
X88790Y3872359D01*
X89590Y3873158D01*
X89990Y3874359D01*
Y3880092D01*
G01X93290Y3872092D02*
X95790Y3880092D01*
X98290Y3872092D01*
G01X97390Y3874892D02*
X94190D01*
G01X101490Y3872092D02*
Y3880092D01*
X106090Y3872092D01*
Y3880092D01*
G01X111790D02*
Y3872092D01*
G01X109490Y3880092D02*
X114090D01*
G01X117290Y3872092D02*
X119790Y3880092D01*
X122290Y3872092D01*
G01X121390Y3874892D02*
X118190D01*
G01X133790Y3872092D02*
Y3880092D01*
X136190D01*
X136990Y3879692D01*
X137590Y3878759D01*
X137790Y3877692D01*
X137590Y3876625D01*
X137090Y3875825D01*
X136190Y3875425D01*
X133790D01*
G01X145990Y3879425D02*
X145390Y3879825D01*
X144690Y3880092D01*
X143890D01*
X142990Y3879692D01*
X142290Y3879025D01*
X141790Y3878225D01*
X141390Y3876892D01*
X141290Y3875692D01*
X141490Y3874492D01*
X141790Y3873692D01*
X142390Y3872892D01*
X143090Y3872359D01*
X143790Y3872092D01*
X144490D01*
X145190Y3872359D01*
X145790Y3872759D01*
X146290Y3873292D01*
G01X152590Y3876359D02*
X152990Y3876759D01*
X153290Y3877425D01*
X153490Y3878359D01*
X153290Y3879159D01*
X152890Y3879692D01*
X152190Y3880092D01*
X149490D01*
Y3872092D01*
X152790D01*
X153490Y3872625D01*
X153890Y3873425D01*
X154090Y3874359D01*
X153890Y3875292D01*
X153290Y3876092D01*
X152590Y3876359D01*
X149490D01*
G01X165690Y3873158D02*
X166490Y3872492D01*
X167390Y3872092D01*
X168190D01*
X168990Y3872492D01*
X169590Y3873158D01*
X169890Y3874092D01*
X169690Y3875025D01*
X169190Y3875825D01*
X168290Y3876359D01*
X167090Y3876625D01*
X166390Y3877159D01*
X166090Y3878092D01*
X166290Y3879025D01*
X166790Y3879692D01*
X167490Y3880092D01*
X168190D01*
X168890Y3879825D01*
X169490Y3879159D01*
G01X173790Y3872092D02*
Y3880092D01*
X176190D01*
X176990Y3879692D01*
X177590Y3878759D01*
X177790Y3877692D01*
X177590Y3876625D01*
X177090Y3875825D01*
X176190Y3875425D01*
X173790D01*
G01X185790Y3872092D02*
X181790D01*
Y3880092D01*
X185790D01*
G01X184190Y3876225D02*
X181790D01*
G01X193990Y3879425D02*
X193390Y3879825D01*
X192690Y3880092D01*
X191890D01*
X190990Y3879692D01*
X190290Y3879025D01*
X189790Y3878225D01*
X189390Y3876892D01*
X189290Y3875692D01*
X189490Y3874492D01*
X189790Y3873692D01*
X190390Y3872892D01*
X191090Y3872359D01*
X191790Y3872092D01*
X192490D01*
X193190Y3872359D01*
X193790Y3872759D01*
X194290Y3873292D01*
G01X198590Y3880092D02*
X200990D01*
G01X199790D02*
Y3872092D01*
G01X198590D02*
X200990D01*
G01X205890D02*
Y3880092D01*
X209690D01*
G01X208290Y3876225D02*
X205890D01*
G01X214590Y3880092D02*
X216990D01*
G01X215790D02*
Y3872092D01*
G01X214590D02*
X216990D01*
G01X225990Y3879425D02*
X225390Y3879825D01*
X224690Y3880092D01*
X223890D01*
X222990Y3879692D01*
X222290Y3879025D01*
X221790Y3878225D01*
X221390Y3876892D01*
X221290Y3875692D01*
X221490Y3874492D01*
X221790Y3873692D01*
X222390Y3872892D01*
X223090Y3872359D01*
X223790Y3872092D01*
X224490D01*
X225190Y3872359D01*
X225790Y3872759D01*
X226290Y3873292D01*
G01X229290Y3872092D02*
X231790Y3880092D01*
X234290Y3872092D01*
G01X233390Y3874892D02*
X230190D01*
G01X239790Y3880092D02*
Y3872092D01*
G01X237490Y3880092D02*
X242090D01*
G01X246590D02*
X248990D01*
G01X247790D02*
Y3872092D01*
G01X246590D02*
X248990D01*
G01X255790D02*
X254990Y3872225D01*
X254290Y3872759D01*
X253690Y3873559D01*
X253290Y3874492D01*
X253090Y3875559D01*
Y3876625D01*
X253290Y3877692D01*
X253690Y3878625D01*
X254290Y3879425D01*
X254990Y3879959D01*
X255790Y3880092D01*
X256590Y3879959D01*
X257290Y3879425D01*
X257890Y3878625D01*
X258290Y3877692D01*
X258490Y3876625D01*
Y3875559D01*
X258290Y3874492D01*
X257890Y3873559D01*
X257290Y3872759D01*
X256590Y3872225D01*
X255790Y3872092D01*
G01X261490D02*
Y3880092D01*
X266090Y3872092D01*
Y3880092D01*
G01X282790Y3869425D02*
X277790Y3877425D01*
Y3878759D01*
X278790Y3880092D01*
X279790D01*
X280790Y3878759D01*
Y3877425D01*
X279790Y3876092D01*
X277790Y3874759D01*
X276790Y3873425D01*
Y3870759D01*
X277790Y3869425D01*
X280790D01*
X282790Y3872092D01*
G01X295790D02*
X294990Y3872225D01*
X294290Y3872759D01*
X293690Y3873559D01*
X293290Y3874492D01*
X293090Y3875559D01*
Y3876625D01*
X293290Y3877692D01*
X293690Y3878625D01*
X294290Y3879425D01*
X294990Y3879959D01*
X295790Y3880092D01*
X296590Y3879959D01*
X297290Y3879425D01*
X297890Y3878625D01*
X298290Y3877692D01*
X298490Y3876625D01*
Y3875559D01*
X298290Y3874492D01*
X297890Y3873559D01*
X297290Y3872759D01*
X296590Y3872225D01*
X295790Y3872092D01*
G01X296590Y3874225D02*
X297790Y3872092D01*
G01X305990Y3879425D02*
X305390Y3879825D01*
X304690Y3880092D01*
X303890D01*
X302990Y3879692D01*
X302290Y3879025D01*
X301790Y3878225D01*
X301390Y3876892D01*
X301290Y3875692D01*
X301490Y3874492D01*
X301790Y3873692D01*
X302390Y3872892D01*
X303090Y3872359D01*
X303790Y3872092D01*
X304490D01*
X305190Y3872359D01*
X305790Y3872759D01*
X306290Y3873292D01*
G01X311790Y3880092D02*
Y3872092D01*
G01X309490Y3880092D02*
X314090D01*
G01X329790Y3872092D02*
X325790D01*
Y3880092D01*
X329790D01*
G01X328190Y3876225D02*
X325790D01*
G01X335790Y3872092D02*
X334990Y3872225D01*
X334290Y3872759D01*
X333690Y3873559D01*
X333290Y3874492D01*
X333090Y3875559D01*
Y3876625D01*
X333290Y3877692D01*
X333690Y3878625D01*
X334290Y3879425D01*
X334990Y3879959D01*
X335790Y3880092D01*
X336590Y3879959D01*
X337290Y3879425D01*
X337890Y3878625D01*
X338290Y3877692D01*
X338490Y3876625D01*
Y3875559D01*
X338290Y3874492D01*
X337890Y3873559D01*
X337290Y3872759D01*
X336590Y3872225D01*
X335790Y3872092D01*
G01X336590Y3874225D02*
X337790Y3872092D01*
G01X349890D02*
Y3880092D01*
X353690D01*
G01X352290Y3876225D02*
X349890D01*
G01X357290Y3872092D02*
X359790Y3880092D01*
X362290Y3872092D01*
G01X361390Y3874892D02*
X358190D01*
G01X367790Y3872092D02*
X366990Y3872225D01*
X366290Y3872759D01*
X365690Y3873559D01*
X365290Y3874492D01*
X365090Y3875559D01*
Y3876625D01*
X365290Y3877692D01*
X365690Y3878625D01*
X366290Y3879425D01*
X366990Y3879959D01*
X367790Y3880092D01*
X368590Y3879959D01*
X369290Y3879425D01*
X369890Y3878625D01*
X370290Y3877692D01*
X370490Y3876625D01*
Y3875559D01*
X370290Y3874492D01*
X369890Y3873559D01*
X369290Y3872759D01*
X368590Y3872225D01*
X367790Y3872092D01*
G01X368590Y3874225D02*
X369790Y3872092D01*
G01X375790Y3871825D02*
X375590Y3871959D01*
Y3872225D01*
X375790Y3872359D01*
X375990Y3872225D01*
Y3871959D01*
X375790Y3871825D01*
G01X-48210Y3887092D02*
Y3895092D01*
X-49410Y3893492D01*
G01Y3887092D02*
X-47010D01*
G01X-40210Y3886825D02*
X-40410Y3886959D01*
Y3887225D01*
X-40210Y3887359D01*
X-40010Y3887225D01*
Y3886959D01*
X-40210Y3886825D01*
G01X-34210Y3887092D02*
Y3895092D01*
X-31810D01*
X-31010Y3894692D01*
X-30410Y3893759D01*
X-30210Y3892692D01*
X-30410Y3891625D01*
X-30910Y3890825D01*
X-31810Y3890425D01*
X-34210D01*
G01X-22010Y3894425D02*
X-22610Y3894825D01*
X-23310Y3895092D01*
X-24110D01*
X-25010Y3894692D01*
X-25710Y3894025D01*
X-26210Y3893225D01*
X-26610Y3891892D01*
X-26710Y3890692D01*
X-26510Y3889492D01*
X-26210Y3888692D01*
X-25610Y3887892D01*
X-24910Y3887359D01*
X-24210Y3887092D01*
X-23510D01*
X-22810Y3887359D01*
X-22210Y3887759D01*
X-21710Y3888292D01*
G01X-15410Y3891359D02*
X-15010Y3891759D01*
X-14710Y3892425D01*
X-14510Y3893359D01*
X-14710Y3894159D01*
X-15110Y3894692D01*
X-15810Y3895092D01*
X-18510D01*
Y3887092D01*
X-15210D01*
X-14510Y3887625D01*
X-14110Y3888425D01*
X-13910Y3889359D01*
X-14110Y3890292D01*
X-14710Y3891092D01*
X-15410Y3891359D01*
X-18510D01*
G01X-2310Y3888158D02*
X-1510Y3887492D01*
X-610Y3887092D01*
X190D01*
X990Y3887492D01*
X1590Y3888158D01*
X1890Y3889092D01*
X1690Y3890025D01*
X1190Y3890825D01*
X290Y3891359D01*
X-910Y3891625D01*
X-1610Y3892159D01*
X-1910Y3893092D01*
X-1710Y3894025D01*
X-1210Y3894692D01*
X-510Y3895092D01*
X190D01*
X890Y3894825D01*
X1490Y3894159D01*
G01X6590Y3895092D02*
X8990D01*
G01X7790D02*
Y3887092D01*
G01X6590D02*
X8990D01*
G01X13890Y3895092D02*
X17690D01*
X13890Y3887092D01*
X17690D01*
G01X25790D02*
X21790D01*
Y3895092D01*
X25790D01*
G01X24190Y3891225D02*
X21790D01*
G01X55790Y3886825D02*
X55590Y3886959D01*
Y3887225D01*
X55790Y3887359D01*
X55990Y3887225D01*
Y3886959D01*
X55790Y3886825D01*
G01Y3890425D02*
X55590Y3890559D01*
Y3890825D01*
X55790Y3890959D01*
X55990Y3890825D01*
Y3890559D01*
X55790Y3890425D01*
G01X69890Y3887092D02*
Y3895092D01*
X73690D01*
G01X72290Y3891225D02*
X69890D01*
G01X79790Y3887092D02*
X78990Y3887225D01*
X78290Y3887759D01*
X77690Y3888559D01*
X77290Y3889492D01*
X77090Y3890559D01*
Y3891625D01*
X77290Y3892692D01*
X77690Y3893625D01*
X78290Y3894425D01*
X78990Y3894959D01*
X79790Y3895092D01*
X80590Y3894959D01*
X81290Y3894425D01*
X81890Y3893625D01*
X82290Y3892692D01*
X82490Y3891625D01*
Y3890559D01*
X82290Y3889492D01*
X81890Y3888559D01*
X81290Y3887759D01*
X80590Y3887225D01*
X79790Y3887092D01*
G01X85790Y3895092D02*
Y3887092D01*
X89790D01*
G01X93790Y3895092D02*
Y3887092D01*
X97790D01*
G01X103790D02*
X102990Y3887225D01*
X102290Y3887759D01*
X101690Y3888559D01*
X101290Y3889492D01*
X101090Y3890559D01*
Y3891625D01*
X101290Y3892692D01*
X101690Y3893625D01*
X102290Y3894425D01*
X102990Y3894959D01*
X103790Y3895092D01*
X104590Y3894959D01*
X105290Y3894425D01*
X105890Y3893625D01*
X106290Y3892692D01*
X106490Y3891625D01*
Y3890559D01*
X106290Y3889492D01*
X105890Y3888559D01*
X105290Y3887759D01*
X104590Y3887225D01*
X103790Y3887092D01*
G01X108790Y3895092D02*
X110190Y3887092D01*
X111790Y3895092D01*
X113390Y3887092D01*
X114790Y3895092D01*
G01X128390Y3891092D02*
X130390D01*
Y3888692D01*
X129790Y3887892D01*
X129090Y3887359D01*
X128090Y3887092D01*
X127090Y3887359D01*
X126390Y3887892D01*
X125790Y3888692D01*
X125390Y3889625D01*
X125190Y3890692D01*
Y3891625D01*
X125390Y3892425D01*
X125790Y3893359D01*
X126390Y3894159D01*
X126990Y3894692D01*
X127790Y3895092D01*
X128490D01*
X129290Y3894825D01*
X129890Y3894292D01*
G01X137790Y3887092D02*
X133790D01*
Y3895092D01*
X137790D01*
G01X136190Y3891225D02*
X133790D01*
G01X141790Y3887092D02*
Y3895092D01*
X144290D01*
X145090Y3894692D01*
X145590Y3894159D01*
X145790Y3893092D01*
X145590Y3892025D01*
X144990Y3891359D01*
X144290Y3890959D01*
X141790D01*
G01X144290D02*
X145790Y3887092D01*
G01X152590Y3891359D02*
X152990Y3891759D01*
X153290Y3892425D01*
X153490Y3893359D01*
X153290Y3894159D01*
X152890Y3894692D01*
X152190Y3895092D01*
X149490D01*
Y3887092D01*
X152790D01*
X153490Y3887625D01*
X153890Y3888425D01*
X154090Y3889359D01*
X153890Y3890292D01*
X153290Y3891092D01*
X152590Y3891359D01*
X149490D01*
G01X161790Y3887092D02*
X157790D01*
Y3895092D01*
X161790D01*
G01X160190Y3891225D02*
X157790D01*
G01X165790Y3887092D02*
Y3895092D01*
X168290D01*
X169090Y3894692D01*
X169590Y3894159D01*
X169790Y3893092D01*
X169590Y3892025D01*
X168990Y3891359D01*
X168290Y3890959D01*
X165790D01*
G01X168290D02*
X169790Y3887092D01*
G01X181890D02*
Y3895092D01*
X185690D01*
G01X184290Y3891225D02*
X181890D01*
G01X190590Y3895092D02*
X192990D01*
G01X191790D02*
Y3887092D01*
G01X190590D02*
X192990D01*
G01X197790Y3895092D02*
Y3887092D01*
X201790D01*
G01X209790D02*
X205790D01*
Y3895092D01*
X209790D01*
G01X208190Y3891225D02*
X205790D01*
G01X215090Y3884692D02*
X216490Y3886559D01*
Y3888425D01*
X215090D01*
Y3886559D01*
X216490D01*
G01Y3889759D02*
Y3891625D01*
X215090D01*
Y3889759D01*
X216490D01*
G01X228790Y3895092D02*
X230190Y3887092D01*
X231790Y3895092D01*
X233390Y3887092D01*
X234790Y3895092D01*
G01X238590D02*
X240990D01*
G01X239790D02*
Y3887092D01*
G01X238590D02*
X240990D01*
G01X247790Y3895092D02*
Y3887092D01*
G01X245490Y3895092D02*
X250090D01*
G01X253690Y3887092D02*
Y3895092D01*
G01X257890D02*
Y3887092D01*
G01Y3891092D02*
X253690D01*
G01X271790Y3895092D02*
Y3887092D01*
G01X269490Y3895092D02*
X274090D01*
G01X279790Y3887092D02*
X278990Y3887225D01*
X278290Y3887759D01*
X277690Y3888559D01*
X277290Y3889492D01*
X277090Y3890559D01*
Y3891625D01*
X277290Y3892692D01*
X277690Y3893625D01*
X278290Y3894425D01*
X278990Y3894959D01*
X279790Y3895092D01*
X280590Y3894959D01*
X281290Y3894425D01*
X281890Y3893625D01*
X282290Y3892692D01*
X282490Y3891625D01*
Y3890559D01*
X282290Y3889492D01*
X281890Y3888559D01*
X281290Y3887759D01*
X280590Y3887225D01*
X279790Y3887092D01*
G01X285790Y3895092D02*
Y3887092D01*
X289790D01*
G01X297790D02*
X293790D01*
Y3895092D01*
X297790D01*
G01X296190Y3891225D02*
X293790D01*
G01X301790Y3887092D02*
Y3895092D01*
X304290D01*
X305090Y3894692D01*
X305590Y3894159D01*
X305790Y3893092D01*
X305590Y3892025D01*
X304990Y3891359D01*
X304290Y3890959D01*
X301790D01*
G01X304290D02*
X305790Y3887092D01*
G01X309290D02*
X311790Y3895092D01*
X314290Y3887092D01*
G01X313390Y3889892D02*
X310190D01*
G01X317490Y3887092D02*
Y3895092D01*
X322090Y3887092D01*
Y3895092D01*
G01X329990Y3894425D02*
X329390Y3894825D01*
X328690Y3895092D01*
X327890D01*
X326990Y3894692D01*
X326290Y3894025D01*
X325790Y3893225D01*
X325390Y3891892D01*
X325290Y3890692D01*
X325490Y3889492D01*
X325790Y3888692D01*
X326390Y3887892D01*
X327090Y3887359D01*
X327790Y3887092D01*
X328490D01*
X329190Y3887359D01*
X329790Y3887759D01*
X330290Y3888292D01*
G01X337790Y3887092D02*
X333790D01*
Y3895092D01*
X337790D01*
G01X336190Y3891225D02*
X333790D01*
G01X350490Y3888559D02*
X353090D01*
G01Y3890959D02*
X350490D01*
G01X358690Y3889759D02*
X361090D01*
G01X359790Y3891492D02*
Y3888025D01*
G01X365990Y3886825D02*
X369590Y3895092D01*
G01X374490Y3889759D02*
X377090D01*
G01X383790Y3895092D02*
X382990Y3894825D01*
X382390Y3894159D01*
X381990Y3893359D01*
X381690Y3892292D01*
X381590Y3891092D01*
X381690Y3889892D01*
X381990Y3888825D01*
X382390Y3888025D01*
X382990Y3887359D01*
X383790Y3887092D01*
X384590Y3887359D01*
X385190Y3888025D01*
X385590Y3888825D01*
X385890Y3889892D01*
X385990Y3891092D01*
X385890Y3892292D01*
X385590Y3893359D01*
X385190Y3894159D01*
X384590Y3894825D01*
X383790Y3895092D01*
G01X391790Y3886825D02*
X391590Y3886959D01*
Y3887225D01*
X391790Y3887359D01*
X391990Y3887225D01*
Y3886959D01*
X391790Y3886825D01*
G01X399790Y3887092D02*
Y3895092D01*
X398590Y3893492D01*
G01Y3887092D02*
X400990D01*
G01X405590Y3888292D02*
X406190Y3887625D01*
X406890Y3887225D01*
X407790Y3887092D01*
X408690Y3887359D01*
X409390Y3887892D01*
X409890Y3888825D01*
X409990Y3889892D01*
X409790Y3890959D01*
X409290Y3891625D01*
X408590Y3892159D01*
X407890Y3892292D01*
X407190Y3892159D01*
X406290Y3891625D01*
X406590Y3895092D01*
X409290D01*
G01X413190Y3887092D02*
Y3895092D01*
X415790Y3888425D01*
X418390Y3895092D01*
Y3887092D01*
G01X421190D02*
Y3895092D01*
X423790Y3888425D01*
X426390Y3895092D01*
Y3887092D01*
G01X-50510Y3902092D02*
Y3910092D01*
X-45910Y3902092D01*
Y3910092D01*
G01X-40210Y3902092D02*
X-41010Y3902225D01*
X-41710Y3902759D01*
X-42310Y3903559D01*
X-42710Y3904492D01*
X-42910Y3905559D01*
Y3906625D01*
X-42710Y3907692D01*
X-42310Y3908625D01*
X-41710Y3909425D01*
X-41010Y3909959D01*
X-40210Y3910092D01*
X-39410Y3909959D01*
X-38710Y3909425D01*
X-38110Y3908625D01*
X-37710Y3907692D01*
X-37510Y3906625D01*
Y3905559D01*
X-37710Y3904492D01*
X-38110Y3903559D01*
X-38710Y3902759D01*
X-39410Y3902225D01*
X-40210Y3902092D01*
G01X-32210Y3910092D02*
Y3902092D01*
G01X-34510Y3910092D02*
X-29910D01*
G01X-22210Y3902092D02*
X-26210D01*
Y3910092D01*
X-22210D01*
G01X-23810Y3906225D02*
X-26210D01*
G01X-18310Y3903158D02*
X-17510Y3902492D01*
X-16610Y3902092D01*
X-15810D01*
X-15010Y3902492D01*
X-14410Y3903158D01*
X-14110Y3904092D01*
X-14310Y3905025D01*
X-14810Y3905825D01*
X-15710Y3906359D01*
X-16910Y3906625D01*
X-17610Y3907159D01*
X-17910Y3908092D01*
X-17710Y3909025D01*
X-17210Y3909692D01*
X-16510Y3910092D01*
X-15810D01*
X-15110Y3909825D01*
X-14510Y3909159D01*
G01X-8210Y3901825D02*
X-8410Y3901959D01*
Y3902225D01*
X-8210Y3902359D01*
X-8010Y3902225D01*
Y3901959D01*
X-8210Y3901825D01*
G01Y3905425D02*
X-8410Y3905559D01*
Y3905825D01*
X-8210Y3905959D01*
X-8010Y3905825D01*
Y3905559D01*
X-8210Y3905425D01*
G01X7290Y3899425D02*
X6290Y3900759D01*
X5790Y3902092D01*
Y3907425D01*
X6290Y3908759D01*
X7290Y3910092D01*
G01X13590D02*
Y3904359D01*
X13990Y3903158D01*
X14790Y3902359D01*
X15790Y3902092D01*
X16790Y3902359D01*
X17590Y3903158D01*
X17990Y3904359D01*
Y3910092D01*
G01X21490Y3902092D02*
Y3910092D01*
X26090Y3902092D01*
Y3910092D01*
G01X29790D02*
Y3902092D01*
X33790D01*
G01X41790D02*
X37790D01*
Y3910092D01*
X41790D01*
G01X40190Y3906225D02*
X37790D01*
G01X45690Y3903158D02*
X46490Y3902492D01*
X47390Y3902092D01*
X48190D01*
X48990Y3902492D01*
X49590Y3903158D01*
X49890Y3904092D01*
X49690Y3905025D01*
X49190Y3905825D01*
X48290Y3906359D01*
X47090Y3906625D01*
X46390Y3907159D01*
X46090Y3908092D01*
X46290Y3909025D01*
X46790Y3909692D01*
X47490Y3910092D01*
X48190D01*
X48890Y3909825D01*
X49490Y3909159D01*
G01X53690Y3903158D02*
X54490Y3902492D01*
X55390Y3902092D01*
X56190D01*
X56990Y3902492D01*
X57590Y3903158D01*
X57890Y3904092D01*
X57690Y3905025D01*
X57190Y3905825D01*
X56290Y3906359D01*
X55090Y3906625D01*
X54390Y3907159D01*
X54090Y3908092D01*
X54290Y3909025D01*
X54790Y3909692D01*
X55490Y3910092D01*
X56190D01*
X56890Y3909825D01*
X57490Y3909159D01*
G01X71790Y3902092D02*
X70990Y3902225D01*
X70290Y3902759D01*
X69690Y3903559D01*
X69290Y3904492D01*
X69090Y3905559D01*
Y3906625D01*
X69290Y3907692D01*
X69690Y3908625D01*
X70290Y3909425D01*
X70990Y3909959D01*
X71790Y3910092D01*
X72590Y3909959D01*
X73290Y3909425D01*
X73890Y3908625D01*
X74290Y3907692D01*
X74490Y3906625D01*
Y3905559D01*
X74290Y3904492D01*
X73890Y3903559D01*
X73290Y3902759D01*
X72590Y3902225D01*
X71790Y3902092D01*
G01X79790Y3910092D02*
Y3902092D01*
G01X77490Y3910092D02*
X82090D01*
G01X85690Y3902092D02*
Y3910092D01*
G01X89890D02*
Y3902092D01*
G01Y3906092D02*
X85690D01*
G01X97790Y3902092D02*
X93790D01*
Y3910092D01*
X97790D01*
G01X96190Y3906225D02*
X93790D01*
G01X101790Y3902092D02*
Y3910092D01*
X104290D01*
X105090Y3909692D01*
X105590Y3909159D01*
X105790Y3908092D01*
X105590Y3907025D01*
X104990Y3906359D01*
X104290Y3905959D01*
X101790D01*
G01X104290D02*
X105790Y3902092D01*
G01X108790Y3910092D02*
X110190Y3902092D01*
X111790Y3910092D01*
X113390Y3902092D01*
X114790Y3910092D01*
G01X118590D02*
X120990D01*
G01X119790D02*
Y3902092D01*
G01X118590D02*
X120990D01*
G01X125690Y3903158D02*
X126490Y3902492D01*
X127390Y3902092D01*
X128190D01*
X128990Y3902492D01*
X129590Y3903158D01*
X129890Y3904092D01*
X129690Y3905025D01*
X129190Y3905825D01*
X128290Y3906359D01*
X127090Y3906625D01*
X126390Y3907159D01*
X126090Y3908092D01*
X126290Y3909025D01*
X126790Y3909692D01*
X127490Y3910092D01*
X128190D01*
X128890Y3909825D01*
X129490Y3909159D01*
G01X137790Y3902092D02*
X133790D01*
Y3910092D01*
X137790D01*
G01X136190Y3906225D02*
X133790D01*
G01X149690Y3903158D02*
X150490Y3902492D01*
X151390Y3902092D01*
X152190D01*
X152990Y3902492D01*
X153590Y3903158D01*
X153890Y3904092D01*
X153690Y3905025D01*
X153190Y3905825D01*
X152290Y3906359D01*
X151090Y3906625D01*
X150390Y3907159D01*
X150090Y3908092D01*
X150290Y3909025D01*
X150790Y3909692D01*
X151490Y3910092D01*
X152190D01*
X152890Y3909825D01*
X153490Y3909159D01*
G01X157790Y3902092D02*
Y3910092D01*
X160190D01*
X160990Y3909692D01*
X161590Y3908759D01*
X161790Y3907692D01*
X161590Y3906625D01*
X161090Y3905825D01*
X160190Y3905425D01*
X157790D01*
G01X169790Y3902092D02*
X165790D01*
Y3910092D01*
X169790D01*
G01X168190Y3906225D02*
X165790D01*
G01X177990Y3909425D02*
X177390Y3909825D01*
X176690Y3910092D01*
X175890D01*
X174990Y3909692D01*
X174290Y3909025D01*
X173790Y3908225D01*
X173390Y3906892D01*
X173290Y3905692D01*
X173490Y3904492D01*
X173790Y3903692D01*
X174390Y3902892D01*
X175090Y3902359D01*
X175790Y3902092D01*
X176490D01*
X177190Y3902359D01*
X177790Y3902759D01*
X178290Y3903292D01*
G01X182590Y3910092D02*
X184990D01*
G01X183790D02*
Y3902092D01*
G01X182590D02*
X184990D01*
G01X189890D02*
Y3910092D01*
X193690D01*
G01X192290Y3906225D02*
X189890D01*
G01X198590Y3910092D02*
X200990D01*
G01X199790D02*
Y3902092D01*
G01X198590D02*
X200990D01*
G01X209790D02*
X205790D01*
Y3910092D01*
X209790D01*
G01X208190Y3906225D02*
X205790D01*
G01X213590Y3902092D02*
Y3910092D01*
X215590D01*
X216390Y3909692D01*
X216990Y3909159D01*
X217490Y3908359D01*
X217890Y3907425D01*
X217990Y3906092D01*
X217890Y3904759D01*
X217490Y3903825D01*
X216990Y3903025D01*
X216390Y3902492D01*
X215590Y3902092D01*
X213590D01*
G01X230590Y3910092D02*
X232990D01*
G01X231790D02*
Y3902092D01*
G01X230590D02*
X232990D01*
G01X237490D02*
Y3910092D01*
X242090Y3902092D01*
Y3910092D01*
G01X253790Y3902092D02*
Y3910092D01*
X256190D01*
X256990Y3909692D01*
X257590Y3908759D01*
X257790Y3907692D01*
X257590Y3906625D01*
X257090Y3905825D01*
X256190Y3905425D01*
X253790D01*
G01X265990Y3909425D02*
X265390Y3909825D01*
X264690Y3910092D01*
X263890D01*
X262990Y3909692D01*
X262290Y3909025D01*
X261790Y3908225D01*
X261390Y3906892D01*
X261290Y3905692D01*
X261490Y3904492D01*
X261790Y3903692D01*
X262390Y3902892D01*
X263090Y3902359D01*
X263790Y3902092D01*
X264490D01*
X265190Y3902359D01*
X265790Y3902759D01*
X266290Y3903292D01*
G01X272590Y3906359D02*
X272990Y3906759D01*
X273290Y3907425D01*
X273490Y3908359D01*
X273290Y3909159D01*
X272890Y3909692D01*
X272190Y3910092D01*
X269490D01*
Y3902092D01*
X272790D01*
X273490Y3902625D01*
X273890Y3903425D01*
X274090Y3904359D01*
X273890Y3905292D01*
X273290Y3906092D01*
X272590Y3906359D01*
X269490D01*
G01X285690Y3903158D02*
X286490Y3902492D01*
X287390Y3902092D01*
X288190D01*
X288990Y3902492D01*
X289590Y3903158D01*
X289890Y3904092D01*
X289690Y3905025D01*
X289190Y3905825D01*
X288290Y3906359D01*
X287090Y3906625D01*
X286390Y3907159D01*
X286090Y3908092D01*
X286290Y3909025D01*
X286790Y3909692D01*
X287490Y3910092D01*
X288190D01*
X288890Y3909825D01*
X289490Y3909159D01*
G01X293790Y3902092D02*
Y3910092D01*
X296190D01*
X296990Y3909692D01*
X297590Y3908759D01*
X297790Y3907692D01*
X297590Y3906625D01*
X297090Y3905825D01*
X296190Y3905425D01*
X293790D01*
G01X305790Y3902092D02*
X301790D01*
Y3910092D01*
X305790D01*
G01X304190Y3906225D02*
X301790D01*
G01X313990Y3909425D02*
X313390Y3909825D01*
X312690Y3910092D01*
X311890D01*
X310990Y3909692D01*
X310290Y3909025D01*
X309790Y3908225D01*
X309390Y3906892D01*
X309290Y3905692D01*
X309490Y3904492D01*
X309790Y3903692D01*
X310390Y3902892D01*
X311090Y3902359D01*
X311790Y3902092D01*
X312490D01*
X313190Y3902359D01*
X313790Y3902759D01*
X314290Y3903292D01*
G01X320290Y3899425D02*
X321290Y3900759D01*
X321790Y3902092D01*
Y3907425D01*
X321290Y3908759D01*
X320290Y3910092D01*
G01X-48210Y3917092D02*
X-49010Y3917225D01*
X-49710Y3917759D01*
X-50310Y3918559D01*
X-50710Y3919492D01*
X-50910Y3920559D01*
Y3921625D01*
X-50710Y3922692D01*
X-50310Y3923625D01*
X-49710Y3924425D01*
X-49010Y3924959D01*
X-48210Y3925092D01*
X-47410Y3924959D01*
X-46710Y3924425D01*
X-46110Y3923625D01*
X-45710Y3922692D01*
X-45510Y3921625D01*
Y3920559D01*
X-45710Y3919492D01*
X-46110Y3918559D01*
X-46710Y3917759D01*
X-47410Y3917225D01*
X-48210Y3917092D01*
G01X-47410Y3919225D02*
X-46210Y3917092D01*
G01X-41910Y3922425D02*
Y3918692D01*
X-41510Y3917759D01*
X-40910Y3917225D01*
X-40210Y3917092D01*
X-39510Y3917225D01*
X-38910Y3917759D01*
X-38510Y3918692D01*
G01Y3917092D02*
Y3922425D01*
G01X-30410Y3917092D02*
Y3922425D01*
G01Y3921492D02*
X-30810Y3922025D01*
X-31410Y3922292D01*
X-32110Y3922425D01*
X-32810Y3922159D01*
X-33410Y3921625D01*
X-33810Y3920825D01*
X-34010Y3919759D01*
X-33810Y3918692D01*
X-33410Y3917892D01*
X-32810Y3917359D01*
X-32110Y3917092D01*
X-31410Y3917225D01*
X-30810Y3917625D01*
X-30410Y3918158D01*
G01X-25910Y3917092D02*
Y3922425D01*
G01Y3921092D02*
X-25510Y3921759D01*
X-24910Y3922292D01*
X-24110Y3922425D01*
X-23410Y3922292D01*
X-22810Y3921759D01*
X-22510Y3920825D01*
Y3917092D01*
G01X-16210Y3925092D02*
Y3917092D01*
G01X-17610Y3922425D02*
X-14810D01*
G01X-6410Y3917092D02*
Y3922425D01*
G01Y3921492D02*
X-6810Y3922025D01*
X-7410Y3922292D01*
X-8110Y3922425D01*
X-8810Y3922159D01*
X-9410Y3921625D01*
X-9810Y3920825D01*
X-10010Y3919759D01*
X-9810Y3918692D01*
X-9410Y3917892D01*
X-8810Y3917359D01*
X-8110Y3917092D01*
X-7410Y3917225D01*
X-6810Y3917625D01*
X-6410Y3918158D01*
G01X5890Y3917092D02*
Y3925092D01*
X9690D01*
G01X8290Y3921225D02*
X5890D01*
G01X13290Y3917092D02*
X15790Y3925092D01*
X18290Y3917092D01*
G01X17390Y3919892D02*
X14190D01*
G01X24590Y3921359D02*
X24990Y3921759D01*
X25290Y3922425D01*
X25490Y3923359D01*
X25290Y3924159D01*
X24890Y3924692D01*
X24190Y3925092D01*
X21490D01*
Y3917092D01*
X24790D01*
X25490Y3917625D01*
X25890Y3918425D01*
X26090Y3919359D01*
X25890Y3920292D01*
X25290Y3921092D01*
X24590Y3921359D01*
X21490D01*
G01X37490Y3917092D02*
Y3925092D01*
X42090Y3917092D01*
Y3925092D01*
G01X47790Y3917092D02*
X46990Y3917225D01*
X46290Y3917759D01*
X45690Y3918559D01*
X45290Y3919492D01*
X45090Y3920559D01*
Y3921625D01*
X45290Y3922692D01*
X45690Y3923625D01*
X46290Y3924425D01*
X46990Y3924959D01*
X47790Y3925092D01*
X48590Y3924959D01*
X49290Y3924425D01*
X49890Y3923625D01*
X50290Y3922692D01*
X50490Y3921625D01*
Y3920559D01*
X50290Y3919492D01*
X49890Y3918559D01*
X49290Y3917759D01*
X48590Y3917225D01*
X47790Y3917092D01*
G01X55790Y3925092D02*
Y3917092D01*
G01X53490Y3925092D02*
X58090D01*
G01X65790Y3917092D02*
X61790D01*
Y3925092D01*
X65790D01*
G01X64190Y3921225D02*
X61790D01*
G01X77790Y3917092D02*
Y3925092D01*
X80290D01*
X81090Y3924692D01*
X81590Y3924159D01*
X81790Y3923092D01*
X81590Y3922025D01*
X80990Y3921359D01*
X80290Y3920959D01*
X77790D01*
G01X80290D02*
X81790Y3917092D01*
G01X89790D02*
X85790D01*
Y3925092D01*
X89790D01*
G01X88190Y3921225D02*
X85790D01*
G01X93290Y3925092D02*
X95790Y3917092D01*
X98290Y3925092D01*
G01X103790Y3916825D02*
X103590Y3916959D01*
Y3917225D01*
X103790Y3917359D01*
X103990Y3917225D01*
Y3916959D01*
X103790Y3916825D01*
G01Y3920425D02*
X103590Y3920559D01*
Y3920825D01*
X103790Y3920959D01*
X103990Y3920825D01*
Y3920559D01*
X103790Y3920425D01*
G01X109890Y3917092D02*
Y3925092D01*
X113690D01*
G01X112290Y3921225D02*
X109890D01*
G01X-12910Y3363152D02*
X-25410D01*
X-16452Y3357417D01*
Y3365167D01*
G01X-12910Y3369662D02*
X-25410D01*
X-14993Y3373692D01*
X-25410Y3377722D01*
X-12910D01*
G01Y3382062D02*
X-25410D01*
X-14993Y3386092D01*
X-25410Y3390122D01*
X-12910D01*
G01X-22410Y3501359D02*
X-22010Y3501759D01*
X-21710Y3502425D01*
X-21510Y3503359D01*
X-21710Y3504159D01*
X-22110Y3504692D01*
X-22810Y3505092D01*
X-25510D01*
Y3497092D01*
X-22210D01*
X-21510Y3497625D01*
X-21110Y3498425D01*
X-20910Y3499359D01*
X-21110Y3500292D01*
X-21710Y3501092D01*
X-22410Y3501359D01*
X-25510D01*
G01X-15210Y3496825D02*
X-15410Y3496959D01*
Y3497225D01*
X-15210Y3497359D01*
X-15010Y3497225D01*
Y3496959D01*
X-15210Y3496825D01*
G01X-8410Y3505092D02*
X-6010D01*
G01X-7210D02*
Y3497092D01*
G01X-8410D02*
X-6010D01*
G01X-1110D02*
Y3505092D01*
X2690D01*
G01X1290Y3501225D02*
X-1110D01*
G01X16790Y3505092D02*
Y3497092D01*
G01X14490Y3505092D02*
X19090D01*
G01X22690Y3497092D02*
Y3505092D01*
G01X26890D02*
Y3497092D01*
G01Y3501092D02*
X22690D01*
G01X34790Y3497092D02*
X30790D01*
Y3505092D01*
X34790D01*
G01X33190Y3501225D02*
X30790D01*
G01X46790Y3497092D02*
Y3505092D01*
X49190D01*
X49990Y3504692D01*
X50590Y3503759D01*
X50790Y3502692D01*
X50590Y3501625D01*
X50090Y3500825D01*
X49190Y3500425D01*
X46790D01*
G01X56790Y3505092D02*
Y3497092D01*
G01X54490Y3505092D02*
X59090D01*
G01X62690Y3497092D02*
Y3505092D01*
G01X66890D02*
Y3497092D01*
G01Y3501092D02*
X62690D01*
G01X80790Y3505092D02*
Y3497092D01*
G01X78490Y3505092D02*
X83090D01*
G01X88790Y3497092D02*
X87990Y3497225D01*
X87290Y3497759D01*
X86690Y3498559D01*
X86290Y3499492D01*
X86090Y3500559D01*
Y3501625D01*
X86290Y3502692D01*
X86690Y3503625D01*
X87290Y3504425D01*
X87990Y3504959D01*
X88790Y3505092D01*
X89590Y3504959D01*
X90290Y3504425D01*
X90890Y3503625D01*
X91290Y3502692D01*
X91490Y3501625D01*
Y3500559D01*
X91290Y3499492D01*
X90890Y3498559D01*
X90290Y3497759D01*
X89590Y3497225D01*
X88790Y3497092D01*
G01X96790D02*
X95990Y3497225D01*
X95290Y3497759D01*
X94690Y3498559D01*
X94290Y3499492D01*
X94090Y3500559D01*
Y3501625D01*
X94290Y3502692D01*
X94690Y3503625D01*
X95290Y3504425D01*
X95990Y3504959D01*
X96790Y3505092D01*
X97590Y3504959D01*
X98290Y3504425D01*
X98890Y3503625D01*
X99290Y3502692D01*
X99490Y3501625D01*
Y3500559D01*
X99290Y3499492D01*
X98890Y3498559D01*
X98290Y3497759D01*
X97590Y3497225D01*
X96790Y3497092D01*
G01X102790Y3505092D02*
Y3497092D01*
X106790D01*
G01X111590Y3505092D02*
X113990D01*
G01X112790D02*
Y3497092D01*
G01X111590D02*
X113990D01*
G01X118490D02*
Y3505092D01*
X123090Y3497092D01*
Y3505092D01*
G01X129390Y3501092D02*
X131390D01*
Y3498692D01*
X130790Y3497892D01*
X130090Y3497359D01*
X129090Y3497092D01*
X128090Y3497359D01*
X127390Y3497892D01*
X126790Y3498692D01*
X126390Y3499625D01*
X126190Y3500692D01*
Y3501625D01*
X126390Y3502425D01*
X126790Y3503359D01*
X127390Y3504159D01*
X127990Y3504692D01*
X128790Y3505092D01*
X129490D01*
X130290Y3504825D01*
X130890Y3504292D01*
G01X142690Y3497092D02*
Y3505092D01*
G01X146890D02*
Y3497092D01*
G01Y3501092D02*
X142690D01*
G01X152790Y3497092D02*
X151990Y3497225D01*
X151290Y3497759D01*
X150690Y3498559D01*
X150290Y3499492D01*
X150090Y3500559D01*
Y3501625D01*
X150290Y3502692D01*
X150690Y3503625D01*
X151290Y3504425D01*
X151990Y3504959D01*
X152790Y3505092D01*
X153590Y3504959D01*
X154290Y3504425D01*
X154890Y3503625D01*
X155290Y3502692D01*
X155490Y3501625D01*
Y3500559D01*
X155290Y3499492D01*
X154890Y3498559D01*
X154290Y3497759D01*
X153590Y3497225D01*
X152790Y3497092D01*
G01X158790Y3505092D02*
Y3497092D01*
X162790D01*
G01X170790D02*
X166790D01*
Y3505092D01*
X170790D01*
G01X169190Y3501225D02*
X166790D01*
G01X183590Y3505092D02*
X185990D01*
G01X184790D02*
Y3497092D01*
G01X183590D02*
X185990D01*
G01X190690Y3498158D02*
X191490Y3497492D01*
X192390Y3497092D01*
X193190D01*
X193990Y3497492D01*
X194590Y3498158D01*
X194890Y3499092D01*
X194690Y3500025D01*
X194190Y3500825D01*
X193290Y3501359D01*
X192090Y3501625D01*
X191390Y3502159D01*
X191090Y3503092D01*
X191290Y3504025D01*
X191790Y3504692D01*
X192490Y3505092D01*
X193190D01*
X193890Y3504825D01*
X194490Y3504159D01*
G01X206190Y3497092D02*
Y3505092D01*
X208790Y3498425D01*
X211390Y3505092D01*
Y3497092D01*
G01X214290D02*
X216790Y3505092D01*
X219290Y3497092D01*
G01X218390Y3499892D02*
X215190D01*
G01X222590Y3497092D02*
Y3505092D01*
X224590D01*
X225390Y3504692D01*
X225990Y3504159D01*
X226490Y3503359D01*
X226890Y3502425D01*
X226990Y3501092D01*
X226890Y3499759D01*
X226490Y3498825D01*
X225990Y3498025D01*
X225390Y3497492D01*
X224590Y3497092D01*
X222590D01*
G01X234790D02*
X230790D01*
Y3505092D01*
X234790D01*
G01X233190Y3501225D02*
X230790D01*
G01X249590Y3501359D02*
X249990Y3501759D01*
X250290Y3502425D01*
X250490Y3503359D01*
X250290Y3504159D01*
X249890Y3504692D01*
X249190Y3505092D01*
X246490D01*
Y3497092D01*
X249790D01*
X250490Y3497625D01*
X250890Y3498425D01*
X251090Y3499359D01*
X250890Y3500292D01*
X250290Y3501092D01*
X249590Y3501359D01*
X246490D01*
G01X256790Y3497092D02*
Y3500692D01*
X254790Y3505092D01*
G01X258790D02*
X256790Y3500692D01*
G01X270790Y3497092D02*
Y3505092D01*
X273290D01*
X274090Y3504692D01*
X274590Y3504159D01*
X274790Y3503092D01*
X274590Y3502025D01*
X273990Y3501359D01*
X273290Y3500959D01*
X270790D01*
G01X273290D02*
X274790Y3497092D01*
G01X280790D02*
X279990Y3497225D01*
X279290Y3497759D01*
X278690Y3498559D01*
X278290Y3499492D01*
X278090Y3500559D01*
Y3501625D01*
X278290Y3502692D01*
X278690Y3503625D01*
X279290Y3504425D01*
X279990Y3504959D01*
X280790Y3505092D01*
X281590Y3504959D01*
X282290Y3504425D01*
X282890Y3503625D01*
X283290Y3502692D01*
X283490Y3501625D01*
Y3500559D01*
X283290Y3499492D01*
X282890Y3498559D01*
X282290Y3497759D01*
X281590Y3497225D01*
X280790Y3497092D01*
G01X286590Y3505092D02*
Y3499359D01*
X286990Y3498158D01*
X287790Y3497359D01*
X288790Y3497092D01*
X289790Y3497359D01*
X290590Y3498158D01*
X290990Y3499359D01*
Y3505092D01*
G01X296790D02*
Y3497092D01*
G01X294490Y3505092D02*
X299090D01*
G01X303590D02*
X305990D01*
G01X304790D02*
Y3497092D01*
G01X303590D02*
X305990D01*
G01X310490D02*
Y3505092D01*
X315090Y3497092D01*
Y3505092D01*
G01X321390Y3501092D02*
X323390D01*
Y3498692D01*
X322790Y3497892D01*
X322090Y3497359D01*
X321090Y3497092D01*
X320090Y3497359D01*
X319390Y3497892D01*
X318790Y3498692D01*
X318390Y3499625D01*
X318190Y3500692D01*
Y3501625D01*
X318390Y3502425D01*
X318790Y3503359D01*
X319390Y3504159D01*
X319990Y3504692D01*
X320790Y3505092D01*
X321490D01*
X322290Y3504825D01*
X322890Y3504292D01*
G01X328590Y3495625D02*
X328990Y3497359D01*
G01X342490Y3497092D02*
Y3505092D01*
X347090Y3497092D01*
Y3505092D01*
G01X352790Y3497092D02*
X351990Y3497225D01*
X351290Y3497759D01*
X350690Y3498559D01*
X350290Y3499492D01*
X350090Y3500559D01*
Y3501625D01*
X350290Y3502692D01*
X350690Y3503625D01*
X351290Y3504425D01*
X351990Y3504959D01*
X352790Y3505092D01*
X353590Y3504959D01*
X354290Y3504425D01*
X354890Y3503625D01*
X355290Y3502692D01*
X355490Y3501625D01*
Y3500559D01*
X355290Y3499492D01*
X354890Y3498559D01*
X354290Y3497759D01*
X353590Y3497225D01*
X352790Y3497092D01*
G01X358490D02*
Y3505092D01*
X363090Y3497092D01*
Y3505092D01*
G01X367490Y3499759D02*
X370090D01*
G01X374890Y3497092D02*
Y3505092D01*
X378690D01*
G01X377290Y3501225D02*
X374890D01*
G01X382590Y3505092D02*
Y3499359D01*
X382990Y3498158D01*
X383790Y3497359D01*
X384790Y3497092D01*
X385790Y3497359D01*
X386590Y3498158D01*
X386990Y3499359D01*
Y3505092D01*
G01X390490Y3497092D02*
Y3505092D01*
X395090Y3497092D01*
Y3505092D01*
G01X402990Y3504425D02*
X402390Y3504825D01*
X401690Y3505092D01*
X400890D01*
X399990Y3504692D01*
X399290Y3504025D01*
X398790Y3503225D01*
X398390Y3501892D01*
X398290Y3500692D01*
X398490Y3499492D01*
X398790Y3498692D01*
X399390Y3497892D01*
X400090Y3497359D01*
X400790Y3497092D01*
X401490D01*
X402190Y3497359D01*
X402790Y3497759D01*
X403290Y3498292D01*
G01X408790Y3505092D02*
Y3497092D01*
G01X406490Y3505092D02*
X411090D01*
G01X415590D02*
X417990D01*
G01X416790D02*
Y3497092D01*
G01X415590D02*
X417990D01*
G01X424790D02*
X423990Y3497225D01*
X423290Y3497759D01*
X422690Y3498559D01*
X422290Y3499492D01*
X422090Y3500559D01*
Y3501625D01*
X422290Y3502692D01*
X422690Y3503625D01*
X423290Y3504425D01*
X423990Y3504959D01*
X424790Y3505092D01*
X425590Y3504959D01*
X426290Y3504425D01*
X426890Y3503625D01*
X427290Y3502692D01*
X427490Y3501625D01*
Y3500559D01*
X427290Y3499492D01*
X426890Y3498559D01*
X426290Y3497759D01*
X425590Y3497225D01*
X424790Y3497092D01*
G01X430490D02*
Y3505092D01*
X435090Y3497092D01*
Y3505092D01*
G01X438290Y3497092D02*
X440790Y3505092D01*
X443290Y3497092D01*
G01X442390Y3499892D02*
X439190D01*
G01X446790Y3505092D02*
Y3497092D01*
X450790D01*
G01X462790D02*
Y3505092D01*
X465190D01*
X465990Y3504692D01*
X466590Y3503759D01*
X466790Y3502692D01*
X466590Y3501625D01*
X466090Y3500825D01*
X465190Y3500425D01*
X462790D01*
G01X470290Y3497092D02*
X472790Y3505092D01*
X475290Y3497092D01*
G01X474390Y3499892D02*
X471190D01*
G01X478590Y3497092D02*
Y3505092D01*
X480590D01*
X481390Y3504692D01*
X481990Y3504159D01*
X482490Y3503359D01*
X482890Y3502425D01*
X482990Y3501092D01*
X482890Y3499759D01*
X482490Y3498825D01*
X481990Y3498025D01*
X481390Y3497492D01*
X480590Y3497092D01*
X478590D01*
G01X494690Y3498158D02*
X495490Y3497492D01*
X496390Y3497092D01*
X497190D01*
X497990Y3497492D01*
X498590Y3498158D01*
X498890Y3499092D01*
X498690Y3500025D01*
X498190Y3500825D01*
X497290Y3501359D01*
X496090Y3501625D01*
X495390Y3502159D01*
X495090Y3503092D01*
X495290Y3504025D01*
X495790Y3504692D01*
X496490Y3505092D01*
X497190D01*
X497890Y3504825D01*
X498490Y3504159D01*
G01X503590Y3505092D02*
X505990D01*
G01X504790D02*
Y3497092D01*
G01X503590D02*
X505990D01*
G01X510890Y3505092D02*
X514690D01*
X510890Y3497092D01*
X514690D01*
G01X522790D02*
X518790D01*
Y3505092D01*
X522790D01*
G01X521190Y3501225D02*
X518790D01*
G01X535590Y3505092D02*
X537990D01*
G01X536790D02*
Y3497092D01*
G01X535590D02*
X537990D01*
G01X542690Y3498158D02*
X543490Y3497492D01*
X544390Y3497092D01*
X545190D01*
X545990Y3497492D01*
X546590Y3498158D01*
X546890Y3499092D01*
X546690Y3500025D01*
X546190Y3500825D01*
X545290Y3501359D01*
X544090Y3501625D01*
X543390Y3502159D01*
X543090Y3503092D01*
X543290Y3504025D01*
X543790Y3504692D01*
X544490Y3505092D01*
X545190D01*
X545890Y3504825D01*
X546490Y3504159D01*
G01X560790Y3505092D02*
Y3497092D01*
G01X558490Y3505092D02*
X563090D01*
G01X566690Y3497092D02*
Y3505092D01*
G01X570890D02*
Y3497092D01*
G01Y3501092D02*
X566690D01*
G01X578790Y3497092D02*
X574790D01*
Y3505092D01*
X578790D01*
G01X577190Y3501225D02*
X574790D01*
G01X590790Y3497092D02*
Y3505092D01*
X593190D01*
X593990Y3504692D01*
X594590Y3503759D01*
X594790Y3502692D01*
X594590Y3501625D01*
X594090Y3500825D01*
X593190Y3500425D01*
X590790D01*
G01X598790Y3497092D02*
Y3505092D01*
X601290D01*
X602090Y3504692D01*
X602590Y3504159D01*
X602790Y3503092D01*
X602590Y3502025D01*
X601990Y3501359D01*
X601290Y3500959D01*
X598790D01*
G01X601290D02*
X602790Y3497092D01*
G01X608790D02*
X607990Y3497225D01*
X607290Y3497759D01*
X606690Y3498559D01*
X606290Y3499492D01*
X606090Y3500559D01*
Y3501625D01*
X606290Y3502692D01*
X606690Y3503625D01*
X607290Y3504425D01*
X607990Y3504959D01*
X608790Y3505092D01*
X609590Y3504959D01*
X610290Y3504425D01*
X610890Y3503625D01*
X611290Y3502692D01*
X611490Y3501625D01*
Y3500559D01*
X611290Y3499492D01*
X610890Y3498559D01*
X610290Y3497759D01*
X609590Y3497225D01*
X608790Y3497092D01*
G01X614890D02*
Y3505092D01*
X618690D01*
G01X617290Y3501225D02*
X614890D01*
G01X623590Y3505092D02*
X625990D01*
G01X624790D02*
Y3497092D01*
G01X623590D02*
X625990D01*
G01X630790Y3505092D02*
Y3497092D01*
X634790D01*
G01X642790D02*
X638790D01*
Y3505092D01*
X642790D01*
G01X641190Y3501225D02*
X638790D01*
G01X654690Y3498158D02*
X655490Y3497492D01*
X656390Y3497092D01*
X657190D01*
X657990Y3497492D01*
X658590Y3498158D01*
X658890Y3499092D01*
X658690Y3500025D01*
X658190Y3500825D01*
X657290Y3501359D01*
X656090Y3501625D01*
X655390Y3502159D01*
X655090Y3503092D01*
X655290Y3504025D01*
X655790Y3504692D01*
X656490Y3505092D01*
X657190D01*
X657890Y3504825D01*
X658490Y3504159D01*
G01X663590Y3505092D02*
X665990D01*
G01X664790D02*
Y3497092D01*
G01X663590D02*
X665990D01*
G01X670890Y3505092D02*
X674690D01*
X670890Y3497092D01*
X674690D01*
G01X682790D02*
X678790D01*
Y3505092D01*
X682790D01*
G01X681190Y3501225D02*
X678790D01*
G01X695690Y3499759D02*
X698090D01*
G01X696790Y3501492D02*
Y3498025D01*
G01X710890Y3503759D02*
X711490Y3504559D01*
X712190Y3504959D01*
X712990Y3505092D01*
X713990Y3504825D01*
X714690Y3504159D01*
X714890Y3503359D01*
X714790Y3502558D01*
X714390Y3501892D01*
X712390Y3500559D01*
X711490Y3499625D01*
X710890Y3498292D01*
X710690Y3497092D01*
X714890D01*
G01X720790Y3505092D02*
X719990Y3504825D01*
X719390Y3504159D01*
X718990Y3503359D01*
X718690Y3502292D01*
X718590Y3501092D01*
X718690Y3499892D01*
X718990Y3498825D01*
X719390Y3498025D01*
X719990Y3497359D01*
X720790Y3497092D01*
X721590Y3497359D01*
X722190Y3498025D01*
X722590Y3498825D01*
X722890Y3499892D01*
X722990Y3501092D01*
X722890Y3502292D01*
X722590Y3503359D01*
X722190Y3504159D01*
X721590Y3504825D01*
X720790Y3505092D01*
G01X726190Y3497092D02*
Y3505092D01*
X728790Y3498425D01*
X731390Y3505092D01*
Y3497092D01*
G01X735590Y3505092D02*
X737990D01*
G01X736790D02*
Y3497092D01*
G01X735590D02*
X737990D01*
G01X742790Y3505092D02*
Y3497092D01*
X746790D01*
G01X-25710Y3512092D02*
X-23210Y3520092D01*
X-20710Y3512092D01*
G01X-21610Y3514892D02*
X-24810D01*
G01X-15210Y3511825D02*
X-15410Y3511959D01*
Y3512225D01*
X-15210Y3512359D01*
X-15010Y3512225D01*
Y3511959D01*
X-15210Y3511825D01*
G01X-8410Y3520092D02*
X-6010D01*
G01X-7210D02*
Y3512092D01*
G01X-8410D02*
X-6010D01*
G01X-1110D02*
Y3520092D01*
X2690D01*
G01X1290Y3516225D02*
X-1110D01*
G01X16790Y3520092D02*
Y3512092D01*
G01X14490Y3520092D02*
X19090D01*
G01X22690Y3512092D02*
Y3520092D01*
G01X26890D02*
Y3512092D01*
G01Y3516092D02*
X22690D01*
G01X34790Y3512092D02*
X30790D01*
Y3520092D01*
X34790D01*
G01X33190Y3516225D02*
X30790D01*
G01X46790Y3512092D02*
Y3520092D01*
X49190D01*
X49990Y3519692D01*
X50590Y3518759D01*
X50790Y3517692D01*
X50590Y3516625D01*
X50090Y3515825D01*
X49190Y3515425D01*
X46790D01*
G01X56790Y3520092D02*
Y3512092D01*
G01X54490Y3520092D02*
X59090D01*
G01X62690Y3512092D02*
Y3520092D01*
G01X66890D02*
Y3512092D01*
G01Y3516092D02*
X62690D01*
G01X80790Y3520092D02*
Y3512092D01*
G01X78490Y3520092D02*
X83090D01*
G01X88790Y3512092D02*
X87990Y3512225D01*
X87290Y3512759D01*
X86690Y3513559D01*
X86290Y3514492D01*
X86090Y3515559D01*
Y3516625D01*
X86290Y3517692D01*
X86690Y3518625D01*
X87290Y3519425D01*
X87990Y3519959D01*
X88790Y3520092D01*
X89590Y3519959D01*
X90290Y3519425D01*
X90890Y3518625D01*
X91290Y3517692D01*
X91490Y3516625D01*
Y3515559D01*
X91290Y3514492D01*
X90890Y3513559D01*
X90290Y3512759D01*
X89590Y3512225D01*
X88790Y3512092D01*
G01X96790D02*
X95990Y3512225D01*
X95290Y3512759D01*
X94690Y3513559D01*
X94290Y3514492D01*
X94090Y3515559D01*
Y3516625D01*
X94290Y3517692D01*
X94690Y3518625D01*
X95290Y3519425D01*
X95990Y3519959D01*
X96790Y3520092D01*
X97590Y3519959D01*
X98290Y3519425D01*
X98890Y3518625D01*
X99290Y3517692D01*
X99490Y3516625D01*
Y3515559D01*
X99290Y3514492D01*
X98890Y3513559D01*
X98290Y3512759D01*
X97590Y3512225D01*
X96790Y3512092D01*
G01X102790Y3520092D02*
Y3512092D01*
X106790D01*
G01X111590Y3520092D02*
X113990D01*
G01X112790D02*
Y3512092D01*
G01X111590D02*
X113990D01*
G01X118490D02*
Y3520092D01*
X123090Y3512092D01*
Y3520092D01*
G01X129390Y3516092D02*
X131390D01*
Y3513692D01*
X130790Y3512892D01*
X130090Y3512359D01*
X129090Y3512092D01*
X128090Y3512359D01*
X127390Y3512892D01*
X126790Y3513692D01*
X126390Y3514625D01*
X126190Y3515692D01*
Y3516625D01*
X126390Y3517425D01*
X126790Y3518359D01*
X127390Y3519159D01*
X127990Y3519692D01*
X128790Y3520092D01*
X129490D01*
X130290Y3519825D01*
X130890Y3519292D01*
G01X142690Y3512092D02*
Y3520092D01*
G01X146890D02*
Y3512092D01*
G01Y3516092D02*
X142690D01*
G01X152790Y3512092D02*
X151990Y3512225D01*
X151290Y3512759D01*
X150690Y3513559D01*
X150290Y3514492D01*
X150090Y3515559D01*
Y3516625D01*
X150290Y3517692D01*
X150690Y3518625D01*
X151290Y3519425D01*
X151990Y3519959D01*
X152790Y3520092D01*
X153590Y3519959D01*
X154290Y3519425D01*
X154890Y3518625D01*
X155290Y3517692D01*
X155490Y3516625D01*
Y3515559D01*
X155290Y3514492D01*
X154890Y3513559D01*
X154290Y3512759D01*
X153590Y3512225D01*
X152790Y3512092D01*
G01X158790Y3520092D02*
Y3512092D01*
X162790D01*
G01X170790D02*
X166790D01*
Y3520092D01*
X170790D01*
G01X169190Y3516225D02*
X166790D01*
G01X183590Y3520092D02*
X185990D01*
G01X184790D02*
Y3512092D01*
G01X183590D02*
X185990D01*
G01X190690Y3513158D02*
X191490Y3512492D01*
X192390Y3512092D01*
X193190D01*
X193990Y3512492D01*
X194590Y3513158D01*
X194890Y3514092D01*
X194690Y3515025D01*
X194190Y3515825D01*
X193290Y3516359D01*
X192090Y3516625D01*
X191390Y3517159D01*
X191090Y3518092D01*
X191290Y3519025D01*
X191790Y3519692D01*
X192490Y3520092D01*
X193190D01*
X193890Y3519825D01*
X194490Y3519159D01*
G01X206190Y3512092D02*
Y3520092D01*
X208790Y3513425D01*
X211390Y3520092D01*
Y3512092D01*
G01X214290D02*
X216790Y3520092D01*
X219290Y3512092D01*
G01X218390Y3514892D02*
X215190D01*
G01X222590Y3512092D02*
Y3520092D01*
X224590D01*
X225390Y3519692D01*
X225990Y3519159D01*
X226490Y3518359D01*
X226890Y3517425D01*
X226990Y3516092D01*
X226890Y3514759D01*
X226490Y3513825D01*
X225990Y3513025D01*
X225390Y3512492D01*
X224590Y3512092D01*
X222590D01*
G01X234790D02*
X230790D01*
Y3520092D01*
X234790D01*
G01X233190Y3516225D02*
X230790D01*
G01X249590Y3516359D02*
X249990Y3516759D01*
X250290Y3517425D01*
X250490Y3518359D01*
X250290Y3519159D01*
X249890Y3519692D01*
X249190Y3520092D01*
X246490D01*
Y3512092D01*
X249790D01*
X250490Y3512625D01*
X250890Y3513425D01*
X251090Y3514359D01*
X250890Y3515292D01*
X250290Y3516092D01*
X249590Y3516359D01*
X246490D01*
G01X256790Y3512092D02*
Y3515692D01*
X254790Y3520092D01*
G01X258790D02*
X256790Y3515692D01*
G01X270590Y3512092D02*
Y3520092D01*
X272590D01*
X273390Y3519692D01*
X273990Y3519159D01*
X274490Y3518359D01*
X274890Y3517425D01*
X274990Y3516092D01*
X274890Y3514759D01*
X274490Y3513825D01*
X273990Y3513025D01*
X273390Y3512492D01*
X272590Y3512092D01*
X270590D01*
G01X278790D02*
Y3520092D01*
X281290D01*
X282090Y3519692D01*
X282590Y3519159D01*
X282790Y3518092D01*
X282590Y3517025D01*
X281990Y3516359D01*
X281290Y3515959D01*
X278790D01*
G01X281290D02*
X282790Y3512092D01*
G01X287590Y3520092D02*
X289990D01*
G01X288790D02*
Y3512092D01*
G01X287590D02*
X289990D01*
G01X294790Y3520092D02*
Y3512092D01*
X298790D01*
G01X302790Y3520092D02*
Y3512092D01*
X306790D01*
G01X311590Y3520092D02*
X313990D01*
G01X312790D02*
Y3512092D01*
G01X311590D02*
X313990D01*
G01X318490D02*
Y3520092D01*
X323090Y3512092D01*
Y3520092D01*
G01X329390Y3516092D02*
X331390D01*
Y3513692D01*
X330790Y3512892D01*
X330090Y3512359D01*
X329090Y3512092D01*
X328090Y3512359D01*
X327390Y3512892D01*
X326790Y3513692D01*
X326390Y3514625D01*
X326190Y3515692D01*
Y3516625D01*
X326390Y3517425D01*
X326790Y3518359D01*
X327390Y3519159D01*
X327990Y3519692D01*
X328790Y3520092D01*
X329490D01*
X330290Y3519825D01*
X330890Y3519292D01*
G01X336590Y3510625D02*
X336990Y3512359D01*
G01X350490Y3512092D02*
Y3520092D01*
X355090Y3512092D01*
Y3520092D01*
G01X360790Y3512092D02*
X359990Y3512225D01*
X359290Y3512759D01*
X358690Y3513559D01*
X358290Y3514492D01*
X358090Y3515559D01*
Y3516625D01*
X358290Y3517692D01*
X358690Y3518625D01*
X359290Y3519425D01*
X359990Y3519959D01*
X360790Y3520092D01*
X361590Y3519959D01*
X362290Y3519425D01*
X362890Y3518625D01*
X363290Y3517692D01*
X363490Y3516625D01*
Y3515559D01*
X363290Y3514492D01*
X362890Y3513559D01*
X362290Y3512759D01*
X361590Y3512225D01*
X360790Y3512092D01*
G01X366490D02*
Y3520092D01*
X371090Y3512092D01*
Y3520092D01*
G01X375490Y3514759D02*
X378090D01*
G01X382890Y3512092D02*
Y3520092D01*
X386690D01*
G01X385290Y3516225D02*
X382890D01*
G01X390590Y3520092D02*
Y3514359D01*
X390990Y3513158D01*
X391790Y3512359D01*
X392790Y3512092D01*
X393790Y3512359D01*
X394590Y3513158D01*
X394990Y3514359D01*
Y3520092D01*
G01X398490Y3512092D02*
Y3520092D01*
X403090Y3512092D01*
Y3520092D01*
G01X410990Y3519425D02*
X410390Y3519825D01*
X409690Y3520092D01*
X408890D01*
X407990Y3519692D01*
X407290Y3519025D01*
X406790Y3518225D01*
X406390Y3516892D01*
X406290Y3515692D01*
X406490Y3514492D01*
X406790Y3513692D01*
X407390Y3512892D01*
X408090Y3512359D01*
X408790Y3512092D01*
X409490D01*
X410190Y3512359D01*
X410790Y3512759D01*
X411290Y3513292D01*
G01X416790Y3520092D02*
Y3512092D01*
G01X414490Y3520092D02*
X419090D01*
G01X423590D02*
X425990D01*
G01X424790D02*
Y3512092D01*
G01X423590D02*
X425990D01*
G01X432790D02*
X431990Y3512225D01*
X431290Y3512759D01*
X430690Y3513559D01*
X430290Y3514492D01*
X430090Y3515559D01*
Y3516625D01*
X430290Y3517692D01*
X430690Y3518625D01*
X431290Y3519425D01*
X431990Y3519959D01*
X432790Y3520092D01*
X433590Y3519959D01*
X434290Y3519425D01*
X434890Y3518625D01*
X435290Y3517692D01*
X435490Y3516625D01*
Y3515559D01*
X435290Y3514492D01*
X434890Y3513559D01*
X434290Y3512759D01*
X433590Y3512225D01*
X432790Y3512092D01*
G01X438490D02*
Y3520092D01*
X443090Y3512092D01*
Y3520092D01*
G01X446290Y3512092D02*
X448790Y3520092D01*
X451290Y3512092D01*
G01X450390Y3514892D02*
X447190D01*
G01X454790Y3520092D02*
Y3512092D01*
X458790D01*
G01X470790D02*
Y3520092D01*
X473190D01*
X473990Y3519692D01*
X474590Y3518759D01*
X474790Y3517692D01*
X474590Y3516625D01*
X474090Y3515825D01*
X473190Y3515425D01*
X470790D01*
G01X478290Y3512092D02*
X480790Y3520092D01*
X483290Y3512092D01*
G01X482390Y3514892D02*
X479190D01*
G01X486590Y3512092D02*
Y3520092D01*
X488590D01*
X489390Y3519692D01*
X489990Y3519159D01*
X490490Y3518359D01*
X490890Y3517425D01*
X490990Y3516092D01*
X490890Y3514759D01*
X490490Y3513825D01*
X489990Y3513025D01*
X489390Y3512492D01*
X488590Y3512092D01*
X486590D01*
G01X502690Y3513158D02*
X503490Y3512492D01*
X504390Y3512092D01*
X505190D01*
X505990Y3512492D01*
X506590Y3513158D01*
X506890Y3514092D01*
X506690Y3515025D01*
X506190Y3515825D01*
X505290Y3516359D01*
X504090Y3516625D01*
X503390Y3517159D01*
X503090Y3518092D01*
X503290Y3519025D01*
X503790Y3519692D01*
X504490Y3520092D01*
X505190D01*
X505890Y3519825D01*
X506490Y3519159D01*
G01X511590Y3520092D02*
X513990D01*
G01X512790D02*
Y3512092D01*
G01X511590D02*
X513990D01*
G01X518890Y3520092D02*
X522690D01*
X518890Y3512092D01*
X522690D01*
G01X530790D02*
X526790D01*
Y3520092D01*
X530790D01*
G01X529190Y3516225D02*
X526790D01*
G01X543590Y3520092D02*
X545990D01*
G01X544790D02*
Y3512092D01*
G01X543590D02*
X545990D01*
G01X550690Y3513158D02*
X551490Y3512492D01*
X552390Y3512092D01*
X553190D01*
X553990Y3512492D01*
X554590Y3513158D01*
X554890Y3514092D01*
X554690Y3515025D01*
X554190Y3515825D01*
X553290Y3516359D01*
X552090Y3516625D01*
X551390Y3517159D01*
X551090Y3518092D01*
X551290Y3519025D01*
X551790Y3519692D01*
X552490Y3520092D01*
X553190D01*
X553890Y3519825D01*
X554490Y3519159D01*
G01X568790Y3520092D02*
Y3512092D01*
G01X566490Y3520092D02*
X571090D01*
G01X574690Y3512092D02*
Y3520092D01*
G01X578890D02*
Y3512092D01*
G01Y3516092D02*
X574690D01*
G01X586790Y3512092D02*
X582790D01*
Y3520092D01*
X586790D01*
G01X585190Y3516225D02*
X582790D01*
G01X598590Y3512092D02*
Y3520092D01*
X600590D01*
X601390Y3519692D01*
X601990Y3519159D01*
X602490Y3518359D01*
X602890Y3517425D01*
X602990Y3516092D01*
X602890Y3514759D01*
X602490Y3513825D01*
X601990Y3513025D01*
X601390Y3512492D01*
X600590Y3512092D01*
X598590D01*
G01X606790D02*
Y3520092D01*
X609290D01*
X610090Y3519692D01*
X610590Y3519159D01*
X610790Y3518092D01*
X610590Y3517025D01*
X609990Y3516359D01*
X609290Y3515959D01*
X606790D01*
G01X609290D02*
X610790Y3512092D01*
G01X615590Y3520092D02*
X617990D01*
G01X616790D02*
Y3512092D01*
G01X615590D02*
X617990D01*
G01X622790Y3520092D02*
Y3512092D01*
X626790D01*
G01X630790Y3520092D02*
Y3512092D01*
X634790D01*
G01X646690Y3513158D02*
X647490Y3512492D01*
X648390Y3512092D01*
X649190D01*
X649990Y3512492D01*
X650590Y3513158D01*
X650890Y3514092D01*
X650690Y3515025D01*
X650190Y3515825D01*
X649290Y3516359D01*
X648090Y3516625D01*
X647390Y3517159D01*
X647090Y3518092D01*
X647290Y3519025D01*
X647790Y3519692D01*
X648490Y3520092D01*
X649190D01*
X649890Y3519825D01*
X650490Y3519159D01*
G01X655590Y3520092D02*
X657990D01*
G01X656790D02*
Y3512092D01*
G01X655590D02*
X657990D01*
G01X662890Y3520092D02*
X666690D01*
X662890Y3512092D01*
X666690D01*
G01X674790D02*
X670790D01*
Y3520092D01*
X674790D01*
G01X673190Y3516225D02*
X670790D01*
G01X687690Y3514759D02*
X690090D01*
G01X688790Y3516492D02*
Y3513025D01*
G01X704790Y3512092D02*
Y3520092D01*
X703590Y3518492D01*
G01Y3512092D02*
X705990D01*
G01X712790Y3520092D02*
X711990Y3519825D01*
X711390Y3519159D01*
X710990Y3518359D01*
X710690Y3517292D01*
X710590Y3516092D01*
X710690Y3514892D01*
X710990Y3513825D01*
X711390Y3513025D01*
X711990Y3512359D01*
X712790Y3512092D01*
X713590Y3512359D01*
X714190Y3513025D01*
X714590Y3513825D01*
X714890Y3514892D01*
X714990Y3516092D01*
X714890Y3517292D01*
X714590Y3518359D01*
X714190Y3519159D01*
X713590Y3519825D01*
X712790Y3520092D01*
G01X718190Y3512092D02*
Y3520092D01*
X720790Y3513425D01*
X723390Y3520092D01*
Y3512092D01*
G01X727590Y3520092D02*
X729990D01*
G01X728790D02*
Y3512092D01*
G01X727590D02*
X729990D01*
G01X734790Y3520092D02*
Y3512092D01*
X738790D01*
G01X-32610Y3621092D02*
X-30610D01*
Y3618692D01*
X-31210Y3617892D01*
X-31910Y3617359D01*
X-32910Y3617092D01*
X-33910Y3617359D01*
X-34610Y3617892D01*
X-35210Y3618692D01*
X-35610Y3619625D01*
X-35810Y3620692D01*
Y3621625D01*
X-35610Y3622425D01*
X-35210Y3623359D01*
X-34610Y3624159D01*
X-34010Y3624692D01*
X-33210Y3625092D01*
X-32510D01*
X-31710Y3624825D01*
X-31110Y3624292D01*
G01X-27210Y3617092D02*
Y3625092D01*
X-24710D01*
X-23910Y3624692D01*
X-23410Y3624159D01*
X-23210Y3623092D01*
X-23410Y3622025D01*
X-24010Y3621359D01*
X-24710Y3620959D01*
X-27210D01*
G01X-24710D02*
X-23210Y3617092D01*
G01X-17210D02*
X-18010Y3617225D01*
X-18710Y3617759D01*
X-19310Y3618559D01*
X-19710Y3619492D01*
X-19910Y3620559D01*
Y3621625D01*
X-19710Y3622692D01*
X-19310Y3623625D01*
X-18710Y3624425D01*
X-18010Y3624959D01*
X-17210Y3625092D01*
X-16410Y3624959D01*
X-15710Y3624425D01*
X-15110Y3623625D01*
X-14710Y3622692D01*
X-14510Y3621625D01*
Y3620559D01*
X-14710Y3619492D01*
X-15110Y3618559D01*
X-15710Y3617759D01*
X-16410Y3617225D01*
X-17210Y3617092D01*
G01X-11410Y3625092D02*
Y3619359D01*
X-11010Y3618158D01*
X-10210Y3617359D01*
X-9210Y3617092D01*
X-8210Y3617359D01*
X-7410Y3618158D01*
X-7010Y3619359D01*
Y3625092D01*
G01X-3210Y3617092D02*
Y3625092D01*
X-810D01*
X-10Y3624692D01*
X590Y3623759D01*
X790Y3622692D01*
X590Y3621625D01*
X90Y3620825D01*
X-810Y3620425D01*
X-3210D01*
G01X4690Y3618158D02*
X5490Y3617492D01*
X6390Y3617092D01*
X7190D01*
X7990Y3617492D01*
X8590Y3618158D01*
X8890Y3619092D01*
X8690Y3620025D01*
X8190Y3620825D01*
X7290Y3621359D01*
X6090Y3621625D01*
X5390Y3622159D01*
X5090Y3623092D01*
X5290Y3624025D01*
X5790Y3624692D01*
X6490Y3625092D01*
X7190D01*
X7890Y3624825D01*
X8490Y3624159D01*
G01X20290Y3617092D02*
X22790Y3625092D01*
X25290Y3617092D01*
G01X24390Y3619892D02*
X21190D01*
G01X36290Y3617092D02*
X38790Y3625092D01*
X41290Y3617092D01*
G01X40390Y3619892D02*
X37190D01*
G01X44490Y3617092D02*
Y3625092D01*
X49090Y3617092D01*
Y3625092D01*
G01X52590Y3617092D02*
Y3625092D01*
X54590D01*
X55390Y3624692D01*
X55990Y3624159D01*
X56490Y3623359D01*
X56890Y3622425D01*
X56990Y3621092D01*
X56890Y3619759D01*
X56490Y3618825D01*
X55990Y3618025D01*
X55390Y3617492D01*
X54590Y3617092D01*
X52590D01*
G01X71590Y3621359D02*
X71990Y3621759D01*
X72290Y3622425D01*
X72490Y3623359D01*
X72290Y3624159D01*
X71890Y3624692D01*
X71190Y3625092D01*
X68490D01*
Y3617092D01*
X71790D01*
X72490Y3617625D01*
X72890Y3618425D01*
X73090Y3619359D01*
X72890Y3620292D01*
X72290Y3621092D01*
X71590Y3621359D01*
X68490D01*
G01X78590Y3615625D02*
X78990Y3617359D01*
G01X86790Y3625092D02*
Y3617092D01*
G01X84490Y3625092D02*
X89090D01*
G01X92690Y3617092D02*
Y3625092D01*
G01X96890D02*
Y3617092D01*
G01Y3621092D02*
X92690D01*
G01X104790Y3617092D02*
X100790D01*
Y3625092D01*
X104790D01*
G01X103190Y3621225D02*
X100790D01*
G01X108490Y3617092D02*
Y3625092D01*
X113090Y3617092D01*
Y3625092D01*
G01X127390Y3621092D02*
X129390D01*
Y3618692D01*
X128790Y3617892D01*
X128090Y3617359D01*
X127090Y3617092D01*
X126090Y3617359D01*
X125390Y3617892D01*
X124790Y3618692D01*
X124390Y3619625D01*
X124190Y3620692D01*
Y3621625D01*
X124390Y3622425D01*
X124790Y3623359D01*
X125390Y3624159D01*
X125990Y3624692D01*
X126790Y3625092D01*
X127490D01*
X128290Y3624825D01*
X128890Y3624292D01*
G01X132790Y3617092D02*
Y3625092D01*
X135290D01*
X136090Y3624692D01*
X136590Y3624159D01*
X136790Y3623092D01*
X136590Y3622025D01*
X135990Y3621359D01*
X135290Y3620959D01*
X132790D01*
G01X135290D02*
X136790Y3617092D01*
G01X142790D02*
X141990Y3617225D01*
X141290Y3617759D01*
X140690Y3618559D01*
X140290Y3619492D01*
X140090Y3620559D01*
Y3621625D01*
X140290Y3622692D01*
X140690Y3623625D01*
X141290Y3624425D01*
X141990Y3624959D01*
X142790Y3625092D01*
X143590Y3624959D01*
X144290Y3624425D01*
X144890Y3623625D01*
X145290Y3622692D01*
X145490Y3621625D01*
Y3620559D01*
X145290Y3619492D01*
X144890Y3618559D01*
X144290Y3617759D01*
X143590Y3617225D01*
X142790Y3617092D01*
G01X148590Y3625092D02*
Y3619359D01*
X148990Y3618158D01*
X149790Y3617359D01*
X150790Y3617092D01*
X151790Y3617359D01*
X152590Y3618158D01*
X152990Y3619359D01*
Y3625092D01*
G01X156790Y3617092D02*
Y3625092D01*
X159190D01*
X159990Y3624692D01*
X160590Y3623759D01*
X160790Y3622692D01*
X160590Y3621625D01*
X160090Y3620825D01*
X159190Y3620425D01*
X156790D01*
G01X172290Y3617092D02*
X174790Y3625092D01*
X177290Y3617092D01*
G01X176390Y3619892D02*
X173190D01*
G01X192990Y3624425D02*
X192390Y3624825D01*
X191690Y3625092D01*
X190890D01*
X189990Y3624692D01*
X189290Y3624025D01*
X188790Y3623225D01*
X188390Y3621892D01*
X188290Y3620692D01*
X188490Y3619492D01*
X188790Y3618692D01*
X189390Y3617892D01*
X190090Y3617359D01*
X190790Y3617092D01*
X191490D01*
X192190Y3617359D01*
X192790Y3617759D01*
X193290Y3618292D01*
G01X196290Y3617092D02*
X198790Y3625092D01*
X201290Y3617092D01*
G01X200390Y3619892D02*
X197190D01*
G01X204490Y3617092D02*
Y3625092D01*
X209090Y3617092D01*
Y3625092D01*
G01X223590Y3621359D02*
X223990Y3621759D01*
X224290Y3622425D01*
X224490Y3623359D01*
X224290Y3624159D01*
X223890Y3624692D01*
X223190Y3625092D01*
X220490D01*
Y3617092D01*
X223790D01*
X224490Y3617625D01*
X224890Y3618425D01*
X225090Y3619359D01*
X224890Y3620292D01*
X224290Y3621092D01*
X223590Y3621359D01*
X220490D01*
G01X232790Y3617092D02*
X228790D01*
Y3625092D01*
X232790D01*
G01X231190Y3621225D02*
X228790D01*
G01X244790Y3617092D02*
Y3625092D01*
X247190D01*
X247990Y3624692D01*
X248590Y3623759D01*
X248790Y3622692D01*
X248590Y3621625D01*
X248090Y3620825D01*
X247190Y3620425D01*
X244790D01*
G01X252790Y3625092D02*
Y3617092D01*
X256790D01*
G01X260290D02*
X262790Y3625092D01*
X265290Y3617092D01*
G01X264390Y3619892D02*
X261190D01*
G01X272990Y3624425D02*
X272390Y3624825D01*
X271690Y3625092D01*
X270890D01*
X269990Y3624692D01*
X269290Y3624025D01*
X268790Y3623225D01*
X268390Y3621892D01*
X268290Y3620692D01*
X268490Y3619492D01*
X268790Y3618692D01*
X269390Y3617892D01*
X270090Y3617359D01*
X270790Y3617092D01*
X271490D01*
X272190Y3617359D01*
X272790Y3617759D01*
X273290Y3618292D01*
G01X280790Y3617092D02*
X276790D01*
Y3625092D01*
X280790D01*
G01X279190Y3621225D02*
X276790D01*
G01X284590Y3617092D02*
Y3625092D01*
X286590D01*
X287390Y3624692D01*
X287990Y3624159D01*
X288490Y3623359D01*
X288890Y3622425D01*
X288990Y3621092D01*
X288890Y3619759D01*
X288490Y3618825D01*
X287990Y3618025D01*
X287390Y3617492D01*
X286590Y3617092D01*
X284590D01*
G01X300690Y3618158D02*
X301490Y3617492D01*
X302390Y3617092D01*
X303190D01*
X303990Y3617492D01*
X304590Y3618158D01*
X304890Y3619092D01*
X304690Y3620025D01*
X304190Y3620825D01*
X303290Y3621359D01*
X302090Y3621625D01*
X301390Y3622159D01*
X301090Y3623092D01*
X301290Y3624025D01*
X301790Y3624692D01*
X302490Y3625092D01*
X303190D01*
X303890Y3624825D01*
X304490Y3624159D01*
G01X312790Y3617092D02*
X308790D01*
Y3625092D01*
X312790D01*
G01X311190Y3621225D02*
X308790D01*
G01X316790Y3617092D02*
Y3625092D01*
X319190D01*
X319990Y3624692D01*
X320590Y3623759D01*
X320790Y3622692D01*
X320590Y3621625D01*
X320090Y3620825D01*
X319190Y3620425D01*
X316790D01*
G01X324290Y3617092D02*
X326790Y3625092D01*
X329290Y3617092D01*
G01X328390Y3619892D02*
X325190D01*
G01X332790Y3617092D02*
Y3625092D01*
X335290D01*
X336090Y3624692D01*
X336590Y3624159D01*
X336790Y3623092D01*
X336590Y3622025D01*
X335990Y3621359D01*
X335290Y3620959D01*
X332790D01*
G01X335290D02*
X336790Y3617092D01*
G01X340290D02*
X342790Y3625092D01*
X345290Y3617092D01*
G01X344390Y3619892D02*
X341190D01*
G01X350790Y3625092D02*
Y3617092D01*
G01X348490Y3625092D02*
X353090D01*
G01X360790Y3617092D02*
X356790D01*
Y3625092D01*
X360790D01*
G01X359190Y3621225D02*
X356790D01*
G01X364790Y3625092D02*
Y3617092D01*
X368790D01*
G01X374790D02*
Y3620692D01*
X372790Y3625092D01*
G01X376790D02*
X374790Y3620692D01*
G01X388890Y3617092D02*
Y3625092D01*
X392690D01*
G01X391290Y3621225D02*
X388890D01*
G01X396790Y3617092D02*
Y3625092D01*
X399290D01*
X400090Y3624692D01*
X400590Y3624159D01*
X400790Y3623092D01*
X400590Y3622025D01*
X399990Y3621359D01*
X399290Y3620959D01*
X396790D01*
G01X399290D02*
X400790Y3617092D01*
G01X406790D02*
X405990Y3617225D01*
X405290Y3617759D01*
X404690Y3618559D01*
X404290Y3619492D01*
X404090Y3620559D01*
Y3621625D01*
X404290Y3622692D01*
X404690Y3623625D01*
X405290Y3624425D01*
X405990Y3624959D01*
X406790Y3625092D01*
X407590Y3624959D01*
X408290Y3624425D01*
X408890Y3623625D01*
X409290Y3622692D01*
X409490Y3621625D01*
Y3620559D01*
X409290Y3619492D01*
X408890Y3618559D01*
X408290Y3617759D01*
X407590Y3617225D01*
X406790Y3617092D01*
G01X412190D02*
Y3625092D01*
X414790Y3618425D01*
X417390Y3625092D01*
Y3617092D01*
G01X431390Y3621092D02*
X433390D01*
Y3618692D01*
X432790Y3617892D01*
X432090Y3617359D01*
X431090Y3617092D01*
X430090Y3617359D01*
X429390Y3617892D01*
X428790Y3618692D01*
X428390Y3619625D01*
X428190Y3620692D01*
Y3621625D01*
X428390Y3622425D01*
X428790Y3623359D01*
X429390Y3624159D01*
X429990Y3624692D01*
X430790Y3625092D01*
X431490D01*
X432290Y3624825D01*
X432890Y3624292D01*
G01X436790Y3617092D02*
Y3625092D01*
X439290D01*
X440090Y3624692D01*
X440590Y3624159D01*
X440790Y3623092D01*
X440590Y3622025D01*
X439990Y3621359D01*
X439290Y3620959D01*
X436790D01*
G01X439290D02*
X440790Y3617092D01*
G01X446790D02*
X445990Y3617225D01*
X445290Y3617759D01*
X444690Y3618559D01*
X444290Y3619492D01*
X444090Y3620559D01*
Y3621625D01*
X444290Y3622692D01*
X444690Y3623625D01*
X445290Y3624425D01*
X445990Y3624959D01*
X446790Y3625092D01*
X447590Y3624959D01*
X448290Y3624425D01*
X448890Y3623625D01*
X449290Y3622692D01*
X449490Y3621625D01*
Y3620559D01*
X449290Y3619492D01*
X448890Y3618559D01*
X448290Y3617759D01*
X447590Y3617225D01*
X446790Y3617092D01*
G01X452590Y3625092D02*
Y3619359D01*
X452990Y3618158D01*
X453790Y3617359D01*
X454790Y3617092D01*
X455790Y3617359D01*
X456590Y3618158D01*
X456990Y3619359D01*
Y3625092D01*
G01X460790Y3617092D02*
Y3625092D01*
X463190D01*
X463990Y3624692D01*
X464590Y3623759D01*
X464790Y3622692D01*
X464590Y3621625D01*
X464090Y3620825D01*
X463190Y3620425D01*
X460790D01*
G01X479590Y3621359D02*
X479990Y3621759D01*
X480290Y3622425D01*
X480490Y3623359D01*
X480290Y3624159D01*
X479890Y3624692D01*
X479190Y3625092D01*
X476490D01*
Y3617092D01*
X479790D01*
X480490Y3617625D01*
X480890Y3618425D01*
X481090Y3619359D01*
X480890Y3620292D01*
X480290Y3621092D01*
X479590Y3621359D01*
X476490D01*
G01X486790Y3616825D02*
X486590Y3616959D01*
Y3617225D01*
X486790Y3617359D01*
X486990Y3617225D01*
Y3616959D01*
X486790Y3616825D01*
G01X-33210Y3640092D02*
Y3632092D01*
G01X-35510Y3640092D02*
X-30910D01*
G01X-25210Y3632092D02*
X-26010Y3632225D01*
X-26710Y3632759D01*
X-27310Y3633559D01*
X-27710Y3634492D01*
X-27910Y3635559D01*
Y3636625D01*
X-27710Y3637692D01*
X-27310Y3638625D01*
X-26710Y3639425D01*
X-26010Y3639959D01*
X-25210Y3640092D01*
X-24410Y3639959D01*
X-23710Y3639425D01*
X-23110Y3638625D01*
X-22710Y3637692D01*
X-22510Y3636625D01*
Y3635559D01*
X-22710Y3634492D01*
X-23110Y3633559D01*
X-23710Y3632759D01*
X-24410Y3632225D01*
X-25210Y3632092D01*
G01X-9210Y3640092D02*
Y3632092D01*
G01X-11510Y3640092D02*
X-6910D01*
G01X-3310Y3632092D02*
Y3640092D01*
G01X890D02*
Y3632092D01*
G01Y3636092D02*
X-3310D01*
G01X8790Y3632092D02*
X4790D01*
Y3640092D01*
X8790D01*
G01X7190Y3636225D02*
X4790D01*
G01X23590Y3636359D02*
X23990Y3636759D01*
X24290Y3637425D01*
X24490Y3638359D01*
X24290Y3639159D01*
X23890Y3639692D01*
X23190Y3640092D01*
X20490D01*
Y3632092D01*
X23790D01*
X24490Y3632625D01*
X24890Y3633425D01*
X25090Y3634359D01*
X24890Y3635292D01*
X24290Y3636092D01*
X23590Y3636359D01*
X20490D01*
G01X30790Y3632092D02*
X29990Y3632225D01*
X29290Y3632759D01*
X28690Y3633559D01*
X28290Y3634492D01*
X28090Y3635559D01*
Y3636625D01*
X28290Y3637692D01*
X28690Y3638625D01*
X29290Y3639425D01*
X29990Y3639959D01*
X30790Y3640092D01*
X31590Y3639959D01*
X32290Y3639425D01*
X32890Y3638625D01*
X33290Y3637692D01*
X33490Y3636625D01*
Y3635559D01*
X33290Y3634492D01*
X32890Y3633559D01*
X32290Y3632759D01*
X31590Y3632225D01*
X30790Y3632092D01*
G01X36290D02*
X38790Y3640092D01*
X41290Y3632092D01*
G01X40390Y3634892D02*
X37190D01*
G01X44790Y3632092D02*
Y3640092D01*
X47290D01*
X48090Y3639692D01*
X48590Y3639159D01*
X48790Y3638092D01*
X48590Y3637025D01*
X47990Y3636359D01*
X47290Y3635959D01*
X44790D01*
G01X47290D02*
X48790Y3632092D01*
G01X52590D02*
Y3640092D01*
X54590D01*
X55390Y3639692D01*
X55990Y3639159D01*
X56490Y3638359D01*
X56890Y3637425D01*
X56990Y3636092D01*
X56890Y3634759D01*
X56490Y3633825D01*
X55990Y3633025D01*
X55390Y3632492D01*
X54590Y3632092D01*
X52590D01*
G01X72990Y3639425D02*
X72390Y3639825D01*
X71690Y3640092D01*
X70890D01*
X69990Y3639692D01*
X69290Y3639025D01*
X68790Y3638225D01*
X68390Y3636892D01*
X68290Y3635692D01*
X68490Y3634492D01*
X68790Y3633692D01*
X69390Y3632892D01*
X70090Y3632359D01*
X70790Y3632092D01*
X71490D01*
X72190Y3632359D01*
X72790Y3632759D01*
X73290Y3633292D01*
G01X78790Y3632092D02*
X77990Y3632225D01*
X77290Y3632759D01*
X76690Y3633559D01*
X76290Y3634492D01*
X76090Y3635559D01*
Y3636625D01*
X76290Y3637692D01*
X76690Y3638625D01*
X77290Y3639425D01*
X77990Y3639959D01*
X78790Y3640092D01*
X79590Y3639959D01*
X80290Y3639425D01*
X80890Y3638625D01*
X81290Y3637692D01*
X81490Y3636625D01*
Y3635559D01*
X81290Y3634492D01*
X80890Y3633559D01*
X80290Y3632759D01*
X79590Y3632225D01*
X78790Y3632092D01*
G01X84590Y3640092D02*
Y3634359D01*
X84990Y3633158D01*
X85790Y3632359D01*
X86790Y3632092D01*
X87790Y3632359D01*
X88590Y3633158D01*
X88990Y3634359D01*
Y3640092D01*
G01X92790Y3632092D02*
Y3640092D01*
X95190D01*
X95990Y3639692D01*
X96590Y3638759D01*
X96790Y3637692D01*
X96590Y3636625D01*
X96090Y3635825D01*
X95190Y3635425D01*
X92790D01*
G01X102790Y3632092D02*
X101990Y3632225D01*
X101290Y3632759D01*
X100690Y3633559D01*
X100290Y3634492D01*
X100090Y3635559D01*
Y3636625D01*
X100290Y3637692D01*
X100690Y3638625D01*
X101290Y3639425D01*
X101990Y3639959D01*
X102790Y3640092D01*
X103590Y3639959D01*
X104290Y3639425D01*
X104890Y3638625D01*
X105290Y3637692D01*
X105490Y3636625D01*
Y3635559D01*
X105290Y3634492D01*
X104890Y3633559D01*
X104290Y3632759D01*
X103590Y3632225D01*
X102790Y3632092D01*
G01X108490D02*
Y3640092D01*
X113090Y3632092D01*
Y3640092D01*
G01X116690Y3633158D02*
X117490Y3632492D01*
X118390Y3632092D01*
X119190D01*
X119990Y3632492D01*
X120590Y3633158D01*
X120890Y3634092D01*
X120690Y3635025D01*
X120190Y3635825D01*
X119290Y3636359D01*
X118090Y3636625D01*
X117390Y3637159D01*
X117090Y3638092D01*
X117290Y3639025D01*
X117790Y3639692D01*
X118490Y3640092D01*
X119190D01*
X119890Y3639825D01*
X120490Y3639159D01*
G01X126790Y3631825D02*
X126590Y3631959D01*
Y3632225D01*
X126790Y3632359D01*
X126990Y3632225D01*
Y3631959D01*
X126790Y3631825D01*
G01X133590Y3640092D02*
X135990D01*
G01X134790D02*
Y3632092D01*
G01X133590D02*
X135990D01*
G01X140890D02*
Y3640092D01*
X144690D01*
G01X143290Y3636225D02*
X140890D01*
G01X157590Y3640092D02*
X159990D01*
G01X158790D02*
Y3632092D01*
G01X157590D02*
X159990D01*
G01X166790Y3640092D02*
Y3632092D01*
G01X164490Y3640092D02*
X169090D01*
G01X181590D02*
X183990D01*
G01X182790D02*
Y3632092D01*
G01X181590D02*
X183990D01*
G01X188690Y3633158D02*
X189490Y3632492D01*
X190390Y3632092D01*
X191190D01*
X191990Y3632492D01*
X192590Y3633158D01*
X192890Y3634092D01*
X192690Y3635025D01*
X192190Y3635825D01*
X191290Y3636359D01*
X190090Y3636625D01*
X189390Y3637159D01*
X189090Y3638092D01*
X189290Y3639025D01*
X189790Y3639692D01*
X190490Y3640092D01*
X191190D01*
X191890Y3639825D01*
X192490Y3639159D01*
G01X204490Y3632092D02*
Y3640092D01*
X209090Y3632092D01*
Y3640092D01*
G01X214790Y3632092D02*
X213990Y3632225D01*
X213290Y3632759D01*
X212690Y3633559D01*
X212290Y3634492D01*
X212090Y3635559D01*
Y3636625D01*
X212290Y3637692D01*
X212690Y3638625D01*
X213290Y3639425D01*
X213990Y3639959D01*
X214790Y3640092D01*
X215590Y3639959D01*
X216290Y3639425D01*
X216890Y3638625D01*
X217290Y3637692D01*
X217490Y3636625D01*
Y3635559D01*
X217290Y3634492D01*
X216890Y3633559D01*
X216290Y3632759D01*
X215590Y3632225D01*
X214790Y3632092D01*
G01X222790Y3640092D02*
Y3632092D01*
G01X220490Y3640092D02*
X225090D01*
G01X236790Y3632092D02*
Y3640092D01*
X239190D01*
X239990Y3639692D01*
X240590Y3638759D01*
X240790Y3637692D01*
X240590Y3636625D01*
X240090Y3635825D01*
X239190Y3635425D01*
X236790D01*
G01X246790Y3632092D02*
X245990Y3632225D01*
X245290Y3632759D01*
X244690Y3633559D01*
X244290Y3634492D01*
X244090Y3635559D01*
Y3636625D01*
X244290Y3637692D01*
X244690Y3638625D01*
X245290Y3639425D01*
X245990Y3639959D01*
X246790Y3640092D01*
X247590Y3639959D01*
X248290Y3639425D01*
X248890Y3638625D01*
X249290Y3637692D01*
X249490Y3636625D01*
Y3635559D01*
X249290Y3634492D01*
X248890Y3633559D01*
X248290Y3632759D01*
X247590Y3632225D01*
X246790Y3632092D01*
G01X252690Y3633158D02*
X253490Y3632492D01*
X254390Y3632092D01*
X255190D01*
X255990Y3632492D01*
X256590Y3633158D01*
X256890Y3634092D01*
X256690Y3635025D01*
X256190Y3635825D01*
X255290Y3636359D01*
X254090Y3636625D01*
X253390Y3637159D01*
X253090Y3638092D01*
X253290Y3639025D01*
X253790Y3639692D01*
X254490Y3640092D01*
X255190D01*
X255890Y3639825D01*
X256490Y3639159D01*
G01X260690Y3633158D02*
X261490Y3632492D01*
X262390Y3632092D01*
X263190D01*
X263990Y3632492D01*
X264590Y3633158D01*
X264890Y3634092D01*
X264690Y3635025D01*
X264190Y3635825D01*
X263290Y3636359D01*
X262090Y3636625D01*
X261390Y3637159D01*
X261090Y3638092D01*
X261290Y3639025D01*
X261790Y3639692D01*
X262490Y3640092D01*
X263190D01*
X263890Y3639825D01*
X264490Y3639159D01*
G01X269590Y3640092D02*
X271990D01*
G01X270790D02*
Y3632092D01*
G01X269590D02*
X271990D01*
G01X279590Y3636359D02*
X279990Y3636759D01*
X280290Y3637425D01*
X280490Y3638359D01*
X280290Y3639159D01*
X279890Y3639692D01*
X279190Y3640092D01*
X276490D01*
Y3632092D01*
X279790D01*
X280490Y3632625D01*
X280890Y3633425D01*
X281090Y3634359D01*
X280890Y3635292D01*
X280290Y3636092D01*
X279590Y3636359D01*
X276490D01*
G01X284790Y3640092D02*
Y3632092D01*
X288790D01*
G01X296790D02*
X292790D01*
Y3640092D01*
X296790D01*
G01X295190Y3636225D02*
X292790D01*
G01X310790Y3640092D02*
Y3632092D01*
G01X308490Y3640092D02*
X313090D01*
G01X318790Y3632092D02*
X317990Y3632225D01*
X317290Y3632759D01*
X316690Y3633559D01*
X316290Y3634492D01*
X316090Y3635559D01*
Y3636625D01*
X316290Y3637692D01*
X316690Y3638625D01*
X317290Y3639425D01*
X317990Y3639959D01*
X318790Y3640092D01*
X319590Y3639959D01*
X320290Y3639425D01*
X320890Y3638625D01*
X321290Y3637692D01*
X321490Y3636625D01*
Y3635559D01*
X321290Y3634492D01*
X320890Y3633559D01*
X320290Y3632759D01*
X319590Y3632225D01*
X318790Y3632092D01*
G01X332890D02*
Y3640092D01*
X336690D01*
G01X335290Y3636225D02*
X332890D01*
G01X341590Y3640092D02*
X343990D01*
G01X342790D02*
Y3632092D01*
G01X341590D02*
X343990D01*
G01X350790Y3640092D02*
Y3632092D01*
G01X348490Y3640092D02*
X353090D01*
G01X365590D02*
X367990D01*
G01X366790D02*
Y3632092D01*
G01X365590D02*
X367990D01*
G01X372490D02*
Y3640092D01*
X377090Y3632092D01*
Y3640092D01*
G01X390790D02*
Y3632092D01*
G01X388490Y3640092D02*
X393090D01*
G01X396690Y3632092D02*
Y3640092D01*
G01X400890D02*
Y3632092D01*
G01Y3636092D02*
X396690D01*
G01X408790Y3632092D02*
X404790D01*
Y3640092D01*
X408790D01*
G01X407190Y3636225D02*
X404790D01*
G01X420790Y3640092D02*
Y3632092D01*
X424790D01*
G01X430790D02*
X429990Y3632225D01*
X429290Y3632759D01*
X428690Y3633559D01*
X428290Y3634492D01*
X428090Y3635559D01*
Y3636625D01*
X428290Y3637692D01*
X428690Y3638625D01*
X429290Y3639425D01*
X429990Y3639959D01*
X430790Y3640092D01*
X431590Y3639959D01*
X432290Y3639425D01*
X432890Y3638625D01*
X433290Y3637692D01*
X433490Y3636625D01*
Y3635559D01*
X433290Y3634492D01*
X432890Y3633559D01*
X432290Y3632759D01*
X431590Y3632225D01*
X430790Y3632092D01*
G01X440990Y3639425D02*
X440390Y3639825D01*
X439690Y3640092D01*
X438890D01*
X437990Y3639692D01*
X437290Y3639025D01*
X436790Y3638225D01*
X436390Y3636892D01*
X436290Y3635692D01*
X436490Y3634492D01*
X436790Y3633692D01*
X437390Y3632892D01*
X438090Y3632359D01*
X438790Y3632092D01*
X439490D01*
X440190Y3632359D01*
X440790Y3632759D01*
X441290Y3633292D01*
G01X444290Y3632092D02*
X446790Y3640092D01*
X449290Y3632092D01*
G01X448390Y3634892D02*
X445190D01*
G01X454790Y3640092D02*
Y3632092D01*
G01X452490Y3640092D02*
X457090D01*
G01X461590D02*
X463990D01*
G01X462790D02*
Y3632092D01*
G01X461590D02*
X463990D01*
G01X470790D02*
X469990Y3632225D01*
X469290Y3632759D01*
X468690Y3633559D01*
X468290Y3634492D01*
X468090Y3635559D01*
Y3636625D01*
X468290Y3637692D01*
X468690Y3638625D01*
X469290Y3639425D01*
X469990Y3639959D01*
X470790Y3640092D01*
X471590Y3639959D01*
X472290Y3639425D01*
X472890Y3638625D01*
X473290Y3637692D01*
X473490Y3636625D01*
Y3635559D01*
X473290Y3634492D01*
X472890Y3633559D01*
X472290Y3632759D01*
X471590Y3632225D01*
X470790Y3632092D01*
G01X476490D02*
Y3640092D01*
X481090Y3632092D01*
Y3640092D01*
G01X484690Y3633158D02*
X485490Y3632492D01*
X486390Y3632092D01*
X487190D01*
X487990Y3632492D01*
X488590Y3633158D01*
X488890Y3634092D01*
X488690Y3635025D01*
X488190Y3635825D01*
X487290Y3636359D01*
X486090Y3636625D01*
X485390Y3637159D01*
X485090Y3638092D01*
X485290Y3639025D01*
X485790Y3639692D01*
X486490Y3640092D01*
X487190D01*
X487890Y3639825D01*
X488490Y3639159D01*
G01X500890Y3632092D02*
Y3640092D01*
X504690D01*
G01X503290Y3636225D02*
X500890D01*
G01X510790Y3632092D02*
X509990Y3632225D01*
X509290Y3632759D01*
X508690Y3633559D01*
X508290Y3634492D01*
X508090Y3635559D01*
Y3636625D01*
X508290Y3637692D01*
X508690Y3638625D01*
X509290Y3639425D01*
X509990Y3639959D01*
X510790Y3640092D01*
X511590Y3639959D01*
X512290Y3639425D01*
X512890Y3638625D01*
X513290Y3637692D01*
X513490Y3636625D01*
Y3635559D01*
X513290Y3634492D01*
X512890Y3633559D01*
X512290Y3632759D01*
X511590Y3632225D01*
X510790Y3632092D01*
G01X516790D02*
Y3640092D01*
X519290D01*
X520090Y3639692D01*
X520590Y3639159D01*
X520790Y3638092D01*
X520590Y3637025D01*
X519990Y3636359D01*
X519290Y3635959D01*
X516790D01*
G01X519290D02*
X520790Y3632092D01*
G01X535590Y3636359D02*
X535990Y3636759D01*
X536290Y3637425D01*
X536490Y3638359D01*
X536290Y3639159D01*
X535890Y3639692D01*
X535190Y3640092D01*
X532490D01*
Y3632092D01*
X535790D01*
X536490Y3632625D01*
X536890Y3633425D01*
X537090Y3634359D01*
X536890Y3635292D01*
X536290Y3636092D01*
X535590Y3636359D01*
X532490D01*
G01X542790Y3632092D02*
X541990Y3632225D01*
X541290Y3632759D01*
X540690Y3633559D01*
X540290Y3634492D01*
X540090Y3635559D01*
Y3636625D01*
X540290Y3637692D01*
X540690Y3638625D01*
X541290Y3639425D01*
X541990Y3639959D01*
X542790Y3640092D01*
X543590Y3639959D01*
X544290Y3639425D01*
X544890Y3638625D01*
X545290Y3637692D01*
X545490Y3636625D01*
Y3635559D01*
X545290Y3634492D01*
X544890Y3633559D01*
X544290Y3632759D01*
X543590Y3632225D01*
X542790Y3632092D01*
G01X550790Y3640092D02*
Y3632092D01*
G01X548490Y3640092D02*
X553090D01*
G01X556690Y3632092D02*
Y3640092D01*
G01X560890D02*
Y3632092D01*
G01Y3636092D02*
X556690D01*
G01X-35210Y3647092D02*
Y3655092D01*
X-32810D01*
X-32010Y3654692D01*
X-31410Y3653759D01*
X-31210Y3652692D01*
X-31410Y3651625D01*
X-31910Y3650825D01*
X-32810Y3650425D01*
X-35210D01*
G01X-27210Y3655092D02*
Y3647092D01*
X-23210D01*
G01X-15210D02*
X-19210D01*
Y3655092D01*
X-15210D01*
G01X-16810Y3651225D02*
X-19210D01*
G01X-11710Y3647092D02*
X-9210Y3655092D01*
X-6710Y3647092D01*
G01X-7610Y3649892D02*
X-10810D01*
G01X-3310Y3648158D02*
X-2510Y3647492D01*
X-1610Y3647092D01*
X-810D01*
X-10Y3647492D01*
X590Y3648158D01*
X890Y3649092D01*
X690Y3650025D01*
X190Y3650825D01*
X-710Y3651359D01*
X-1910Y3651625D01*
X-2610Y3652159D01*
X-2910Y3653092D01*
X-2710Y3654025D01*
X-2210Y3654692D01*
X-1510Y3655092D01*
X-810D01*
X-110Y3654825D01*
X490Y3654159D01*
G01X8790Y3647092D02*
X4790D01*
Y3655092D01*
X8790D01*
G01X7190Y3651225D02*
X4790D01*
G01X20890Y3647092D02*
Y3655092D01*
X24690D01*
G01X23290Y3651225D02*
X20890D01*
G01X30790Y3647092D02*
X29990Y3647225D01*
X29290Y3647759D01*
X28690Y3648559D01*
X28290Y3649492D01*
X28090Y3650559D01*
Y3651625D01*
X28290Y3652692D01*
X28690Y3653625D01*
X29290Y3654425D01*
X29990Y3654959D01*
X30790Y3655092D01*
X31590Y3654959D01*
X32290Y3654425D01*
X32890Y3653625D01*
X33290Y3652692D01*
X33490Y3651625D01*
Y3650559D01*
X33290Y3649492D01*
X32890Y3648559D01*
X32290Y3647759D01*
X31590Y3647225D01*
X30790Y3647092D01*
G01X36790Y3655092D02*
Y3647092D01*
X40790D01*
G01X44790Y3655092D02*
Y3647092D01*
X48790D01*
G01X54790D02*
X53990Y3647225D01*
X53290Y3647759D01*
X52690Y3648559D01*
X52290Y3649492D01*
X52090Y3650559D01*
Y3651625D01*
X52290Y3652692D01*
X52690Y3653625D01*
X53290Y3654425D01*
X53990Y3654959D01*
X54790Y3655092D01*
X55590Y3654959D01*
X56290Y3654425D01*
X56890Y3653625D01*
X57290Y3652692D01*
X57490Y3651625D01*
Y3650559D01*
X57290Y3649492D01*
X56890Y3648559D01*
X56290Y3647759D01*
X55590Y3647225D01*
X54790Y3647092D01*
G01X59790Y3655092D02*
X61190Y3647092D01*
X62790Y3655092D01*
X64390Y3647092D01*
X65790Y3655092D01*
G01X78790D02*
Y3647092D01*
G01X76490Y3655092D02*
X81090D01*
G01X84690Y3647092D02*
Y3655092D01*
G01X88890D02*
Y3647092D01*
G01Y3651092D02*
X84690D01*
G01X96790Y3647092D02*
X92790D01*
Y3655092D01*
X96790D01*
G01X95190Y3651225D02*
X92790D01*
G01X108690Y3648158D02*
X109490Y3647492D01*
X110390Y3647092D01*
X111190D01*
X111990Y3647492D01*
X112590Y3648158D01*
X112890Y3649092D01*
X112690Y3650025D01*
X112190Y3650825D01*
X111290Y3651359D01*
X110090Y3651625D01*
X109390Y3652159D01*
X109090Y3653092D01*
X109290Y3654025D01*
X109790Y3654692D01*
X110490Y3655092D01*
X111190D01*
X111890Y3654825D01*
X112490Y3654159D01*
G01X116790Y3655092D02*
Y3647092D01*
X120790D01*
G01X125590Y3655092D02*
X127990D01*
G01X126790D02*
Y3647092D01*
G01X125590D02*
X127990D01*
G01X132590D02*
Y3655092D01*
X134590D01*
X135390Y3654692D01*
X135990Y3654159D01*
X136490Y3653359D01*
X136890Y3652425D01*
X136990Y3651092D01*
X136890Y3649759D01*
X136490Y3648825D01*
X135990Y3648025D01*
X135390Y3647492D01*
X134590Y3647092D01*
X132590D01*
G01X144790D02*
X140790D01*
Y3655092D01*
X144790D01*
G01X143190Y3651225D02*
X140790D01*
G01X148690Y3648158D02*
X149490Y3647492D01*
X150390Y3647092D01*
X151190D01*
X151990Y3647492D01*
X152590Y3648158D01*
X152890Y3649092D01*
X152690Y3650025D01*
X152190Y3650825D01*
X151290Y3651359D01*
X150090Y3651625D01*
X149390Y3652159D01*
X149090Y3653092D01*
X149290Y3654025D01*
X149790Y3654692D01*
X150490Y3655092D01*
X151190D01*
X151890Y3654825D01*
X152490Y3654159D01*
G01X166790Y3655092D02*
Y3647092D01*
G01X164490Y3655092D02*
X169090D01*
G01X174790Y3647092D02*
X173990Y3647225D01*
X173290Y3647759D01*
X172690Y3648559D01*
X172290Y3649492D01*
X172090Y3650559D01*
Y3651625D01*
X172290Y3652692D01*
X172690Y3653625D01*
X173290Y3654425D01*
X173990Y3654959D01*
X174790Y3655092D01*
X175590Y3654959D01*
X176290Y3654425D01*
X176890Y3653625D01*
X177290Y3652692D01*
X177490Y3651625D01*
Y3650559D01*
X177290Y3649492D01*
X176890Y3648559D01*
X176290Y3647759D01*
X175590Y3647225D01*
X174790Y3647092D01*
G01X191390Y3651092D02*
X193390D01*
Y3648692D01*
X192790Y3647892D01*
X192090Y3647359D01*
X191090Y3647092D01*
X190090Y3647359D01*
X189390Y3647892D01*
X188790Y3648692D01*
X188390Y3649625D01*
X188190Y3650692D01*
Y3651625D01*
X188390Y3652425D01*
X188790Y3653359D01*
X189390Y3654159D01*
X189990Y3654692D01*
X190790Y3655092D01*
X191490D01*
X192290Y3654825D01*
X192890Y3654292D01*
G01X200790Y3647092D02*
X196790D01*
Y3655092D01*
X200790D01*
G01X199190Y3651225D02*
X196790D01*
G01X204490Y3647092D02*
Y3655092D01*
X209090Y3647092D01*
Y3655092D01*
G01X216790Y3647092D02*
X212790D01*
Y3655092D01*
X216790D01*
G01X215190Y3651225D02*
X212790D01*
G01X220790Y3647092D02*
Y3655092D01*
X223290D01*
X224090Y3654692D01*
X224590Y3654159D01*
X224790Y3653092D01*
X224590Y3652025D01*
X223990Y3651359D01*
X223290Y3650959D01*
X220790D01*
G01X223290D02*
X224790Y3647092D01*
G01X228290D02*
X230790Y3655092D01*
X233290Y3647092D01*
G01X232390Y3649892D02*
X229190D01*
G01X238790Y3655092D02*
Y3647092D01*
G01X236490Y3655092D02*
X241090D01*
G01X248790Y3647092D02*
X244790D01*
Y3655092D01*
X248790D01*
G01X247190Y3651225D02*
X244790D01*
G01X262790Y3655092D02*
Y3647092D01*
G01X260490Y3655092D02*
X265090D01*
G01X268690Y3647092D02*
Y3655092D01*
G01X272890D02*
Y3647092D01*
G01Y3651092D02*
X268690D01*
G01X280790Y3647092D02*
X276790D01*
Y3655092D01*
X280790D01*
G01X279190Y3651225D02*
X276790D01*
G01X292790Y3647092D02*
Y3655092D01*
X295190D01*
X295990Y3654692D01*
X296590Y3653759D01*
X296790Y3652692D01*
X296590Y3651625D01*
X296090Y3650825D01*
X295190Y3650425D01*
X292790D01*
G01X300290Y3647092D02*
X302790Y3655092D01*
X305290Y3647092D01*
G01X304390Y3649892D02*
X301190D01*
G01X308590Y3647092D02*
Y3655092D01*
X310590D01*
X311390Y3654692D01*
X311990Y3654159D01*
X312490Y3653359D01*
X312890Y3652425D01*
X312990Y3651092D01*
X312890Y3649759D01*
X312490Y3648825D01*
X311990Y3648025D01*
X311390Y3647492D01*
X310590Y3647092D01*
X308590D01*
G01X316690Y3648158D02*
X317490Y3647492D01*
X318390Y3647092D01*
X319190D01*
X319990Y3647492D01*
X320590Y3648158D01*
X320890Y3649092D01*
X320690Y3650025D01*
X320190Y3650825D01*
X319290Y3651359D01*
X318090Y3651625D01*
X317390Y3652159D01*
X317090Y3653092D01*
X317290Y3654025D01*
X317790Y3654692D01*
X318490Y3655092D01*
X319190D01*
X319890Y3654825D01*
X320490Y3654159D01*
G01X332290Y3647092D02*
X334790Y3655092D01*
X337290Y3647092D01*
G01X336390Y3649892D02*
X333190D01*
G01X340490Y3647092D02*
Y3655092D01*
X345090Y3647092D01*
Y3655092D01*
G01X348590Y3647092D02*
Y3655092D01*
X350590D01*
X351390Y3654692D01*
X351990Y3654159D01*
X352490Y3653359D01*
X352890Y3652425D01*
X352990Y3651092D01*
X352890Y3649759D01*
X352490Y3648825D01*
X351990Y3648025D01*
X351390Y3647492D01*
X350590Y3647092D01*
X348590D01*
G01X364190D02*
Y3655092D01*
X366790Y3648425D01*
X369390Y3655092D01*
Y3647092D01*
G01X372290D02*
X374790Y3655092D01*
X377290Y3647092D01*
G01X376390Y3649892D02*
X373190D01*
G01X380690Y3648158D02*
X381490Y3647492D01*
X382390Y3647092D01*
X383190D01*
X383990Y3647492D01*
X384590Y3648158D01*
X384890Y3649092D01*
X384690Y3650025D01*
X384190Y3650825D01*
X383290Y3651359D01*
X382090Y3651625D01*
X381390Y3652159D01*
X381090Y3653092D01*
X381290Y3654025D01*
X381790Y3654692D01*
X382490Y3655092D01*
X383190D01*
X383890Y3654825D01*
X384490Y3654159D01*
G01X388590Y3647092D02*
Y3655092D01*
G01X392390D02*
X388590Y3650158D01*
G01X392990Y3647092D02*
X390290Y3652425D01*
G01X404290Y3647092D02*
X406790Y3655092D01*
X409290Y3647092D01*
G01X408390Y3649892D02*
X405190D01*
G01X412490Y3647092D02*
Y3655092D01*
X417090Y3647092D01*
Y3655092D01*
G01X420590Y3647092D02*
Y3655092D01*
X422590D01*
X423390Y3654692D01*
X423990Y3654159D01*
X424490Y3653359D01*
X424890Y3652425D01*
X424990Y3651092D01*
X424890Y3649759D01*
X424490Y3648825D01*
X423990Y3648025D01*
X423390Y3647492D01*
X422590Y3647092D01*
X420590D01*
G01X436290D02*
X438790Y3655092D01*
X441290Y3647092D01*
G01X440390Y3649892D02*
X437190D01*
G01X444590Y3647092D02*
Y3655092D01*
X446590D01*
X447390Y3654692D01*
X447990Y3654159D01*
X448490Y3653359D01*
X448890Y3652425D01*
X448990Y3651092D01*
X448890Y3649759D01*
X448490Y3648825D01*
X447990Y3648025D01*
X447390Y3647492D01*
X446590Y3647092D01*
X444590D01*
G01X452590D02*
Y3655092D01*
X454590D01*
X455390Y3654692D01*
X455990Y3654159D01*
X456490Y3653359D01*
X456890Y3652425D01*
X456990Y3651092D01*
X456890Y3649759D01*
X456490Y3648825D01*
X455990Y3648025D01*
X455390Y3647492D01*
X454590Y3647092D01*
X452590D01*
G01X470790Y3655092D02*
Y3647092D01*
G01X468490Y3655092D02*
X473090D01*
G01X476690Y3647092D02*
Y3655092D01*
G01X480890D02*
Y3647092D01*
G01Y3651092D02*
X476690D01*
G01X488790Y3647092D02*
X484790D01*
Y3655092D01*
X488790D01*
G01X487190Y3651225D02*
X484790D01*
G01X502790Y3655092D02*
Y3647092D01*
G01X500490Y3655092D02*
X505090D01*
G01X512790Y3647092D02*
X508790D01*
Y3655092D01*
X512790D01*
G01X511190Y3651225D02*
X508790D01*
G01X516690Y3648158D02*
X517490Y3647492D01*
X518390Y3647092D01*
X519190D01*
X519990Y3647492D01*
X520590Y3648158D01*
X520890Y3649092D01*
X520690Y3650025D01*
X520190Y3650825D01*
X519290Y3651359D01*
X518090Y3651625D01*
X517390Y3652159D01*
X517090Y3653092D01*
X517290Y3654025D01*
X517790Y3654692D01*
X518490Y3655092D01*
X519190D01*
X519890Y3654825D01*
X520490Y3654159D01*
G01X526790Y3655092D02*
Y3647092D01*
G01X524490Y3655092D02*
X529090D01*
G01X540790Y3647092D02*
Y3655092D01*
X543190D01*
X543990Y3654692D01*
X544590Y3653759D01*
X544790Y3652692D01*
X544590Y3651625D01*
X544090Y3650825D01*
X543190Y3650425D01*
X540790D01*
G01X548290Y3647092D02*
X550790Y3655092D01*
X553290Y3647092D01*
G01X552390Y3649892D02*
X549190D01*
G01X556590Y3647092D02*
Y3655092D01*
X558590D01*
X559390Y3654692D01*
X559990Y3654159D01*
X560490Y3653359D01*
X560890Y3652425D01*
X560990Y3651092D01*
X560890Y3649759D01*
X560490Y3648825D01*
X559990Y3648025D01*
X559390Y3647492D01*
X558590Y3647092D01*
X556590D01*
G01X564690Y3648158D02*
X565490Y3647492D01*
X566390Y3647092D01*
X567190D01*
X567990Y3647492D01*
X568590Y3648158D01*
X568890Y3649092D01*
X568690Y3650025D01*
X568190Y3650825D01*
X567290Y3651359D01*
X566090Y3651625D01*
X565390Y3652159D01*
X565090Y3653092D01*
X565290Y3654025D01*
X565790Y3654692D01*
X566490Y3655092D01*
X567190D01*
X567890Y3654825D01*
X568490Y3654159D01*
G01X-35710Y3677092D02*
X-33210Y3685092D01*
X-30710Y3677092D01*
G01X-31610Y3679892D02*
X-34810D01*
G01X-27510Y3677092D02*
Y3685092D01*
X-22910Y3677092D01*
Y3685092D01*
G01X-17210Y3677092D02*
Y3680692D01*
X-19210Y3685092D01*
G01X-15210D02*
X-17210Y3680692D01*
G01X-3210Y3677092D02*
Y3685092D01*
X-810D01*
X-10Y3684692D01*
X590Y3683759D01*
X790Y3682692D01*
X590Y3681625D01*
X90Y3680825D01*
X-810Y3680425D01*
X-3210D01*
G01X4790Y3677092D02*
Y3685092D01*
X7290D01*
X8090Y3684692D01*
X8590Y3684159D01*
X8790Y3683092D01*
X8590Y3682025D01*
X7990Y3681359D01*
X7290Y3680959D01*
X4790D01*
G01X7290D02*
X8790Y3677092D01*
G01X14790D02*
X13990Y3677225D01*
X13290Y3677759D01*
X12690Y3678559D01*
X12290Y3679492D01*
X12090Y3680559D01*
Y3681625D01*
X12290Y3682692D01*
X12690Y3683625D01*
X13290Y3684425D01*
X13990Y3684959D01*
X14790Y3685092D01*
X15590Y3684959D01*
X16290Y3684425D01*
X16890Y3683625D01*
X17290Y3682692D01*
X17490Y3681625D01*
Y3680559D01*
X17290Y3679492D01*
X16890Y3678559D01*
X16290Y3677759D01*
X15590Y3677225D01*
X14790Y3677092D01*
G01X20790D02*
Y3685092D01*
X23190D01*
X23990Y3684692D01*
X24590Y3683759D01*
X24790Y3682692D01*
X24590Y3681625D01*
X24090Y3680825D01*
X23190Y3680425D01*
X20790D01*
G01X30790Y3677092D02*
X29990Y3677225D01*
X29290Y3677759D01*
X28690Y3678559D01*
X28290Y3679492D01*
X28090Y3680559D01*
Y3681625D01*
X28290Y3682692D01*
X28690Y3683625D01*
X29290Y3684425D01*
X29990Y3684959D01*
X30790Y3685092D01*
X31590Y3684959D01*
X32290Y3684425D01*
X32890Y3683625D01*
X33290Y3682692D01*
X33490Y3681625D01*
Y3680559D01*
X33290Y3679492D01*
X32890Y3678559D01*
X32290Y3677759D01*
X31590Y3677225D01*
X30790Y3677092D01*
G01X36690Y3678158D02*
X37490Y3677492D01*
X38390Y3677092D01*
X39190D01*
X39990Y3677492D01*
X40590Y3678158D01*
X40890Y3679092D01*
X40690Y3680025D01*
X40190Y3680825D01*
X39290Y3681359D01*
X38090Y3681625D01*
X37390Y3682159D01*
X37090Y3683092D01*
X37290Y3684025D01*
X37790Y3684692D01*
X38490Y3685092D01*
X39190D01*
X39890Y3684825D01*
X40490Y3684159D01*
G01X48790Y3677092D02*
X44790D01*
Y3685092D01*
X48790D01*
G01X47190Y3681225D02*
X44790D01*
G01X52590Y3677092D02*
Y3685092D01*
X54590D01*
X55390Y3684692D01*
X55990Y3684159D01*
X56490Y3683359D01*
X56890Y3682425D01*
X56990Y3681092D01*
X56890Y3679759D01*
X56490Y3678825D01*
X55990Y3678025D01*
X55390Y3677492D01*
X54590Y3677092D01*
X52590D01*
G01X72990Y3684425D02*
X72390Y3684825D01*
X71690Y3685092D01*
X70890D01*
X69990Y3684692D01*
X69290Y3684025D01*
X68790Y3683225D01*
X68390Y3681892D01*
X68290Y3680692D01*
X68490Y3679492D01*
X68790Y3678692D01*
X69390Y3677892D01*
X70090Y3677359D01*
X70790Y3677092D01*
X71490D01*
X72190Y3677359D01*
X72790Y3677759D01*
X73290Y3678292D01*
G01X76690Y3677092D02*
Y3685092D01*
G01X80890D02*
Y3677092D01*
G01Y3681092D02*
X76690D01*
G01X84290Y3677092D02*
X86790Y3685092D01*
X89290Y3677092D01*
G01X88390Y3679892D02*
X85190D01*
G01X92490Y3677092D02*
Y3685092D01*
X97090Y3677092D01*
Y3685092D01*
G01X103390Y3681092D02*
X105390D01*
Y3678692D01*
X104790Y3677892D01*
X104090Y3677359D01*
X103090Y3677092D01*
X102090Y3677359D01*
X101390Y3677892D01*
X100790Y3678692D01*
X100390Y3679625D01*
X100190Y3680692D01*
Y3681625D01*
X100390Y3682425D01*
X100790Y3683359D01*
X101390Y3684159D01*
X101990Y3684692D01*
X102790Y3685092D01*
X103490D01*
X104290Y3684825D01*
X104890Y3684292D01*
G01X112790Y3677092D02*
X108790D01*
Y3685092D01*
X112790D01*
G01X111190Y3681225D02*
X108790D01*
G01X124790Y3677092D02*
Y3685092D01*
X127290D01*
X128090Y3684692D01*
X128590Y3684159D01*
X128790Y3683092D01*
X128590Y3682025D01*
X127990Y3681359D01*
X127290Y3680959D01*
X124790D01*
G01X127290D02*
X128790Y3677092D01*
G01X136790D02*
X132790D01*
Y3685092D01*
X136790D01*
G01X135190Y3681225D02*
X132790D01*
G01X142790Y3677092D02*
X141990Y3677225D01*
X141290Y3677759D01*
X140690Y3678559D01*
X140290Y3679492D01*
X140090Y3680559D01*
Y3681625D01*
X140290Y3682692D01*
X140690Y3683625D01*
X141290Y3684425D01*
X141990Y3684959D01*
X142790Y3685092D01*
X143590Y3684959D01*
X144290Y3684425D01*
X144890Y3683625D01*
X145290Y3682692D01*
X145490Y3681625D01*
Y3680559D01*
X145290Y3679492D01*
X144890Y3678559D01*
X144290Y3677759D01*
X143590Y3677225D01*
X142790Y3677092D01*
G01X143590Y3679225D02*
X144790Y3677092D01*
G01X148590Y3685092D02*
Y3679359D01*
X148990Y3678158D01*
X149790Y3677359D01*
X150790Y3677092D01*
X151790Y3677359D01*
X152590Y3678158D01*
X152990Y3679359D01*
Y3685092D01*
G01X160790Y3677092D02*
X156790D01*
Y3685092D01*
X160790D01*
G01X159190Y3681225D02*
X156790D01*
G01X164690Y3678158D02*
X165490Y3677492D01*
X166390Y3677092D01*
X167190D01*
X167990Y3677492D01*
X168590Y3678158D01*
X168890Y3679092D01*
X168690Y3680025D01*
X168190Y3680825D01*
X167290Y3681359D01*
X166090Y3681625D01*
X165390Y3682159D01*
X165090Y3683092D01*
X165290Y3684025D01*
X165790Y3684692D01*
X166490Y3685092D01*
X167190D01*
X167890Y3684825D01*
X168490Y3684159D01*
G01X174790Y3685092D02*
Y3677092D01*
G01X172490Y3685092D02*
X177090D01*
G01X188190Y3677092D02*
Y3685092D01*
X190790Y3678425D01*
X193390Y3685092D01*
Y3677092D01*
G01X196590Y3685092D02*
Y3679359D01*
X196990Y3678158D01*
X197790Y3677359D01*
X198790Y3677092D01*
X199790Y3677359D01*
X200590Y3678158D01*
X200990Y3679359D01*
Y3685092D01*
G01X204690Y3678158D02*
X205490Y3677492D01*
X206390Y3677092D01*
X207190D01*
X207990Y3677492D01*
X208590Y3678158D01*
X208890Y3679092D01*
X208690Y3680025D01*
X208190Y3680825D01*
X207290Y3681359D01*
X206090Y3681625D01*
X205390Y3682159D01*
X205090Y3683092D01*
X205290Y3684025D01*
X205790Y3684692D01*
X206490Y3685092D01*
X207190D01*
X207890Y3684825D01*
X208490Y3684159D01*
G01X214790Y3685092D02*
Y3677092D01*
G01X212490Y3685092D02*
X217090D01*
G01X231590Y3681359D02*
X231990Y3681759D01*
X232290Y3682425D01*
X232490Y3683359D01*
X232290Y3684159D01*
X231890Y3684692D01*
X231190Y3685092D01*
X228490D01*
Y3677092D01*
X231790D01*
X232490Y3677625D01*
X232890Y3678425D01*
X233090Y3679359D01*
X232890Y3680292D01*
X232290Y3681092D01*
X231590Y3681359D01*
X228490D01*
G01X240790Y3677092D02*
X236790D01*
Y3685092D01*
X240790D01*
G01X239190Y3681225D02*
X236790D01*
G01X252290Y3677092D02*
X254790Y3685092D01*
X257290Y3677092D01*
G01X256390Y3679892D02*
X253190D01*
G01X260790Y3677092D02*
Y3685092D01*
X263190D01*
X263990Y3684692D01*
X264590Y3683759D01*
X264790Y3682692D01*
X264590Y3681625D01*
X264090Y3680825D01*
X263190Y3680425D01*
X260790D01*
G01X268790Y3677092D02*
Y3685092D01*
X271190D01*
X271990Y3684692D01*
X272590Y3683759D01*
X272790Y3682692D01*
X272590Y3681625D01*
X272090Y3680825D01*
X271190Y3680425D01*
X268790D01*
G01X276790Y3677092D02*
Y3685092D01*
X279290D01*
X280090Y3684692D01*
X280590Y3684159D01*
X280790Y3683092D01*
X280590Y3682025D01*
X279990Y3681359D01*
X279290Y3680959D01*
X276790D01*
G01X279290D02*
X280790Y3677092D01*
G01X286790D02*
X285990Y3677225D01*
X285290Y3677759D01*
X284690Y3678559D01*
X284290Y3679492D01*
X284090Y3680559D01*
Y3681625D01*
X284290Y3682692D01*
X284690Y3683625D01*
X285290Y3684425D01*
X285990Y3684959D01*
X286790Y3685092D01*
X287590Y3684959D01*
X288290Y3684425D01*
X288890Y3683625D01*
X289290Y3682692D01*
X289490Y3681625D01*
Y3680559D01*
X289290Y3679492D01*
X288890Y3678559D01*
X288290Y3677759D01*
X287590Y3677225D01*
X286790Y3677092D01*
G01X292290Y3685092D02*
X294790Y3677092D01*
X297290Y3685092D01*
G01X304790Y3677092D02*
X300790D01*
Y3685092D01*
X304790D01*
G01X303190Y3681225D02*
X300790D01*
G01X308590Y3677092D02*
Y3685092D01*
X310590D01*
X311390Y3684692D01*
X311990Y3684159D01*
X312490Y3683359D01*
X312890Y3682425D01*
X312990Y3681092D01*
X312890Y3679759D01*
X312490Y3678825D01*
X311990Y3678025D01*
X311390Y3677492D01*
X310590Y3677092D01*
X308590D01*
G01X327590Y3681359D02*
X327990Y3681759D01*
X328290Y3682425D01*
X328490Y3683359D01*
X328290Y3684159D01*
X327890Y3684692D01*
X327190Y3685092D01*
X324490D01*
Y3677092D01*
X327790D01*
X328490Y3677625D01*
X328890Y3678425D01*
X329090Y3679359D01*
X328890Y3680292D01*
X328290Y3681092D01*
X327590Y3681359D01*
X324490D01*
G01X334790Y3677092D02*
Y3680692D01*
X332790Y3685092D01*
G01X336790D02*
X334790Y3680692D01*
G01X350790Y3677092D02*
X349990Y3677225D01*
X349290Y3677759D01*
X348690Y3678559D01*
X348290Y3679492D01*
X348090Y3680559D01*
Y3681625D01*
X348290Y3682692D01*
X348690Y3683625D01*
X349290Y3684425D01*
X349990Y3684959D01*
X350790Y3685092D01*
X351590Y3684959D01*
X352290Y3684425D01*
X352890Y3683625D01*
X353290Y3682692D01*
X353490Y3681625D01*
Y3680559D01*
X353290Y3679492D01*
X352890Y3678559D01*
X352290Y3677759D01*
X351590Y3677225D01*
X350790Y3677092D01*
G01X351590Y3679225D02*
X352790Y3677092D01*
G01X356590Y3685092D02*
Y3679359D01*
X356990Y3678158D01*
X357790Y3677359D01*
X358790Y3677092D01*
X359790Y3677359D01*
X360590Y3678158D01*
X360990Y3679359D01*
Y3685092D01*
G01X364290Y3677092D02*
X366790Y3685092D01*
X369290Y3677092D01*
G01X368390Y3679892D02*
X365190D01*
G01X372490Y3677092D02*
Y3685092D01*
X377090Y3677092D01*
Y3685092D01*
G01X382790D02*
Y3677092D01*
G01X380490Y3685092D02*
X385090D01*
G01X388290Y3677092D02*
X390790Y3685092D01*
X393290Y3677092D01*
G01X392390Y3679892D02*
X389190D01*
G01X404790Y3677092D02*
Y3685092D01*
X407190D01*
X407990Y3684692D01*
X408590Y3683759D01*
X408790Y3682692D01*
X408590Y3681625D01*
X408090Y3680825D01*
X407190Y3680425D01*
X404790D01*
G01X412790Y3677092D02*
Y3685092D01*
X415290D01*
X416090Y3684692D01*
X416590Y3684159D01*
X416790Y3683092D01*
X416590Y3682025D01*
X415990Y3681359D01*
X415290Y3680959D01*
X412790D01*
G01X415290D02*
X416790Y3677092D01*
G01X421590Y3685092D02*
X423990D01*
G01X422790D02*
Y3677092D01*
G01X421590D02*
X423990D01*
G01X430790D02*
X429990Y3677225D01*
X429290Y3677759D01*
X428690Y3678559D01*
X428290Y3679492D01*
X428090Y3680559D01*
Y3681625D01*
X428290Y3682692D01*
X428690Y3683625D01*
X429290Y3684425D01*
X429990Y3684959D01*
X430790Y3685092D01*
X431590Y3684959D01*
X432290Y3684425D01*
X432890Y3683625D01*
X433290Y3682692D01*
X433490Y3681625D01*
Y3680559D01*
X433290Y3679492D01*
X432890Y3678559D01*
X432290Y3677759D01*
X431590Y3677225D01*
X430790Y3677092D01*
G01X436790D02*
Y3685092D01*
X439290D01*
X440090Y3684692D01*
X440590Y3684159D01*
X440790Y3683092D01*
X440590Y3682025D01*
X439990Y3681359D01*
X439290Y3680959D01*
X436790D01*
G01X439290D02*
X440790Y3677092D01*
G01X454790Y3685092D02*
Y3677092D01*
G01X452490Y3685092D02*
X457090D01*
G01X462790Y3677092D02*
X461990Y3677225D01*
X461290Y3677759D01*
X460690Y3678559D01*
X460290Y3679492D01*
X460090Y3680559D01*
Y3681625D01*
X460290Y3682692D01*
X460690Y3683625D01*
X461290Y3684425D01*
X461990Y3684959D01*
X462790Y3685092D01*
X463590Y3684959D01*
X464290Y3684425D01*
X464890Y3683625D01*
X465290Y3682692D01*
X465490Y3681625D01*
Y3680559D01*
X465290Y3679492D01*
X464890Y3678559D01*
X464290Y3677759D01*
X463590Y3677225D01*
X462790Y3677092D01*
G01X477590Y3685092D02*
X479990D01*
G01X478790D02*
Y3677092D01*
G01X477590D02*
X479990D01*
G01X486790Y3685092D02*
Y3677092D01*
G01X484490Y3685092D02*
X489090D01*
G01X492690Y3678158D02*
X493490Y3677492D01*
X494390Y3677092D01*
X495190D01*
X495990Y3677492D01*
X496590Y3678158D01*
X496890Y3679092D01*
X496690Y3680025D01*
X496190Y3680825D01*
X495290Y3681359D01*
X494090Y3681625D01*
X493390Y3682159D01*
X493090Y3683092D01*
X493290Y3684025D01*
X493790Y3684692D01*
X494490Y3685092D01*
X495190D01*
X495890Y3684825D01*
X496490Y3684159D01*
G01X509590Y3685092D02*
X511990D01*
G01X510790D02*
Y3677092D01*
G01X509590D02*
X511990D01*
G01X516190D02*
Y3685092D01*
X518790Y3678425D01*
X521390Y3685092D01*
Y3677092D01*
G01X524790D02*
Y3685092D01*
X527190D01*
X527990Y3684692D01*
X528590Y3683759D01*
X528790Y3682692D01*
X528590Y3681625D01*
X528090Y3680825D01*
X527190Y3680425D01*
X524790D01*
G01X532790Y3685092D02*
Y3677092D01*
X536790D01*
G01X544790D02*
X540790D01*
Y3685092D01*
X544790D01*
G01X543190Y3681225D02*
X540790D01*
G01X548190Y3677092D02*
Y3685092D01*
X550790Y3678425D01*
X553390Y3685092D01*
Y3677092D01*
G01X560790D02*
X556790D01*
Y3685092D01*
X560790D01*
G01X559190Y3681225D02*
X556790D01*
G01X564490Y3677092D02*
Y3685092D01*
X569090Y3677092D01*
Y3685092D01*
G01X574790D02*
Y3677092D01*
G01X572490Y3685092D02*
X577090D01*
G01X580290Y3677092D02*
X582790Y3685092D01*
X585290Y3677092D01*
G01X584390Y3679892D02*
X581190D01*
G01X590790Y3685092D02*
Y3677092D01*
G01X588490Y3685092D02*
X593090D01*
G01X597590D02*
X599990D01*
G01X598790D02*
Y3677092D01*
G01X597590D02*
X599990D01*
G01X606790D02*
X605990Y3677225D01*
X605290Y3677759D01*
X604690Y3678559D01*
X604290Y3679492D01*
X604090Y3680559D01*
Y3681625D01*
X604290Y3682692D01*
X604690Y3683625D01*
X605290Y3684425D01*
X605990Y3684959D01*
X606790Y3685092D01*
X607590Y3684959D01*
X608290Y3684425D01*
X608890Y3683625D01*
X609290Y3682692D01*
X609490Y3681625D01*
Y3680559D01*
X609290Y3679492D01*
X608890Y3678559D01*
X608290Y3677759D01*
X607590Y3677225D01*
X606790Y3677092D01*
G01X612490D02*
Y3685092D01*
X617090Y3677092D01*
Y3685092D01*
G01X622790Y3676825D02*
X622590Y3676959D01*
Y3677225D01*
X622790Y3677359D01*
X622990Y3677225D01*
Y3676959D01*
X622790Y3676825D01*
G01X-34410Y3700092D02*
X-32010D01*
G01X-33210D02*
Y3692092D01*
G01X-34410D02*
X-32010D01*
G01X-27810D02*
Y3700092D01*
X-25210Y3693425D01*
X-22610Y3700092D01*
Y3692092D01*
G01X-19210D02*
Y3700092D01*
X-16810D01*
X-16010Y3699692D01*
X-15410Y3698759D01*
X-15210Y3697692D01*
X-15410Y3696625D01*
X-15910Y3695825D01*
X-16810Y3695425D01*
X-19210D01*
G01X-7210Y3692092D02*
X-11210D01*
Y3700092D01*
X-7210D01*
G01X-8810Y3696225D02*
X-11210D01*
G01X-3410Y3692092D02*
Y3700092D01*
X-1410D01*
X-610Y3699692D01*
X-10Y3699159D01*
X490Y3698359D01*
X890Y3697425D01*
X990Y3696092D01*
X890Y3694759D01*
X490Y3693825D01*
X-10Y3693025D01*
X-610Y3692492D01*
X-1410Y3692092D01*
X-3410D01*
G01X4290D02*
X6790Y3700092D01*
X9290Y3692092D01*
G01X8390Y3694892D02*
X5190D01*
G01X12490Y3692092D02*
Y3700092D01*
X17090Y3692092D01*
Y3700092D01*
G01X24990Y3699425D02*
X24390Y3699825D01*
X23690Y3700092D01*
X22890D01*
X21990Y3699692D01*
X21290Y3699025D01*
X20790Y3698225D01*
X20390Y3696892D01*
X20290Y3695692D01*
X20490Y3694492D01*
X20790Y3693692D01*
X21390Y3692892D01*
X22090Y3692359D01*
X22790Y3692092D01*
X23490D01*
X24190Y3692359D01*
X24790Y3692759D01*
X25290Y3693292D01*
G01X32790Y3692092D02*
X28790D01*
Y3700092D01*
X32790D01*
G01X31190Y3696225D02*
X28790D01*
G01X36690Y3693158D02*
X37490Y3692492D01*
X38390Y3692092D01*
X39190D01*
X39990Y3692492D01*
X40590Y3693158D01*
X40890Y3694092D01*
X40690Y3695025D01*
X40190Y3695825D01*
X39290Y3696359D01*
X38090Y3696625D01*
X37390Y3697159D01*
X37090Y3698092D01*
X37290Y3699025D01*
X37790Y3699692D01*
X38490Y3700092D01*
X39190D01*
X39890Y3699825D01*
X40490Y3699159D01*
G01X52290Y3692092D02*
X54790Y3700092D01*
X57290Y3692092D01*
G01X56390Y3694892D02*
X53190D01*
G01X60490Y3692092D02*
Y3700092D01*
X65090Y3692092D01*
Y3700092D01*
G01X68590Y3692092D02*
Y3700092D01*
X70590D01*
X71390Y3699692D01*
X71990Y3699159D01*
X72490Y3698359D01*
X72890Y3697425D01*
X72990Y3696092D01*
X72890Y3694759D01*
X72490Y3693825D01*
X71990Y3693025D01*
X71390Y3692492D01*
X70590Y3692092D01*
X68590D01*
G01X87590Y3696359D02*
X87990Y3696759D01*
X88290Y3697425D01*
X88490Y3698359D01*
X88290Y3699159D01*
X87890Y3699692D01*
X87190Y3700092D01*
X84490D01*
Y3692092D01*
X87790D01*
X88490Y3692625D01*
X88890Y3693425D01*
X89090Y3694359D01*
X88890Y3695292D01*
X88290Y3696092D01*
X87590Y3696359D01*
X84490D01*
G01X94790Y3692092D02*
X93990Y3692225D01*
X93290Y3692759D01*
X92690Y3693559D01*
X92290Y3694492D01*
X92090Y3695559D01*
Y3696625D01*
X92290Y3697692D01*
X92690Y3698625D01*
X93290Y3699425D01*
X93990Y3699959D01*
X94790Y3700092D01*
X95590Y3699959D01*
X96290Y3699425D01*
X96890Y3698625D01*
X97290Y3697692D01*
X97490Y3696625D01*
Y3695559D01*
X97290Y3694492D01*
X96890Y3693559D01*
X96290Y3692759D01*
X95590Y3692225D01*
X94790Y3692092D01*
G01X100290D02*
X102790Y3700092D01*
X105290Y3692092D01*
G01X104390Y3694892D02*
X101190D01*
G01X108790Y3692092D02*
Y3700092D01*
X111290D01*
X112090Y3699692D01*
X112590Y3699159D01*
X112790Y3698092D01*
X112590Y3697025D01*
X111990Y3696359D01*
X111290Y3695959D01*
X108790D01*
G01X111290D02*
X112790Y3692092D01*
G01X116590D02*
Y3700092D01*
X118590D01*
X119390Y3699692D01*
X119990Y3699159D01*
X120490Y3698359D01*
X120890Y3697425D01*
X120990Y3696092D01*
X120890Y3694759D01*
X120490Y3693825D01*
X119990Y3693025D01*
X119390Y3692492D01*
X118590Y3692092D01*
X116590D01*
G01X134790Y3700092D02*
Y3692092D01*
G01X132490Y3700092D02*
X137090D01*
G01X140690Y3692092D02*
Y3700092D01*
G01X144890D02*
Y3692092D01*
G01Y3696092D02*
X140690D01*
G01X149590Y3700092D02*
X151990D01*
G01X150790D02*
Y3692092D01*
G01X149590D02*
X151990D01*
G01X160990Y3699425D02*
X160390Y3699825D01*
X159690Y3700092D01*
X158890D01*
X157990Y3699692D01*
X157290Y3699025D01*
X156790Y3698225D01*
X156390Y3696892D01*
X156290Y3695692D01*
X156490Y3694492D01*
X156790Y3693692D01*
X157390Y3692892D01*
X158090Y3692359D01*
X158790Y3692092D01*
X159490D01*
X160190Y3692359D01*
X160790Y3692759D01*
X161290Y3693292D01*
G01X164590Y3692092D02*
Y3700092D01*
G01X168390D02*
X164590Y3695158D01*
G01X168990Y3692092D02*
X166290Y3697425D01*
G01X172490Y3692092D02*
Y3700092D01*
X177090Y3692092D01*
Y3700092D01*
G01X184790Y3692092D02*
X180790D01*
Y3700092D01*
X184790D01*
G01X183190Y3696225D02*
X180790D01*
G01X188690Y3693158D02*
X189490Y3692492D01*
X190390Y3692092D01*
X191190D01*
X191990Y3692492D01*
X192590Y3693158D01*
X192890Y3694092D01*
X192690Y3695025D01*
X192190Y3695825D01*
X191290Y3696359D01*
X190090Y3696625D01*
X189390Y3697159D01*
X189090Y3698092D01*
X189290Y3699025D01*
X189790Y3699692D01*
X190490Y3700092D01*
X191190D01*
X191890Y3699825D01*
X192490Y3699159D01*
G01X196690Y3693158D02*
X197490Y3692492D01*
X198390Y3692092D01*
X199190D01*
X199990Y3692492D01*
X200590Y3693158D01*
X200890Y3694092D01*
X200690Y3695025D01*
X200190Y3695825D01*
X199290Y3696359D01*
X198090Y3696625D01*
X197390Y3697159D01*
X197090Y3698092D01*
X197290Y3699025D01*
X197790Y3699692D01*
X198490Y3700092D01*
X199190D01*
X199890Y3699825D01*
X200490Y3699159D01*
G01X206790Y3691825D02*
X206590Y3691959D01*
Y3692225D01*
X206790Y3692359D01*
X206990Y3692225D01*
Y3691959D01*
X206790Y3691825D01*
G01X-35310Y3708158D02*
X-34510Y3707492D01*
X-33610Y3707092D01*
X-32810D01*
X-32010Y3707492D01*
X-31410Y3708158D01*
X-31110Y3709092D01*
X-31310Y3710025D01*
X-31810Y3710825D01*
X-32710Y3711359D01*
X-33910Y3711625D01*
X-34610Y3712159D01*
X-34910Y3713092D01*
X-34710Y3714025D01*
X-34210Y3714692D01*
X-33510Y3715092D01*
X-32810D01*
X-32110Y3714825D01*
X-31510Y3714159D01*
G01X-27210Y3707092D02*
Y3715092D01*
X-24810D01*
X-24010Y3714692D01*
X-23410Y3713759D01*
X-23210Y3712692D01*
X-23410Y3711625D01*
X-23910Y3710825D01*
X-24810Y3710425D01*
X-27210D01*
G01X-19710Y3707092D02*
X-17210Y3715092D01*
X-14710Y3707092D01*
G01X-15610Y3709892D02*
X-18810D01*
G01X-7010Y3714425D02*
X-7610Y3714825D01*
X-8310Y3715092D01*
X-9110D01*
X-10010Y3714692D01*
X-10710Y3714025D01*
X-11210Y3713225D01*
X-11610Y3711892D01*
X-11710Y3710692D01*
X-11510Y3709492D01*
X-11210Y3708692D01*
X-10610Y3707892D01*
X-9910Y3707359D01*
X-9210Y3707092D01*
X-8510D01*
X-7810Y3707359D01*
X-7210Y3707759D01*
X-6710Y3708292D01*
G01X-2410Y3715092D02*
X-10D01*
G01X-1210D02*
Y3707092D01*
G01X-2410D02*
X-10D01*
G01X4490D02*
Y3715092D01*
X9090Y3707092D01*
Y3715092D01*
G01X15390Y3711092D02*
X17390D01*
Y3708692D01*
X16790Y3707892D01*
X16090Y3707359D01*
X15090Y3707092D01*
X14090Y3707359D01*
X13390Y3707892D01*
X12790Y3708692D01*
X12390Y3709625D01*
X12190Y3710692D01*
Y3711625D01*
X12390Y3712425D01*
X12790Y3713359D01*
X13390Y3714159D01*
X13990Y3714692D01*
X14790Y3715092D01*
X15490D01*
X16290Y3714825D01*
X16890Y3714292D01*
G01X28290Y3707092D02*
X30790Y3715092D01*
X33290Y3707092D01*
G01X32390Y3709892D02*
X29190D01*
G01X36490Y3707092D02*
Y3715092D01*
X41090Y3707092D01*
Y3715092D01*
G01X44590Y3707092D02*
Y3715092D01*
X46590D01*
X47390Y3714692D01*
X47990Y3714159D01*
X48490Y3713359D01*
X48890Y3712425D01*
X48990Y3711092D01*
X48890Y3709759D01*
X48490Y3708825D01*
X47990Y3708025D01*
X47390Y3707492D01*
X46590Y3707092D01*
X44590D01*
G01X60190D02*
Y3715092D01*
X62790Y3708425D01*
X65390Y3715092D01*
Y3707092D01*
G01X68290D02*
X70790Y3715092D01*
X73290Y3707092D01*
G01X72390Y3709892D02*
X69190D01*
G01X78790Y3715092D02*
Y3707092D01*
G01X76490Y3715092D02*
X81090D01*
G01X88790Y3707092D02*
X84790D01*
Y3715092D01*
X88790D01*
G01X87190Y3711225D02*
X84790D01*
G01X92790Y3707092D02*
Y3715092D01*
X95290D01*
X96090Y3714692D01*
X96590Y3714159D01*
X96790Y3713092D01*
X96590Y3712025D01*
X95990Y3711359D01*
X95290Y3710959D01*
X92790D01*
G01X95290D02*
X96790Y3707092D01*
G01X101590Y3715092D02*
X103990D01*
G01X102790D02*
Y3707092D01*
G01X101590D02*
X103990D01*
G01X108290D02*
X110790Y3715092D01*
X113290Y3707092D01*
G01X112390Y3709892D02*
X109190D01*
G01X116790Y3715092D02*
Y3707092D01*
X120790D01*
G01X132590D02*
Y3715092D01*
X134590D01*
X135390Y3714692D01*
X135990Y3714159D01*
X136490Y3713359D01*
X136890Y3712425D01*
X136990Y3711092D01*
X136890Y3709759D01*
X136490Y3708825D01*
X135990Y3708025D01*
X135390Y3707492D01*
X134590Y3707092D01*
X132590D01*
G01X141590Y3715092D02*
X143990D01*
G01X142790D02*
Y3707092D01*
G01X141590D02*
X143990D01*
G01X152790D02*
X148790D01*
Y3715092D01*
X152790D01*
G01X151190Y3711225D02*
X148790D01*
G01X156790Y3715092D02*
Y3707092D01*
X160790D01*
G01X168790D02*
X164790D01*
Y3715092D01*
X168790D01*
G01X167190Y3711225D02*
X164790D01*
G01X176990Y3714425D02*
X176390Y3714825D01*
X175690Y3715092D01*
X174890D01*
X173990Y3714692D01*
X173290Y3714025D01*
X172790Y3713225D01*
X172390Y3711892D01*
X172290Y3710692D01*
X172490Y3709492D01*
X172790Y3708692D01*
X173390Y3707892D01*
X174090Y3707359D01*
X174790Y3707092D01*
X175490D01*
X176190Y3707359D01*
X176790Y3707759D01*
X177290Y3708292D01*
G01X182790Y3715092D02*
Y3707092D01*
G01X180490Y3715092D02*
X185090D01*
G01X188790Y3707092D02*
Y3715092D01*
X191290D01*
X192090Y3714692D01*
X192590Y3714159D01*
X192790Y3713092D01*
X192590Y3712025D01*
X191990Y3711359D01*
X191290Y3710959D01*
X188790D01*
G01X191290D02*
X192790Y3707092D01*
G01X197590Y3715092D02*
X199990D01*
G01X198790D02*
Y3707092D01*
G01X197590D02*
X199990D01*
G01X208990Y3714425D02*
X208390Y3714825D01*
X207690Y3715092D01*
X206890D01*
X205990Y3714692D01*
X205290Y3714025D01*
X204790Y3713225D01*
X204390Y3711892D01*
X204290Y3710692D01*
X204490Y3709492D01*
X204790Y3708692D01*
X205390Y3707892D01*
X206090Y3707359D01*
X206790Y3707092D01*
X207490D01*
X208190Y3707359D01*
X208790Y3707759D01*
X209290Y3708292D01*
G01X224990Y3714425D02*
X224390Y3714825D01*
X223690Y3715092D01*
X222890D01*
X221990Y3714692D01*
X221290Y3714025D01*
X220790Y3713225D01*
X220390Y3711892D01*
X220290Y3710692D01*
X220490Y3709492D01*
X220790Y3708692D01*
X221390Y3707892D01*
X222090Y3707359D01*
X222790Y3707092D01*
X223490D01*
X224190Y3707359D01*
X224790Y3707759D01*
X225290Y3708292D01*
G01X230790Y3707092D02*
X229990Y3707225D01*
X229290Y3707759D01*
X228690Y3708559D01*
X228290Y3709492D01*
X228090Y3710559D01*
Y3711625D01*
X228290Y3712692D01*
X228690Y3713625D01*
X229290Y3714425D01*
X229990Y3714959D01*
X230790Y3715092D01*
X231590Y3714959D01*
X232290Y3714425D01*
X232890Y3713625D01*
X233290Y3712692D01*
X233490Y3711625D01*
Y3710559D01*
X233290Y3709492D01*
X232890Y3708559D01*
X232290Y3707759D01*
X231590Y3707225D01*
X230790Y3707092D01*
G01X236490D02*
Y3715092D01*
X241090Y3707092D01*
Y3715092D01*
G01X244690Y3708158D02*
X245490Y3707492D01*
X246390Y3707092D01*
X247190D01*
X247990Y3707492D01*
X248590Y3708158D01*
X248890Y3709092D01*
X248690Y3710025D01*
X248190Y3710825D01*
X247290Y3711359D01*
X246090Y3711625D01*
X245390Y3712159D01*
X245090Y3713092D01*
X245290Y3714025D01*
X245790Y3714692D01*
X246490Y3715092D01*
X247190D01*
X247890Y3714825D01*
X248490Y3714159D01*
G01X254790Y3715092D02*
Y3707092D01*
G01X252490Y3715092D02*
X257090D01*
G01X260290Y3707092D02*
X262790Y3715092D01*
X265290Y3707092D01*
G01X264390Y3709892D02*
X261190D01*
G01X268490Y3707092D02*
Y3715092D01*
X273090Y3707092D01*
Y3715092D01*
G01X278790D02*
Y3707092D01*
G01X276490Y3715092D02*
X281090D01*
G01X294790D02*
Y3707092D01*
G01X292490Y3715092D02*
X297090D01*
G01X302790Y3707092D02*
X301990Y3707225D01*
X301290Y3707759D01*
X300690Y3708559D01*
X300290Y3709492D01*
X300090Y3710559D01*
Y3711625D01*
X300290Y3712692D01*
X300690Y3713625D01*
X301290Y3714425D01*
X301990Y3714959D01*
X302790Y3715092D01*
X303590Y3714959D01*
X304290Y3714425D01*
X304890Y3713625D01*
X305290Y3712692D01*
X305490Y3711625D01*
Y3710559D01*
X305290Y3709492D01*
X304890Y3708559D01*
X304290Y3707759D01*
X303590Y3707225D01*
X302790Y3707092D01*
G01X316290D02*
X318790Y3715092D01*
X321290Y3707092D01*
G01X320390Y3709892D02*
X317190D01*
G01X328990Y3714425D02*
X328390Y3714825D01*
X327690Y3715092D01*
X326890D01*
X325990Y3714692D01*
X325290Y3714025D01*
X324790Y3713225D01*
X324390Y3711892D01*
X324290Y3710692D01*
X324490Y3709492D01*
X324790Y3708692D01*
X325390Y3707892D01*
X326090Y3707359D01*
X326790Y3707092D01*
X327490D01*
X328190Y3707359D01*
X328790Y3707759D01*
X329290Y3708292D01*
G01X332690Y3707092D02*
Y3715092D01*
G01X336890D02*
Y3707092D01*
G01Y3711092D02*
X332690D01*
G01X341590Y3715092D02*
X343990D01*
G01X342790D02*
Y3707092D01*
G01X341590D02*
X343990D01*
G01X352790D02*
X348790D01*
Y3715092D01*
X352790D01*
G01X351190Y3711225D02*
X348790D01*
G01X356290Y3715092D02*
X358790Y3707092D01*
X361290Y3715092D01*
G01X368790Y3707092D02*
X364790D01*
Y3715092D01*
X368790D01*
G01X367190Y3711225D02*
X364790D01*
G01X380790Y3707092D02*
Y3715092D01*
X383290D01*
X384090Y3714692D01*
X384590Y3714159D01*
X384790Y3713092D01*
X384590Y3712025D01*
X383990Y3711359D01*
X383290Y3710959D01*
X380790D01*
G01X383290D02*
X384790Y3707092D01*
G01X392790D02*
X388790D01*
Y3715092D01*
X392790D01*
G01X391190Y3711225D02*
X388790D01*
G01X398790Y3707092D02*
X397990Y3707225D01*
X397290Y3707759D01*
X396690Y3708559D01*
X396290Y3709492D01*
X396090Y3710559D01*
Y3711625D01*
X396290Y3712692D01*
X396690Y3713625D01*
X397290Y3714425D01*
X397990Y3714959D01*
X398790Y3715092D01*
X399590Y3714959D01*
X400290Y3714425D01*
X400890Y3713625D01*
X401290Y3712692D01*
X401490Y3711625D01*
Y3710559D01*
X401290Y3709492D01*
X400890Y3708559D01*
X400290Y3707759D01*
X399590Y3707225D01*
X398790Y3707092D01*
G01X399590Y3709225D02*
X400790Y3707092D01*
G01X404590Y3715092D02*
Y3709359D01*
X404990Y3708158D01*
X405790Y3707359D01*
X406790Y3707092D01*
X407790Y3707359D01*
X408590Y3708158D01*
X408990Y3709359D01*
Y3715092D01*
G01X413590D02*
X415990D01*
G01X414790D02*
Y3707092D01*
G01X413590D02*
X415990D01*
G01X420790D02*
Y3715092D01*
X423290D01*
X424090Y3714692D01*
X424590Y3714159D01*
X424790Y3713092D01*
X424590Y3712025D01*
X423990Y3711359D01*
X423290Y3710959D01*
X420790D01*
G01X423290D02*
X424790Y3707092D01*
G01X432790D02*
X428790D01*
Y3715092D01*
X432790D01*
G01X431190Y3711225D02*
X428790D01*
G01X436590Y3707092D02*
Y3715092D01*
X438590D01*
X439390Y3714692D01*
X439990Y3714159D01*
X440490Y3713359D01*
X440890Y3712425D01*
X440990Y3711092D01*
X440890Y3709759D01*
X440490Y3708825D01*
X439990Y3708025D01*
X439390Y3707492D01*
X438590Y3707092D01*
X436590D01*
G01X-31010Y3729425D02*
X-31610Y3729825D01*
X-32310Y3730092D01*
X-33110D01*
X-34010Y3729692D01*
X-34710Y3729025D01*
X-35210Y3728225D01*
X-35610Y3726892D01*
X-35710Y3725692D01*
X-35510Y3724492D01*
X-35210Y3723692D01*
X-34610Y3722892D01*
X-33910Y3722359D01*
X-33210Y3722092D01*
X-32510D01*
X-31810Y3722359D01*
X-31210Y3722759D01*
X-30710Y3723292D01*
G01X-27310Y3722092D02*
Y3730092D01*
G01X-23110D02*
Y3722092D01*
G01Y3726092D02*
X-27310D01*
G01X-19710Y3722092D02*
X-17210Y3730092D01*
X-14710Y3722092D01*
G01X-15610Y3724892D02*
X-18810D01*
G01X-11210Y3722092D02*
Y3730092D01*
X-8710D01*
X-7910Y3729692D01*
X-7410Y3729159D01*
X-7210Y3728092D01*
X-7410Y3727025D01*
X-8010Y3726359D01*
X-8710Y3725959D01*
X-11210D01*
G01X-8710D02*
X-7210Y3722092D01*
G01X-1210Y3730092D02*
Y3722092D01*
G01X-3510Y3730092D02*
X1090D01*
G01X6790Y3721825D02*
X6590Y3721959D01*
Y3722225D01*
X6790Y3722359D01*
X6990Y3722225D01*
Y3721959D01*
X6790Y3721825D01*
G01X20190Y3722092D02*
Y3730092D01*
X22790Y3723425D01*
X25390Y3730092D01*
Y3722092D01*
G01X28290D02*
X30790Y3730092D01*
X33290Y3722092D01*
G01X32390Y3724892D02*
X29190D01*
G01X36490Y3722092D02*
Y3730092D01*
X41090Y3722092D01*
Y3730092D01*
G01X44590D02*
Y3724359D01*
X44990Y3723158D01*
X45790Y3722359D01*
X46790Y3722092D01*
X47790Y3722359D01*
X48590Y3723158D01*
X48990Y3724359D01*
Y3730092D01*
G01X52890Y3722092D02*
Y3730092D01*
X56690D01*
G01X55290Y3726225D02*
X52890D01*
G01X60290Y3722092D02*
X62790Y3730092D01*
X65290Y3722092D01*
G01X64390Y3724892D02*
X61190D01*
G01X72990Y3729425D02*
X72390Y3729825D01*
X71690Y3730092D01*
X70890D01*
X69990Y3729692D01*
X69290Y3729025D01*
X68790Y3728225D01*
X68390Y3726892D01*
X68290Y3725692D01*
X68490Y3724492D01*
X68790Y3723692D01*
X69390Y3722892D01*
X70090Y3722359D01*
X70790Y3722092D01*
X71490D01*
X72190Y3722359D01*
X72790Y3722759D01*
X73290Y3723292D01*
G01X78790Y3730092D02*
Y3722092D01*
G01X76490Y3730092D02*
X81090D01*
G01X84590D02*
Y3724359D01*
X84990Y3723158D01*
X85790Y3722359D01*
X86790Y3722092D01*
X87790Y3722359D01*
X88590Y3723158D01*
X88990Y3724359D01*
Y3730092D01*
G01X92790Y3722092D02*
Y3730092D01*
X95290D01*
X96090Y3729692D01*
X96590Y3729159D01*
X96790Y3728092D01*
X96590Y3727025D01*
X95990Y3726359D01*
X95290Y3725959D01*
X92790D01*
G01X95290D02*
X96790Y3722092D01*
G01X104790D02*
X100790D01*
Y3730092D01*
X104790D01*
G01X103190Y3726225D02*
X100790D01*
G01X108790Y3722092D02*
Y3730092D01*
X111290D01*
X112090Y3729692D01*
X112590Y3729159D01*
X112790Y3728092D01*
X112590Y3727025D01*
X111990Y3726359D01*
X111290Y3725959D01*
X108790D01*
G01X111290D02*
X112790Y3722092D01*
G01X125590Y3730092D02*
X127990D01*
G01X126790D02*
Y3722092D01*
G01X125590D02*
X127990D01*
G01X132690Y3723158D02*
X133490Y3722492D01*
X134390Y3722092D01*
X135190D01*
X135990Y3722492D01*
X136590Y3723158D01*
X136890Y3724092D01*
X136690Y3725025D01*
X136190Y3725825D01*
X135290Y3726359D01*
X134090Y3726625D01*
X133390Y3727159D01*
X133090Y3728092D01*
X133290Y3729025D01*
X133790Y3729692D01*
X134490Y3730092D01*
X135190D01*
X135890Y3729825D01*
X136490Y3729159D01*
G01X148890Y3722092D02*
Y3730092D01*
X152690D01*
G01X151290Y3726225D02*
X148890D01*
G01X156790Y3722092D02*
Y3730092D01*
X159290D01*
X160090Y3729692D01*
X160590Y3729159D01*
X160790Y3728092D01*
X160590Y3727025D01*
X159990Y3726359D01*
X159290Y3725959D01*
X156790D01*
G01X159290D02*
X160790Y3722092D01*
G01X168790D02*
X164790D01*
Y3730092D01*
X168790D01*
G01X167190Y3726225D02*
X164790D01*
G01X176790Y3722092D02*
X172790D01*
Y3730092D01*
X176790D01*
G01X175190Y3726225D02*
X172790D01*
G01X190790Y3730092D02*
Y3722092D01*
G01X188490Y3730092D02*
X193090D01*
G01X198790Y3722092D02*
X197990Y3722225D01*
X197290Y3722759D01*
X196690Y3723559D01*
X196290Y3724492D01*
X196090Y3725559D01*
Y3726625D01*
X196290Y3727692D01*
X196690Y3728625D01*
X197290Y3729425D01*
X197990Y3729959D01*
X198790Y3730092D01*
X199590Y3729959D01*
X200290Y3729425D01*
X200890Y3728625D01*
X201290Y3727692D01*
X201490Y3726625D01*
Y3725559D01*
X201290Y3724492D01*
X200890Y3723559D01*
X200290Y3722759D01*
X199590Y3722225D01*
X198790Y3722092D01*
G01X212290D02*
X214790Y3730092D01*
X217290Y3722092D01*
G01X216390Y3724892D02*
X213190D01*
G01X220590Y3722092D02*
Y3730092D01*
X222590D01*
X223390Y3729692D01*
X223990Y3729159D01*
X224490Y3728359D01*
X224890Y3727425D01*
X224990Y3726092D01*
X224890Y3724759D01*
X224490Y3723825D01*
X223990Y3723025D01*
X223390Y3722492D01*
X222590Y3722092D01*
X220590D01*
G01X228790Y3723692D02*
X229290Y3722892D01*
X229890Y3722359D01*
X230590Y3722092D01*
X231390Y3722359D01*
X231990Y3722892D01*
X232590Y3723692D01*
X232790Y3724759D01*
Y3730092D01*
G01X236590D02*
Y3724359D01*
X236990Y3723158D01*
X237790Y3722359D01*
X238790Y3722092D01*
X239790Y3722359D01*
X240590Y3723158D01*
X240990Y3724359D01*
Y3730092D01*
G01X244690Y3723158D02*
X245490Y3722492D01*
X246390Y3722092D01*
X247190D01*
X247990Y3722492D01*
X248590Y3723158D01*
X248890Y3724092D01*
X248690Y3725025D01*
X248190Y3725825D01*
X247290Y3726359D01*
X246090Y3726625D01*
X245390Y3727159D01*
X245090Y3728092D01*
X245290Y3729025D01*
X245790Y3729692D01*
X246490Y3730092D01*
X247190D01*
X247890Y3729825D01*
X248490Y3729159D01*
G01X254790Y3730092D02*
Y3722092D01*
G01X252490Y3730092D02*
X257090D01*
G01X270790D02*
Y3722092D01*
G01X268490Y3730092D02*
X273090D01*
G01X276790Y3722092D02*
Y3730092D01*
X279290D01*
X280090Y3729692D01*
X280590Y3729159D01*
X280790Y3728092D01*
X280590Y3727025D01*
X279990Y3726359D01*
X279290Y3725959D01*
X276790D01*
G01X279290D02*
X280790Y3722092D01*
G01X284290D02*
X286790Y3730092D01*
X289290Y3722092D01*
G01X288390Y3724892D02*
X285190D01*
G01X296990Y3729425D02*
X296390Y3729825D01*
X295690Y3730092D01*
X294890D01*
X293990Y3729692D01*
X293290Y3729025D01*
X292790Y3728225D01*
X292390Y3726892D01*
X292290Y3725692D01*
X292490Y3724492D01*
X292790Y3723692D01*
X293390Y3722892D01*
X294090Y3722359D01*
X294790Y3722092D01*
X295490D01*
X296190Y3722359D01*
X296790Y3722759D01*
X297290Y3723292D01*
G01X304790Y3722092D02*
X300790D01*
Y3730092D01*
X304790D01*
G01X303190Y3726225D02*
X300790D01*
G01X315790Y3730092D02*
X317190Y3722092D01*
X318790Y3730092D01*
X320390Y3722092D01*
X321790Y3730092D01*
G01X325590D02*
X327990D01*
G01X326790D02*
Y3722092D01*
G01X325590D02*
X327990D01*
G01X332590D02*
Y3730092D01*
X334590D01*
X335390Y3729692D01*
X335990Y3729159D01*
X336490Y3728359D01*
X336890Y3727425D01*
X336990Y3726092D01*
X336890Y3724759D01*
X336490Y3723825D01*
X335990Y3723025D01*
X335390Y3722492D01*
X334590Y3722092D01*
X332590D01*
G01X342790Y3730092D02*
Y3722092D01*
G01X340490Y3730092D02*
X345090D01*
G01X348690Y3722092D02*
Y3730092D01*
G01X352890D02*
Y3722092D01*
G01Y3726092D02*
X348690D01*
G01X356690Y3723158D02*
X357490Y3722492D01*
X358390Y3722092D01*
X359190D01*
X359990Y3722492D01*
X360590Y3723158D01*
X360890Y3724092D01*
X360690Y3725025D01*
X360190Y3725825D01*
X359290Y3726359D01*
X358090Y3726625D01*
X357390Y3727159D01*
X357090Y3728092D01*
X357290Y3729025D01*
X357790Y3729692D01*
X358490Y3730092D01*
X359190D01*
X359890Y3729825D01*
X360490Y3729159D01*
G01X366590Y3720625D02*
X366990Y3722359D01*
G01X388590Y3722092D02*
Y3730092D01*
X390590D01*
X391390Y3729692D01*
X391990Y3729159D01*
X392490Y3728359D01*
X392890Y3727425D01*
X392990Y3726092D01*
X392890Y3724759D01*
X392490Y3723825D01*
X391990Y3723025D01*
X391390Y3722492D01*
X390590Y3722092D01*
X388590D01*
G01X397590Y3730092D02*
X399990D01*
G01X398790D02*
Y3722092D01*
G01X397590D02*
X399990D01*
G01X408790D02*
X404790D01*
Y3730092D01*
X408790D01*
G01X407190Y3726225D02*
X404790D01*
G01X412790Y3730092D02*
Y3722092D01*
X416790D01*
G01X424790D02*
X420790D01*
Y3730092D01*
X424790D01*
G01X423190Y3726225D02*
X420790D01*
G01X432990Y3729425D02*
X432390Y3729825D01*
X431690Y3730092D01*
X430890D01*
X429990Y3729692D01*
X429290Y3729025D01*
X428790Y3728225D01*
X428390Y3726892D01*
X428290Y3725692D01*
X428490Y3724492D01*
X428790Y3723692D01*
X429390Y3722892D01*
X430090Y3722359D01*
X430790Y3722092D01*
X431490D01*
X432190Y3722359D01*
X432790Y3722759D01*
X433290Y3723292D01*
G01X438790Y3730092D02*
Y3722092D01*
G01X436490Y3730092D02*
X441090D01*
G01X444790Y3722092D02*
Y3730092D01*
X447290D01*
X448090Y3729692D01*
X448590Y3729159D01*
X448790Y3728092D01*
X448590Y3727025D01*
X447990Y3726359D01*
X447290Y3725959D01*
X444790D01*
G01X447290D02*
X448790Y3722092D01*
G01X453590Y3730092D02*
X455990D01*
G01X454790D02*
Y3722092D01*
G01X453590D02*
X455990D01*
G01X464990Y3729425D02*
X464390Y3729825D01*
X463690Y3730092D01*
X462890D01*
X461990Y3729692D01*
X461290Y3729025D01*
X460790Y3728225D01*
X460390Y3726892D01*
X460290Y3725692D01*
X460490Y3724492D01*
X460790Y3723692D01*
X461390Y3722892D01*
X462090Y3722359D01*
X462790Y3722092D01*
X463490D01*
X464190Y3722359D01*
X464790Y3722759D01*
X465290Y3723292D01*
G01X-6350Y-464479D02*
Y-539479D01*
X493650D01*
Y-464479D01*
X-6350D01*
G01X6250Y-205760D02*
Y-210410D01*
X-6250D01*
Y-205760D01*
G01X6250Y-187160D02*
Y-182510D01*
X-6250D01*
Y-187160D01*
G01X25412Y3335599D02*
X-17895D01*
G01X-10021D02*
Y3388749D01*
G01X25412Y3351348D02*
X-17895D01*
G01X5650Y-529479D02*
Y-534479D01*
G01X4193Y-529479D02*
X7107D01*
G01X12017Y-534479D02*
X9483D01*
Y-529479D01*
X12017D01*
G01X11003Y-531896D02*
X9483D01*
G01X14583Y-529479D02*
Y-534479D01*
X17117D01*
G01X20950Y-534646D02*
X20823Y-534562D01*
Y-534396D01*
X20950Y-534312D01*
X21077Y-534396D01*
Y-534562D01*
X20950Y-534646D01*
G01Y-532396D02*
X20823Y-532312D01*
Y-532146D01*
X20950Y-532062D01*
X21077Y-532146D01*
Y-532312D01*
X20950Y-532396D01*
G01X25733Y-536146D02*
X25100Y-535312D01*
X24783Y-534479D01*
Y-531146D01*
X25100Y-530312D01*
X25733Y-529479D01*
G01X31150D02*
X30643Y-529646D01*
X30263Y-530062D01*
X30010Y-530562D01*
X29820Y-531229D01*
X29757Y-531979D01*
X29820Y-532729D01*
X30010Y-533396D01*
X30263Y-533896D01*
X30643Y-534312D01*
X31150Y-534479D01*
X31657Y-534312D01*
X32037Y-533896D01*
X32290Y-533396D01*
X32480Y-532729D01*
X32543Y-531979D01*
X32480Y-531229D01*
X32290Y-530562D01*
X32037Y-530062D01*
X31657Y-529646D01*
X31150Y-529479D01*
G01X34857Y-533479D02*
X35237Y-534062D01*
X35743Y-534396D01*
X36313Y-534479D01*
X36820Y-534396D01*
X37327Y-533979D01*
X37643Y-533479D01*
X37707Y-532979D01*
X37580Y-532396D01*
X37137Y-531979D01*
X36693Y-531812D01*
X36123D01*
G01X36693D02*
X37073Y-531562D01*
X37390Y-531146D01*
X37517Y-530646D01*
X37390Y-530146D01*
X37073Y-529729D01*
X36503Y-529479D01*
X35933Y-529562D01*
X35363Y-529896D01*
G01X41667Y-536146D02*
X42300Y-535312D01*
X42617Y-534479D01*
Y-531146D01*
X42300Y-530312D01*
X41667Y-529479D01*
G01X45057Y-533479D02*
X45437Y-534062D01*
X45943Y-534396D01*
X46513Y-534479D01*
X47020Y-534396D01*
X47527Y-533979D01*
X47843Y-533479D01*
X47907Y-532979D01*
X47780Y-532396D01*
X47337Y-531979D01*
X46893Y-531812D01*
X46323D01*
G01X46893D02*
X47273Y-531562D01*
X47590Y-531146D01*
X47717Y-530646D01*
X47590Y-530146D01*
X47273Y-529729D01*
X46703Y-529479D01*
X46133Y-529562D01*
X45563Y-529896D01*
G01X50347Y-530312D02*
X50727Y-529812D01*
X51170Y-529562D01*
X51677Y-529479D01*
X52310Y-529646D01*
X52753Y-530062D01*
X52880Y-530562D01*
X52817Y-531062D01*
X52563Y-531479D01*
X51297Y-532312D01*
X50727Y-532896D01*
X50347Y-533729D01*
X50220Y-534479D01*
X52880D01*
G01X56523D02*
X56650Y-533396D01*
X56840Y-532479D01*
X57093Y-531646D01*
X57410Y-530729D01*
X57917Y-529479D01*
X55383D01*
G01X60927Y-532812D02*
X62573D01*
G01X65647Y-530312D02*
X66027Y-529812D01*
X66470Y-529562D01*
X66977Y-529479D01*
X67610Y-529646D01*
X68053Y-530062D01*
X68180Y-530562D01*
X68117Y-531062D01*
X67863Y-531479D01*
X66597Y-532312D01*
X66027Y-532896D01*
X65647Y-533729D01*
X65520Y-534479D01*
X68180D01*
G01X70557Y-533479D02*
X70937Y-534062D01*
X71443Y-534396D01*
X72013Y-534479D01*
X72520Y-534396D01*
X73027Y-533979D01*
X73343Y-533479D01*
X73407Y-532979D01*
X73280Y-532396D01*
X72837Y-531979D01*
X72393Y-531812D01*
X71823D01*
G01X72393D02*
X72773Y-531562D01*
X73090Y-531146D01*
X73217Y-530646D01*
X73090Y-530146D01*
X72773Y-529729D01*
X72203Y-529479D01*
X71633Y-529562D01*
X71063Y-529896D01*
G01X77810Y-534479D02*
Y-529479D01*
X75467Y-533062D01*
X78633D01*
G01X80757Y-533729D02*
X81137Y-534146D01*
X81580Y-534396D01*
X82150Y-534479D01*
X82720Y-534312D01*
X83163Y-533979D01*
X83480Y-533396D01*
X83543Y-532729D01*
X83417Y-532062D01*
X83100Y-531646D01*
X82657Y-531312D01*
X82213Y-531229D01*
X81770Y-531312D01*
X81200Y-531646D01*
X81390Y-529479D01*
X83100D01*
G01X91147Y-534479D02*
Y-529479D01*
X93553D01*
G01X92667Y-531896D02*
X91147D01*
G01X95867Y-534479D02*
X97450Y-529479D01*
X99033Y-534479D01*
G01X98463Y-532729D02*
X96437D01*
G01X101220Y-534479D02*
X103880Y-529479D01*
G01X101220D02*
X103880Y-534479D01*
G01X107650Y-534646D02*
X107523Y-534562D01*
Y-534396D01*
X107650Y-534312D01*
X107777Y-534396D01*
Y-534562D01*
X107650Y-534646D01*
G01Y-532396D02*
X107523Y-532312D01*
Y-532146D01*
X107650Y-532062D01*
X107777Y-532146D01*
Y-532312D01*
X107650Y-532396D01*
G01X112433Y-536146D02*
X111800Y-535312D01*
X111483Y-534479D01*
Y-531146D01*
X111800Y-530312D01*
X112433Y-529479D01*
G01X117850D02*
X117343Y-529646D01*
X116963Y-530062D01*
X116710Y-530562D01*
X116520Y-531229D01*
X116457Y-531979D01*
X116520Y-532729D01*
X116710Y-533396D01*
X116963Y-533896D01*
X117343Y-534312D01*
X117850Y-534479D01*
X118357Y-534312D01*
X118737Y-533896D01*
X118990Y-533396D01*
X119180Y-532729D01*
X119243Y-531979D01*
X119180Y-531229D01*
X118990Y-530562D01*
X118737Y-530062D01*
X118357Y-529646D01*
X117850Y-529479D01*
G01X121557Y-533479D02*
X121937Y-534062D01*
X122443Y-534396D01*
X123013Y-534479D01*
X123520Y-534396D01*
X124027Y-533979D01*
X124343Y-533479D01*
X124407Y-532979D01*
X124280Y-532396D01*
X123837Y-531979D01*
X123393Y-531812D01*
X122823D01*
G01X123393D02*
X123773Y-531562D01*
X124090Y-531146D01*
X124217Y-530646D01*
X124090Y-530146D01*
X123773Y-529729D01*
X123203Y-529479D01*
X122633Y-529562D01*
X122063Y-529896D01*
G01X128367Y-536146D02*
X129000Y-535312D01*
X129317Y-534479D01*
Y-531146D01*
X129000Y-530312D01*
X128367Y-529479D01*
G01X131757Y-533479D02*
X132137Y-534062D01*
X132643Y-534396D01*
X133213Y-534479D01*
X133720Y-534396D01*
X134227Y-533979D01*
X134543Y-533479D01*
X134607Y-532979D01*
X134480Y-532396D01*
X134037Y-531979D01*
X133593Y-531812D01*
X133023D01*
G01X133593D02*
X133973Y-531562D01*
X134290Y-531146D01*
X134417Y-530646D01*
X134290Y-530146D01*
X133973Y-529729D01*
X133403Y-529479D01*
X132833Y-529562D01*
X132263Y-529896D01*
G01X137173Y-533896D02*
X137617Y-534312D01*
X138123Y-534479D01*
X138630Y-534312D01*
X139073Y-533812D01*
X139390Y-533062D01*
X139517Y-532312D01*
Y-531396D01*
X139390Y-530646D01*
X139073Y-529979D01*
X138693Y-529646D01*
X138250Y-529479D01*
X137743Y-529646D01*
X137363Y-529979D01*
X137110Y-530479D01*
X136983Y-531146D01*
X137110Y-531729D01*
X137427Y-532312D01*
X137807Y-532646D01*
X138250Y-532729D01*
X138757Y-532562D01*
X139137Y-532146D01*
X139517Y-531396D01*
G01X143223Y-534479D02*
X143350Y-533396D01*
X143540Y-532479D01*
X143793Y-531646D01*
X144110Y-530729D01*
X144617Y-529479D01*
X142083D01*
G01X147627Y-532812D02*
X149273D01*
G01X152157Y-533479D02*
X152537Y-534062D01*
X153043Y-534396D01*
X153613Y-534479D01*
X154120Y-534396D01*
X154627Y-533979D01*
X154943Y-533479D01*
X155007Y-532979D01*
X154880Y-532396D01*
X154437Y-531979D01*
X153993Y-531812D01*
X153423D01*
G01X153993D02*
X154373Y-531562D01*
X154690Y-531146D01*
X154817Y-530646D01*
X154690Y-530146D01*
X154373Y-529729D01*
X153803Y-529479D01*
X153233Y-529562D01*
X152663Y-529896D01*
G01X157447Y-532396D02*
X157890Y-531812D01*
X158270Y-531479D01*
X158777Y-531312D01*
X159220Y-531479D01*
X159537Y-531812D01*
X159790Y-532312D01*
X159853Y-532896D01*
X159790Y-533396D01*
X159537Y-533896D01*
X159157Y-534312D01*
X158713Y-534479D01*
X158207Y-534312D01*
X157763Y-533812D01*
X157510Y-533062D01*
X157447Y-532229D01*
X157573Y-531146D01*
X157763Y-530562D01*
X158080Y-529979D01*
X158523Y-529562D01*
X158967Y-529479D01*
X159410Y-529646D01*
X159727Y-530062D01*
G01X163750Y-534479D02*
Y-529479D01*
X162990Y-530479D01*
G01Y-534479D02*
X164510D01*
G01X169610D02*
Y-529479D01*
X167267Y-533062D01*
X170433D01*
G01X0Y-10000D02*
Y-173135D01*
G01X51583Y1969D02*
G03X53551Y0I1968J-1D01*
G01X319693D01*
G03X321661Y1969I0J1968D01*
G01Y38504D01*
G02X329535Y46378I7874J0D01*
G01X488591D01*
G02X496465Y38504I0J-7874D01*
G01Y22756D01*
G03X498433Y20787I1968J-1D01*
G01X764575D01*
G03X766543Y22756I0J1968D01*
G01Y38504D01*
G02X774417Y46378I7874J0D01*
G01X871260D01*
G03X879134Y54252I0J7874D01*
G01Y131004D01*
G02X887008Y138878I7874J0D01*
G01X1011024D01*
G02X1018898Y131004I0J-7874D01*
G01Y54252D01*
G03X1026772Y46378I7874J0D01*
G01X1518118D01*
G02X1525992Y38504I0J-7874D01*
G01Y1969D01*
G03X1527961Y0I1969J0D01*
G01X1794102D01*
G03X1796071Y1969I0J1969D01*
G01Y38504D01*
G02X1803945Y46378I7874J0D01*
G01X1849606D01*
G03X1857480Y54252I0J7874D01*
G01Y305794D01*
G03X1855174Y311361I-7873J0D01*
G01X1846007Y320528D01*
G02X1843701Y326096I5568J5568D01*
G01Y1593983D01*
G03X1841395Y1599550I-7873J0D01*
G01X1834196Y1606749D01*
G02X1831890Y1612317I5568J5568D01*
G01Y1732244D01*
G03X1824016Y1740118I-7874J0D01*
G01X1091777D01*
G03X1089809Y1738150I0J-1968D01*
G01Y1736654D01*
G02X1087854Y1734921I-1955J236D01*
G01X769705D01*
G02X767750Y1736654I0J1969D01*
G01Y1738150D01*
G03X765782Y1740118I-1968J0D01*
G01X33465D01*
G03X25591Y1732244I0J-7874D01*
G01Y1612317D01*
G02X23284Y1606749I-7875J1D01*
G01X10180Y1593645D01*
G03X7874Y1588077I5568J-5568D01*
G01Y320191D01*
G02X5568Y314623I-7874J0D01*
G01X2306Y311361D01*
G03X0Y305794I5567J-5567D01*
G01Y54252D01*
G03X7874Y46378I7874J0D01*
G01X43709D01*
G02X51583Y38504I0J-7874D01*
G01Y1969D01*
G01X0Y1750118D02*
Y1790118D01*
G01X7000Y1781618D02*
X0Y1780118D01*
X7000Y1778618D01*
Y1781618D01*
G01X831015Y1780118D02*
X0D01*
G01X59055Y1791450D02*
X0D01*
Y1822946D01*
X59055D01*
Y1791450D01*
G01X28274Y-241061D02*
Y-245711D01*
X15774D01*
Y-241061D01*
G01X28274Y-197661D02*
Y-193011D01*
X15774D01*
Y-197661D01*
G01X13779Y86795D02*
Y-177100D01*
X22024Y-176947D01*
Y-183636D01*
G01X16535Y87795D02*
G02X38583I11024J0D01*
G02X16535I-11024J0D01*
G01X18661Y1420331D02*
G02X58031I19685J0D01*
G02X18661I-19685J0D01*
G01X58117Y1799500D02*
Y1796400D01*
X57197D01*
X56890Y1796555D01*
X56660Y1796917D01*
X56583Y1797330D01*
X56660Y1797743D01*
X56852Y1798053D01*
X57197Y1798208D01*
X58117D01*
G01X53407Y1796658D02*
X53637Y1796503D01*
X53905Y1796400D01*
X54212D01*
X54557Y1796555D01*
X54825Y1796813D01*
X55017Y1797123D01*
X55170Y1797640D01*
X55208Y1798105D01*
X55132Y1798570D01*
X55017Y1798880D01*
X54787Y1799190D01*
X54518Y1799397D01*
X54250Y1799500D01*
X53982D01*
X53713Y1799397D01*
X53483Y1799242D01*
X53292Y1799035D01*
G01X50843Y1797847D02*
X50690Y1797692D01*
X50575Y1797433D01*
X50498Y1797072D01*
X50575Y1796762D01*
X50728Y1796555D01*
X50997Y1796400D01*
X52032D01*
Y1799500D01*
X50767D01*
X50498Y1799293D01*
X50345Y1798983D01*
X50268Y1798622D01*
X50345Y1798260D01*
X50575Y1797950D01*
X50843Y1797847D01*
X52032D01*
G01X45908Y1796400D02*
X44950Y1799500D01*
X43992Y1796400D01*
G01X41083Y1799500D02*
X42617D01*
Y1796400D01*
X41083D01*
G01X41697Y1797898D02*
X42617D01*
G01X39632Y1799500D02*
Y1796400D01*
X37868Y1799500D01*
Y1796400D01*
G01X36493Y1799500D02*
Y1796400D01*
X35727D01*
X35420Y1796555D01*
X35190Y1796762D01*
X34998Y1797072D01*
X34845Y1797433D01*
X34807Y1797950D01*
X34845Y1798467D01*
X34998Y1798828D01*
X35190Y1799138D01*
X35420Y1799345D01*
X35727Y1799500D01*
X36493D01*
G01X32550D02*
X32857Y1799448D01*
X33125Y1799242D01*
X33355Y1798932D01*
X33508Y1798570D01*
X33585Y1798157D01*
Y1797743D01*
X33508Y1797330D01*
X33355Y1796968D01*
X33125Y1796658D01*
X32857Y1796452D01*
X32550Y1796400D01*
X32243Y1796452D01*
X31975Y1796658D01*
X31745Y1796968D01*
X31592Y1797330D01*
X31515Y1797743D01*
Y1798157D01*
X31592Y1798570D01*
X31745Y1798932D01*
X31975Y1799242D01*
X32243Y1799448D01*
X32550Y1799500D01*
G01X30217D02*
Y1796400D01*
X29258D01*
X28952Y1796555D01*
X28760Y1796762D01*
X28683Y1797175D01*
X28760Y1797588D01*
X28990Y1797847D01*
X29258Y1798002D01*
X30217D01*
G01X29258D02*
X28683Y1799500D01*
G01X38346Y1419330D02*
Y-177099D01*
X54582D01*
X54639Y-182785D01*
G01X40708Y1367897D02*
Y-168539D01*
X71700D01*
X71741Y-182700D01*
G01X29685Y631890D02*
G02X51732I11023J0D01*
G02X29685I-11024J0D01*
G01Y1368898D02*
G02X51732I11023J0D01*
G02X29685I-11024J0D01*
G01X39863Y1441027D02*
X47550Y1449198D01*
G01X45569Y1445657D02*
X44136Y1447005D01*
G01D02*
X47550Y1449198D01*
G01X62205Y1714961D02*
G02X40157I-11024J0D01*
G02X62205I11024J0D01*
G01X49717Y1801800D02*
Y1804900D01*
X48183D01*
G01X45850D02*
X46157Y1804848D01*
X46425Y1804642D01*
X46655Y1804332D01*
X46808Y1803970D01*
X46885Y1803557D01*
Y1803143D01*
X46808Y1802730D01*
X46655Y1802368D01*
X46425Y1802058D01*
X46157Y1801852D01*
X45850Y1801800D01*
X45543Y1801852D01*
X45275Y1802058D01*
X45045Y1802368D01*
X44892Y1802730D01*
X44815Y1803143D01*
Y1803557D01*
X44892Y1803970D01*
X45045Y1804332D01*
X45275Y1804642D01*
X45543Y1804848D01*
X45850Y1804900D01*
G01X42520Y1803350D02*
X41753D01*
Y1804280D01*
X41983Y1804590D01*
X42252Y1804797D01*
X42635Y1804900D01*
X43018Y1804797D01*
X43287Y1804590D01*
X43517Y1804280D01*
X43670Y1803918D01*
X43747Y1803505D01*
Y1803143D01*
X43670Y1802833D01*
X43517Y1802472D01*
X43287Y1802162D01*
X43057Y1801955D01*
X42750Y1801800D01*
X42482D01*
X42175Y1801903D01*
X41945Y1802110D01*
G01X39650Y1804900D02*
X39957Y1804848D01*
X40225Y1804642D01*
X40455Y1804332D01*
X40608Y1803970D01*
X40685Y1803557D01*
Y1803143D01*
X40608Y1802730D01*
X40455Y1802368D01*
X40225Y1802058D01*
X39957Y1801852D01*
X39650Y1801800D01*
X39343Y1801852D01*
X39075Y1802058D01*
X38845Y1802368D01*
X38692Y1802730D01*
X38615Y1803143D01*
Y1803557D01*
X38692Y1803970D01*
X38845Y1804332D01*
X39075Y1804642D01*
X39343Y1804848D01*
X39650Y1804900D01*
G01X74624Y3184025D02*
X43128D01*
G01D02*
X84467D01*
G01X35254Y3253907D02*
G03I-2953J0D01*
G01Y3273592D02*
G03I-2953J0D01*
G01X29349Y3315914D02*
X604152D01*
G01X29349Y3331662D02*
Y3315914D01*
G01Y3335599D02*
X604152D01*
G01Y3331662D02*
X29349D01*
G01Y3351348D02*
Y3335599D01*
G01X604152Y3351348D02*
X29349D01*
G01Y3355285D02*
Y3426151D01*
G01Y3418277D02*
X324624D01*
G01X61749Y-252610D02*
Y-257260D01*
X49249D01*
Y-252610D01*
G01X61749Y-196810D02*
Y-192160D01*
X49249D01*
Y-196810D01*
G01X51181Y1713961D02*
Y-162348D01*
X89431D01*
X89499Y-182957D01*
G01X52141Y119148D02*
X56741Y123451D01*
G02X65079Y114538I4169J-4456D01*
G01X60479Y110235D01*
G02X52141Y119148I-4169J4456D01*
G01X47550Y1449198D02*
X45569Y1445657D01*
G01X54939Y3253907D02*
G03I-2953J0D01*
G01Y3273592D02*
G03I-2953J0D01*
G01X78256Y-264925D02*
Y-269575D01*
X65756D01*
Y-264925D01*
G01X78256Y-196725D02*
Y-192075D01*
X65756D01*
Y-196725D01*
G01X69295Y120567D02*
X80129Y117658D01*
G01X76072Y117729D02*
X76583Y119629D01*
G01D02*
X80129Y117658D01*
G01D02*
X76072Y117729D01*
G01X66980Y3165267D02*
X67910Y3164225D01*
X68995Y3163600D01*
X70390Y3163392D01*
X71785Y3163809D01*
X72870Y3164642D01*
X73645Y3166100D01*
X73800Y3167767D01*
X73490Y3169434D01*
X72715Y3170475D01*
X71630Y3171309D01*
X70545Y3171517D01*
X69460Y3171309D01*
X68065Y3170475D01*
X68530Y3175892D01*
X72715D01*
G01X78760Y3163392D02*
Y3175892D01*
X82790Y3165475D01*
X86820Y3175892D01*
Y3163392D01*
G01X91160D02*
Y3175892D01*
X95190Y3165475D01*
X99220Y3175892D01*
Y3163392D01*
G01X74624Y3246405D02*
Y3176151D01*
G01Y3253907D02*
G03I-2952J0D01*
G01Y3273592D02*
G03I-2952J0D01*
G01X95990Y-227982D02*
Y-232632D01*
X83490D01*
Y-227982D01*
G01X95990Y-196982D02*
Y-192332D01*
X83490D01*
Y-196982D01*
G01X125805Y3184025D02*
X84467D01*
G01X98248Y605378D02*
G02X137618I19685J0D01*
G02X98248I-19685J0D01*
G01X125805Y3156466D02*
X94309D01*
G01D02*
X135648D01*
G01X94309Y3246755D02*
Y3176151D01*
G01Y3184025D02*
X125805D01*
G01X94309Y3256859D02*
X100215D01*
G01Y3250954D02*
X94309D01*
G01X100215Y3256859D02*
Y3250954D01*
G01X94309D02*
Y3256859D01*
G01X100215Y3270639D02*
X94309D01*
G01X100215Y3276544D02*
Y3270639D01*
G01X94309D02*
Y3276544D01*
G01D02*
X100215D01*
G01X124182Y-265963D02*
Y-270613D01*
X111682D01*
Y-265963D01*
G01X124182Y-197763D02*
Y-193113D01*
X111682D01*
Y-197763D01*
G01X117932Y604380D02*
Y-183738D01*
G01X119980Y3133867D02*
X120910Y3132825D01*
X121995Y3132200D01*
X123390Y3131992D01*
X124785Y3132409D01*
X125870Y3133242D01*
X126645Y3134700D01*
X126800Y3136367D01*
X126490Y3138034D01*
X125715Y3139075D01*
X124630Y3139909D01*
X123545Y3140117D01*
X122460Y3139909D01*
X121065Y3139075D01*
X121530Y3144492D01*
X125715D01*
G01X131760Y3131992D02*
Y3144492D01*
X135790Y3134075D01*
X139820Y3144492D01*
Y3131992D01*
G01X144160D02*
Y3144492D01*
X148190Y3134075D01*
X152220Y3144492D01*
Y3131992D01*
G01X125805Y3247017D02*
Y3148592D01*
G01X145490Y3208167D02*
X113994D01*
G01D02*
X148443D01*
G01X119900Y3256859D02*
X125805D01*
G01Y3250954D02*
X119900D01*
G01X125805Y3256859D02*
Y3250954D01*
G01X119900D02*
Y3256859D01*
G01X125805Y3270639D02*
X119900D01*
G01X125805Y3276544D02*
Y3270639D01*
G01X119900D02*
Y3276544D01*
G01D02*
X125805D01*
G01X140754Y610529D02*
X148441Y618700D01*
G01X176986Y3156466D02*
X135648D01*
G01X197098Y294335D02*
Y260083D01*
G02X157728I-19685J0D01*
G01Y294335D01*
G02X197098I19685J0D01*
G01X146460Y615159D02*
X145027Y616507D01*
G01D02*
X148441Y618700D01*
G01D02*
X146460Y615159D01*
G01X196996Y1671142D02*
Y1644764D01*
G02X157626I-19685J0D01*
G01Y1671142D01*
G02X196996I19685J0D01*
G01X145490Y3247017D02*
Y3148592D01*
G01Y3156466D02*
X176986D01*
G01X151396Y3246332D02*
Y3200293D01*
G01X145490Y3242833D02*
Y3200293D01*
G01X151396Y3208167D02*
X217922D01*
G01D02*
X148443D01*
G01X145490Y3256859D02*
X151396D01*
G01Y3250954D02*
X145490D01*
G01X151396Y3256859D02*
Y3250954D01*
G01X145490D02*
Y3256859D01*
G01X151396Y3270639D02*
X145490D01*
G01X151396Y3276544D02*
Y3270639D01*
G01X145490D02*
Y3276544D01*
G01X155333Y3270639D02*
X275063D01*
G01X145490Y3276544D02*
X151396D01*
G01X155333D02*
X275063D01*
G01X175405Y3211120D02*
Y3223620D01*
X173545Y3221120D01*
G01Y3211120D02*
X177265D01*
G01X187805Y3210703D02*
X187495Y3210912D01*
Y3211328D01*
X187805Y3211537D01*
X188115Y3211328D01*
Y3210912D01*
X187805Y3210703D01*
G01X196795Y3212995D02*
X197725Y3211953D01*
X198810Y3211328D01*
X200205Y3211120D01*
X201600Y3211537D01*
X202685Y3212370D01*
X203460Y3213828D01*
X203615Y3215495D01*
X203305Y3217162D01*
X202530Y3218203D01*
X201445Y3219037D01*
X200360Y3219245D01*
X199275Y3219037D01*
X197880Y3218203D01*
X198345Y3223620D01*
X202530D01*
G01X208575Y3211120D02*
Y3223620D01*
X212605Y3213203D01*
X216635Y3223620D01*
Y3211120D01*
G01X220975D02*
Y3223620D01*
X225005Y3213203D01*
X229035Y3223620D01*
Y3211120D01*
G01X188650Y-464479D02*
Y-539479D01*
G01Y-514479D02*
X291650D01*
Y-489479D01*
G01X188650D02*
X291650D01*
G01X187527Y313060D02*
X195214Y321231D01*
G01X193233Y317690D02*
X191800Y319038D01*
G01D02*
X195214Y321231D01*
G01D02*
X193233Y317690D01*
G01X196997Y1679594D02*
X204684Y1687765D01*
G01D02*
X202703Y1684224D01*
G01X201270Y1685572D02*
X204684Y1687765D01*
G01X202703Y1684224D02*
X201270Y1685572D01*
G01X204690Y3828158D02*
X205490Y3827492D01*
X206390Y3827092D01*
X207190D01*
X207990Y3827492D01*
X208590Y3828158D01*
X208890Y3829092D01*
X208690Y3830025D01*
X208190Y3830825D01*
X207290Y3831359D01*
X206090Y3831625D01*
X205390Y3832159D01*
X205090Y3833092D01*
X205290Y3834025D01*
X205790Y3834692D01*
X206490Y3835092D01*
X207190D01*
X207890Y3834825D01*
X208490Y3834159D01*
G01X214790Y3827092D02*
X213990Y3827225D01*
X213290Y3827759D01*
X212690Y3828559D01*
X212290Y3829492D01*
X212090Y3830559D01*
Y3831625D01*
X212290Y3832692D01*
X212690Y3833625D01*
X213290Y3834425D01*
X213990Y3834959D01*
X214790Y3835092D01*
X215590Y3834959D01*
X216290Y3834425D01*
X216890Y3833625D01*
X217290Y3832692D01*
X217490Y3831625D01*
Y3830559D01*
X217290Y3829492D01*
X216890Y3828559D01*
X216290Y3827759D01*
X215590Y3827225D01*
X214790Y3827092D01*
G01X220790Y3835092D02*
Y3827092D01*
X224790D01*
G01X228590D02*
Y3835092D01*
X230590D01*
X231390Y3834692D01*
X231990Y3834159D01*
X232490Y3833359D01*
X232890Y3832425D01*
X232990Y3831092D01*
X232890Y3829759D01*
X232490Y3828825D01*
X231990Y3828025D01*
X231390Y3827492D01*
X230590Y3827092D01*
X228590D01*
G01X240790D02*
X236790D01*
Y3835092D01*
X240790D01*
G01X239190Y3831225D02*
X236790D01*
G01X244790Y3827092D02*
Y3835092D01*
X247290D01*
X248090Y3834692D01*
X248590Y3834159D01*
X248790Y3833092D01*
X248590Y3832025D01*
X247990Y3831359D01*
X247290Y3830959D01*
X244790D01*
G01X247290D02*
X248790Y3827092D01*
G01X252190D02*
Y3835092D01*
X254790Y3828425D01*
X257390Y3835092D01*
Y3827092D01*
G01X260290D02*
X262790Y3835092D01*
X265290Y3827092D01*
G01X264390Y3829892D02*
X261190D01*
G01X268690Y3828158D02*
X269490Y3827492D01*
X270390Y3827092D01*
X271190D01*
X271990Y3827492D01*
X272590Y3828158D01*
X272890Y3829092D01*
X272690Y3830025D01*
X272190Y3830825D01*
X271290Y3831359D01*
X270090Y3831625D01*
X269390Y3832159D01*
X269090Y3833092D01*
X269290Y3834025D01*
X269790Y3834692D01*
X270490Y3835092D01*
X271190D01*
X271890Y3834825D01*
X272490Y3834159D01*
G01X276590Y3827092D02*
Y3835092D01*
G01X280390D02*
X276590Y3830158D01*
G01X280990Y3827092D02*
X278290Y3832425D01*
G01X294790Y3827092D02*
X293990Y3827225D01*
X293290Y3827759D01*
X292690Y3828559D01*
X292290Y3829492D01*
X292090Y3830559D01*
Y3831625D01*
X292290Y3832692D01*
X292690Y3833625D01*
X293290Y3834425D01*
X293990Y3834959D01*
X294790Y3835092D01*
X295590Y3834959D01*
X296290Y3834425D01*
X296890Y3833625D01*
X297290Y3832692D01*
X297490Y3831625D01*
Y3830559D01*
X297290Y3829492D01*
X296890Y3828559D01*
X296290Y3827759D01*
X295590Y3827225D01*
X294790Y3827092D01*
G01X300790D02*
Y3835092D01*
X303190D01*
X303990Y3834692D01*
X304590Y3833759D01*
X304790Y3832692D01*
X304590Y3831625D01*
X304090Y3830825D01*
X303190Y3830425D01*
X300790D01*
G01X312790Y3827092D02*
X308790D01*
Y3835092D01*
X312790D01*
G01X311190Y3831225D02*
X308790D01*
G01X316490Y3827092D02*
Y3835092D01*
X321090Y3827092D01*
Y3835092D01*
G01X334790Y3827092D02*
X333990Y3827225D01*
X333290Y3827759D01*
X332690Y3828559D01*
X332290Y3829492D01*
X332090Y3830559D01*
Y3831625D01*
X332290Y3832692D01*
X332690Y3833625D01*
X333290Y3834425D01*
X333990Y3834959D01*
X334790Y3835092D01*
X335590Y3834959D01*
X336290Y3834425D01*
X336890Y3833625D01*
X337290Y3832692D01*
X337490Y3831625D01*
Y3830559D01*
X337290Y3829492D01*
X336890Y3828559D01*
X336290Y3827759D01*
X335590Y3827225D01*
X334790Y3827092D01*
G01X340490D02*
Y3835092D01*
X345090Y3827092D01*
Y3835092D01*
G01X359590Y3831359D02*
X359990Y3831759D01*
X360290Y3832425D01*
X360490Y3833359D01*
X360290Y3834159D01*
X359890Y3834692D01*
X359190Y3835092D01*
X356490D01*
Y3827092D01*
X359790D01*
X360490Y3827625D01*
X360890Y3828425D01*
X361090Y3829359D01*
X360890Y3830292D01*
X360290Y3831092D01*
X359590Y3831359D01*
X356490D01*
G01X366790Y3827092D02*
X365990Y3827225D01*
X365290Y3827759D01*
X364690Y3828559D01*
X364290Y3829492D01*
X364090Y3830559D01*
Y3831625D01*
X364290Y3832692D01*
X364690Y3833625D01*
X365290Y3834425D01*
X365990Y3834959D01*
X366790Y3835092D01*
X367590Y3834959D01*
X368290Y3834425D01*
X368890Y3833625D01*
X369290Y3832692D01*
X369490Y3831625D01*
Y3830559D01*
X369290Y3829492D01*
X368890Y3828559D01*
X368290Y3827759D01*
X367590Y3827225D01*
X366790Y3827092D01*
G01X374790Y3835092D02*
Y3827092D01*
G01X372490Y3835092D02*
X377090D01*
G01X380690Y3827092D02*
Y3835092D01*
G01X384890D02*
Y3827092D01*
G01Y3831092D02*
X380690D01*
G01X396690Y3828158D02*
X397490Y3827492D01*
X398390Y3827092D01*
X399190D01*
X399990Y3827492D01*
X400590Y3828158D01*
X400890Y3829092D01*
X400690Y3830025D01*
X400190Y3830825D01*
X399290Y3831359D01*
X398090Y3831625D01*
X397390Y3832159D01*
X397090Y3833092D01*
X397290Y3834025D01*
X397790Y3834692D01*
X398490Y3835092D01*
X399190D01*
X399890Y3834825D01*
X400490Y3834159D01*
G01X405590Y3835092D02*
X407990D01*
G01X406790D02*
Y3827092D01*
G01X405590D02*
X407990D01*
G01X412590D02*
Y3835092D01*
X414590D01*
X415390Y3834692D01*
X415990Y3834159D01*
X416490Y3833359D01*
X416890Y3832425D01*
X416990Y3831092D01*
X416890Y3829759D01*
X416490Y3828825D01*
X415990Y3828025D01*
X415390Y3827492D01*
X414590Y3827092D01*
X412590D01*
G01X424790D02*
X420790D01*
Y3835092D01*
X424790D01*
G01X423190Y3831225D02*
X420790D01*
G01X430790Y3826825D02*
X430590Y3826959D01*
Y3827225D01*
X430790Y3827359D01*
X430990Y3827225D01*
Y3826959D01*
X430790Y3826825D01*
G01X240582Y190041D02*
X232668Y197991D01*
G01D02*
X236142Y195895D01*
G01D02*
X234748Y194507D01*
G01D02*
X232668Y197991D01*
G01X226606Y1738112D02*
X290406D01*
Y1640912D01*
X226606D01*
Y1738112D01*
G01X256576Y-265755D02*
Y-270405D01*
X244076D01*
Y-265755D01*
G01X256576Y-197555D02*
Y-192905D01*
X244076D01*
Y-197555D01*
G01X250326Y184236D02*
Y-183530D01*
G01X247177Y191535D02*
X253476D01*
G02Y178937I0J-6299D01*
G01X247177D01*
G02Y191535I0J6299D01*
G01X258331Y3161831D02*
X245831D01*
X248331Y3159971D01*
G01X258331D02*
Y3163691D01*
G01X258748Y3174231D02*
X258539Y3173921D01*
X258123D01*
X257914Y3174231D01*
X258123Y3174541D01*
X258539D01*
X258748Y3174231D01*
G01X256456Y3183221D02*
X257498Y3184151D01*
X258123Y3185236D01*
X258331Y3186631D01*
X257914Y3188026D01*
X257081Y3189111D01*
X255623Y3189886D01*
X253956Y3190041D01*
X252289Y3189731D01*
X251248Y3188956D01*
X250414Y3187871D01*
X250206Y3186786D01*
X250414Y3185701D01*
X251248Y3184306D01*
X245831Y3184771D01*
Y3188956D01*
G01X258331Y3195001D02*
X245831D01*
X256248Y3199031D01*
X245831Y3203061D01*
X258331D01*
G01Y3207401D02*
X245831D01*
X256248Y3211431D01*
X245831Y3215461D01*
X258331D01*
G01X277589Y-265757D02*
Y-270407D01*
X265089D01*
Y-265757D01*
G01X277589Y-197557D02*
Y-192907D01*
X265089D01*
Y-197557D01*
G01X277098Y184236D02*
Y-163647D01*
X271034Y-163341D01*
X271086Y-183532D01*
G01X269618Y185236D02*
G02X284579I7481J0D01*
G02X269618I-7481J0D01*
G01X398970Y2009802D02*
X269030Y1741842D01*
G01X267189Y3270639D02*
Y3174820D01*
G01D02*
Y3273592D01*
G01Y3308040D02*
Y3273592D01*
G01Y3276544D02*
Y3308040D01*
G01X275024Y3421229D02*
Y3433729D01*
X273164Y3431229D01*
G01Y3421229D02*
X276884D01*
G01X287424Y3433729D02*
X286184Y3433312D01*
X285254Y3432271D01*
X284634Y3431021D01*
X284169Y3429354D01*
X284014Y3427479D01*
X284169Y3425604D01*
X284634Y3423937D01*
X285254Y3422687D01*
X286184Y3421646D01*
X287424Y3421229D01*
X288664Y3421646D01*
X289594Y3422687D01*
X290214Y3423937D01*
X290679Y3425604D01*
X290834Y3427479D01*
X290679Y3429354D01*
X290214Y3431021D01*
X289594Y3432271D01*
X288664Y3433312D01*
X287424Y3433729D01*
G01X299824D02*
X298584Y3433312D01*
X297654Y3432271D01*
X297034Y3431021D01*
X296569Y3429354D01*
X296414Y3427479D01*
X296569Y3425604D01*
X297034Y3423937D01*
X297654Y3422687D01*
X298584Y3421646D01*
X299824Y3421229D01*
X301064Y3421646D01*
X301994Y3422687D01*
X302614Y3423937D01*
X303079Y3425604D01*
X303234Y3427479D01*
X303079Y3429354D01*
X302614Y3431021D01*
X301994Y3432271D01*
X301064Y3433312D01*
X299824Y3433729D01*
G01X310209Y3425396D02*
X314239D01*
G01X324624Y3421229D02*
Y3433729D01*
X322764Y3431229D01*
G01Y3421229D02*
X326484D01*
G01X333614Y3423104D02*
X334544Y3422062D01*
X335629Y3421437D01*
X337024Y3421229D01*
X338419Y3421646D01*
X339504Y3422479D01*
X340279Y3423937D01*
X340434Y3425604D01*
X340124Y3427271D01*
X339349Y3428312D01*
X338264Y3429146D01*
X337179Y3429354D01*
X336094Y3429146D01*
X334699Y3428312D01*
X335164Y3433729D01*
X339349D01*
G01X349424D02*
X348184Y3433312D01*
X347254Y3432271D01*
X346634Y3431021D01*
X346169Y3429354D01*
X346014Y3427479D01*
X346169Y3425604D01*
X346634Y3423937D01*
X347254Y3422687D01*
X348184Y3421646D01*
X349424Y3421229D01*
X350664Y3421646D01*
X351594Y3422687D01*
X352214Y3423937D01*
X352679Y3425604D01*
X352834Y3427479D01*
X352679Y3429354D01*
X352214Y3431021D01*
X351594Y3432271D01*
X350664Y3433312D01*
X349424Y3433729D01*
G01X357794Y3421229D02*
Y3433729D01*
X361824Y3423312D01*
X365854Y3433729D01*
Y3421229D01*
G01X370194D02*
Y3433729D01*
X374224Y3423312D01*
X378254Y3433729D01*
Y3421229D01*
G01X295625Y-265757D02*
Y-270407D01*
X283125D01*
Y-265757D01*
G01X295625Y-197557D02*
Y-192907D01*
X283125D01*
Y-197557D01*
G01X306772Y990220D02*
Y-137965D01*
X288766D01*
X288959Y-183532D01*
G01X291650Y-464479D02*
Y-539479D01*
G01X293650Y-464479D02*
Y-539479D01*
G01X299157Y-524479D02*
Y-519479D01*
X300423D01*
X300930Y-519729D01*
X301310Y-520062D01*
X301627Y-520562D01*
X301880Y-521146D01*
X301943Y-521979D01*
X301880Y-522812D01*
X301627Y-523396D01*
X301310Y-523896D01*
X300930Y-524229D01*
X300423Y-524479D01*
X299157D01*
G01X304067D02*
X305650Y-519479D01*
X307233Y-524479D01*
G01X306663Y-522729D02*
X304637D01*
G01X310750Y-519479D02*
Y-524479D01*
G01X309293Y-519479D02*
X312207D01*
G01X317117Y-524479D02*
X314583D01*
Y-519479D01*
X317117D01*
G01X316103Y-521896D02*
X314583D01*
G01X320950Y-524646D02*
X320823Y-524562D01*
Y-524396D01*
X320950Y-524312D01*
X321077Y-524396D01*
Y-524562D01*
X320950Y-524646D01*
G01Y-522396D02*
X320823Y-522312D01*
Y-522146D01*
X320950Y-522062D01*
X321077Y-522146D01*
Y-522312D01*
X320950Y-522396D01*
G01X299283Y-499479D02*
Y-494479D01*
X300803D01*
X301310Y-494729D01*
X301690Y-495312D01*
X301817Y-495979D01*
X301690Y-496646D01*
X301373Y-497146D01*
X300803Y-497396D01*
X299283D01*
G01X304510Y-499646D02*
X306790Y-494479D01*
G01X309293Y-499479D02*
Y-494479D01*
X312207Y-499479D01*
Y-494479D01*
G01X315850Y-499646D02*
X315723Y-499562D01*
Y-499396D01*
X315850Y-499312D01*
X315977Y-499396D01*
Y-499562D01*
X315850Y-499646D01*
G01Y-497396D02*
X315723Y-497312D01*
Y-497146D01*
X315850Y-497062D01*
X315977Y-497146D01*
Y-497312D01*
X315850Y-497396D01*
G01X293650Y-514479D02*
X493650D01*
G01X293650Y-489479D02*
X493650D01*
G01X299283Y-474479D02*
Y-469479D01*
X300803D01*
X301310Y-469729D01*
X301690Y-470312D01*
X301817Y-470979D01*
X301690Y-471646D01*
X301373Y-472146D01*
X300803Y-472396D01*
X299283D01*
G01X304383Y-474479D02*
Y-469479D01*
X305967D01*
X306473Y-469729D01*
X306790Y-470062D01*
X306917Y-470729D01*
X306790Y-471396D01*
X306410Y-471812D01*
X305967Y-472062D01*
X304383D01*
G01X305967D02*
X306917Y-474479D01*
G01X310750D02*
X310243Y-474396D01*
X309800Y-474062D01*
X309420Y-473562D01*
X309167Y-472979D01*
X309040Y-472312D01*
Y-471646D01*
X309167Y-470979D01*
X309420Y-470396D01*
X309800Y-469896D01*
X310243Y-469562D01*
X310750Y-469479D01*
X311257Y-469562D01*
X311700Y-469896D01*
X312080Y-470396D01*
X312333Y-470979D01*
X312460Y-471646D01*
Y-472312D01*
X312333Y-472979D01*
X312080Y-473562D01*
X311700Y-474062D01*
X311257Y-474396D01*
X310750Y-474479D01*
G01X314583Y-473479D02*
X314900Y-473979D01*
X315280Y-474312D01*
X315723Y-474479D01*
X316230Y-474312D01*
X316610Y-473979D01*
X316990Y-473479D01*
X317117Y-472812D01*
Y-469479D01*
G01X322217Y-474479D02*
X319683D01*
Y-469479D01*
X322217D01*
G01X321203Y-471896D02*
X319683D01*
G01X327443Y-469896D02*
X327063Y-469646D01*
X326620Y-469479D01*
X326113D01*
X325543Y-469729D01*
X325100Y-470146D01*
X324783Y-470646D01*
X324530Y-471479D01*
X324467Y-472229D01*
X324593Y-472979D01*
X324783Y-473479D01*
X325163Y-473979D01*
X325607Y-474312D01*
X326050Y-474479D01*
X326493D01*
X326937Y-474312D01*
X327317Y-474062D01*
X327633Y-473729D01*
G01X331150Y-469479D02*
Y-474479D01*
G01X329693Y-469479D02*
X332607D01*
G01X336250Y-474646D02*
X336123Y-474562D01*
Y-474396D01*
X336250Y-474312D01*
X336377Y-474396D01*
Y-474562D01*
X336250Y-474646D01*
G01Y-472396D02*
X336123Y-472312D01*
Y-472146D01*
X336250Y-472062D01*
X336377Y-472146D01*
Y-472312D01*
X336250Y-472396D01*
G01X313054Y-265756D02*
Y-270406D01*
X300554D01*
Y-265756D01*
G01X313054Y-197556D02*
Y-192906D01*
X300554D01*
Y-197556D01*
G01X300019Y991220D02*
G02X313523I6752J0D01*
G02X300019I-6752J0D01*
G01X356685Y1668212D02*
X293635D01*
Y1736912D01*
X356685D01*
Y1668212D01*
G01X322500Y1390830D02*
Y-142552D01*
X306193Y-142246D01*
X306374Y-183531D01*
G01X306149Y998645D02*
X313836Y1006816D01*
G01X311855Y1003275D02*
X310422Y1004623D01*
G01D02*
X313836Y1006816D01*
G01D02*
X311855Y1003275D01*
G01X316200Y1391831D02*
G02X328799I6299J0D01*
G02X316200I-6299J0D01*
G01X327790Y3263892D02*
X329790D01*
Y3261492D01*
X329190Y3260692D01*
X328490Y3260159D01*
X327490Y3259892D01*
X326490Y3260159D01*
X325790Y3260692D01*
X325190Y3261492D01*
X324790Y3262425D01*
X324590Y3263492D01*
Y3264425D01*
X324790Y3265225D01*
X325190Y3266159D01*
X325790Y3266959D01*
X326390Y3267492D01*
X327190Y3267892D01*
X327890D01*
X328690Y3267625D01*
X329290Y3267092D01*
G01X333190Y3259892D02*
Y3267892D01*
X335690D01*
X336490Y3267492D01*
X336990Y3266959D01*
X337190Y3265892D01*
X336990Y3264825D01*
X336390Y3264159D01*
X335690Y3263759D01*
X333190D01*
G01X335690D02*
X337190Y3259892D01*
G01X343190D02*
X342390Y3260025D01*
X341690Y3260559D01*
X341090Y3261359D01*
X340690Y3262292D01*
X340490Y3263359D01*
Y3264425D01*
X340690Y3265492D01*
X341090Y3266425D01*
X341690Y3267225D01*
X342390Y3267759D01*
X343190Y3267892D01*
X343990Y3267759D01*
X344690Y3267225D01*
X345290Y3266425D01*
X345690Y3265492D01*
X345890Y3264425D01*
Y3263359D01*
X345690Y3262292D01*
X345290Y3261359D01*
X344690Y3260559D01*
X343990Y3260025D01*
X343190Y3259892D01*
G01X348990Y3267892D02*
Y3262159D01*
X349390Y3260958D01*
X350190Y3260159D01*
X351190Y3259892D01*
X352190Y3260159D01*
X352990Y3260958D01*
X353390Y3262159D01*
Y3267892D01*
G01X357190Y3259892D02*
Y3267892D01*
X359590D01*
X360390Y3267492D01*
X360990Y3266559D01*
X361190Y3265492D01*
X360990Y3264425D01*
X360490Y3263625D01*
X359590Y3263225D01*
X357190D01*
G01X365090Y3260958D02*
X365890Y3260292D01*
X366790Y3259892D01*
X367590D01*
X368390Y3260292D01*
X368990Y3260958D01*
X369290Y3261892D01*
X369090Y3262825D01*
X368590Y3263625D01*
X367690Y3264159D01*
X366490Y3264425D01*
X365790Y3264959D01*
X365490Y3265892D01*
X365690Y3266825D01*
X366190Y3267492D01*
X366890Y3267892D01*
X367590D01*
X368290Y3267625D01*
X368890Y3266959D01*
G01X383990Y3264159D02*
X384390Y3264559D01*
X384690Y3265225D01*
X384890Y3266159D01*
X384690Y3266959D01*
X384290Y3267492D01*
X383590Y3267892D01*
X380890D01*
Y3259892D01*
X384190D01*
X384890Y3260425D01*
X385290Y3261225D01*
X385490Y3262159D01*
X385290Y3263092D01*
X384690Y3263892D01*
X383990Y3264159D01*
X380890D01*
G01X345524Y-266077D02*
Y-270727D01*
X333024D01*
Y-266077D01*
G01X345524Y-197877D02*
Y-193227D01*
X333024D01*
Y-197877D01*
G01X412100Y2008462D02*
X335010Y1745882D01*
G01X619900Y3418277D02*
X324624D01*
G01X362313Y-265962D02*
Y-270612D01*
X349813D01*
Y-265962D01*
G01X362313Y-197762D02*
Y-193112D01*
X349813D01*
Y-197762D01*
G01X350099Y810121D02*
Y-162160D01*
X339731D01*
X339648Y-183852D01*
G01X343346Y811122D02*
G02X356850I6752J0D01*
G02X343346I-6752J0D01*
G01X349310Y1171319D02*
G02X362814I6752J0D01*
G02X349310I-6752J0D01*
G01X378500Y-265610D02*
Y-270260D01*
X366000D01*
Y-265610D01*
G01X378500Y-197410D02*
Y-192760D01*
X366000D01*
Y-197410D01*
G01X356063Y1170318D02*
Y-183737D01*
G01X368437Y175236D02*
Y-168410D01*
X371640D01*
X371721Y-183385D01*
G01X362598Y87795D02*
G02X384646I11024J0D01*
G02X362598I-11024J0D01*
G01X365287Y191535D02*
X371587D01*
G02Y178937I0J-6299D01*
G01X365287D01*
G02Y191535I0J6299D01*
G01X370249Y177751D02*
X375852Y168033D01*
G01X356746Y815058D02*
X364433Y823229D01*
G01X362452Y819688D02*
X361019Y821036D01*
G01D02*
X364433Y823229D01*
G01D02*
X362452Y819688D01*
G01X362399Y1176726D02*
X370086Y1184897D01*
G01X368105Y1181356D02*
X366672Y1182704D01*
G01D02*
X370086Y1184897D01*
G01D02*
X368105Y1181356D01*
G01X393765Y-253443D02*
Y-258093D01*
X381265D01*
Y-253443D01*
G01X393765Y-197643D02*
Y-192993D01*
X381265D01*
Y-197643D01*
G01X373622Y86795D02*
Y-161811D01*
X387209Y-161506D01*
X387268Y-183618D01*
G01X374739Y171934D02*
X375852Y168033D01*
G01D02*
X373034Y170952D01*
G01D02*
X374739Y171934D01*
G01X384647Y1714961D02*
G02X406694I11023J0D01*
G02X384647I-11023J0D01*
G01X413025Y-266062D02*
Y-270712D01*
X400525D01*
Y-266062D01*
G01X413025Y-197862D02*
Y-193212D01*
X400525D01*
Y-197862D01*
G01X395670Y1713961D02*
Y-161506D01*
X406470D01*
X406527Y-183837D01*
G01X395208Y175236D02*
Y-156980D01*
X423680D01*
X423557Y-183805D01*
G01X387728Y185236D02*
G02X402689I7481J0D01*
G02X387728I-7480J0D01*
G01X397265Y2002849D02*
X398970Y2009802D01*
X394566Y2004158D01*
X397265Y2002849D01*
G01X408650Y-514479D02*
Y-539479D01*
G01X411283Y-516979D02*
Y-521979D01*
X413817D01*
G01X416890Y-516979D02*
X418410D01*
G01X417650D02*
Y-521979D01*
G01X416890D02*
X418410D01*
G01X423257Y-519312D02*
X423510Y-519062D01*
X423700Y-518646D01*
X423827Y-518062D01*
X423700Y-517562D01*
X423447Y-517229D01*
X423003Y-516979D01*
X421293D01*
Y-521979D01*
X423383D01*
X423827Y-521646D01*
X424080Y-521146D01*
X424207Y-520562D01*
X424080Y-519979D01*
X423700Y-519479D01*
X423257Y-519312D01*
X421293D01*
G01X427850Y-522146D02*
X427723Y-522062D01*
Y-521896D01*
X427850Y-521812D01*
X427977Y-521896D01*
Y-522062D01*
X427850Y-522146D01*
G01Y-519896D02*
X427723Y-519812D01*
Y-519646D01*
X427850Y-519562D01*
X427977Y-519646D01*
Y-519812D01*
X427850Y-519896D01*
G01X429330Y-278430D02*
Y-283080D01*
X416830D01*
Y-278430D01*
G01X429330Y-197830D02*
Y-193180D01*
X416830D01*
Y-197830D01*
G01X411567Y2001323D02*
X412100Y2008462D01*
X408689Y2002168D01*
X411567Y2001323D01*
G01X447293Y-278223D02*
Y-282873D01*
X434793D01*
Y-278223D01*
G01X447293Y-197623D02*
Y-192973D01*
X434793D01*
Y-197623D01*
G01X447283Y1698268D02*
G02X434803I-6240J0D01*
G02X447283I6240J0D01*
G01X436453Y2003212D02*
X432980Y2009472D01*
X433583Y2002339D01*
X436453Y2003212D01*
G01X432980Y2009472D02*
X513100Y1746222D01*
G01X451650Y-514479D02*
Y-539479D01*
G01Y-489479D02*
Y-514479D01*
G01X441043Y1697268D02*
Y-183598D01*
G01X454819Y2006468D02*
X450480Y2012162D01*
X452104Y2005190D01*
X454819Y2006468D01*
G01X450480Y2012162D02*
X575040Y1747572D01*
G01X456663Y-541646D02*
X456770Y-541521D01*
X456850Y-541312D01*
X456903Y-541021D01*
X456850Y-540771D01*
X456743Y-540604D01*
X456557Y-540479D01*
X455837D01*
Y-542979D01*
X456717D01*
X456903Y-542812D01*
X457010Y-542562D01*
X457063Y-542271D01*
X457010Y-541979D01*
X456850Y-541729D01*
X456663Y-541646D01*
X455837D01*
G01X459130Y-542979D02*
Y-541312D01*
G01Y-541604D02*
X459023Y-541437D01*
X458863Y-541354D01*
X458677Y-541312D01*
X458490Y-541396D01*
X458330Y-541562D01*
X458223Y-541812D01*
X458170Y-542146D01*
X458223Y-542479D01*
X458330Y-542729D01*
X458490Y-542896D01*
X458677Y-542979D01*
X458863Y-542937D01*
X459023Y-542812D01*
X459130Y-542646D01*
G01X460450Y-542687D02*
X460583Y-542854D01*
X460770Y-542979D01*
X460930D01*
X461090Y-542896D01*
X461197Y-542771D01*
X461250Y-542604D01*
X461223Y-542354D01*
X461117Y-542229D01*
X460637Y-541979D01*
X460530Y-541687D01*
X460583Y-541479D01*
X460690Y-541354D01*
X460850Y-541312D01*
X461010Y-541354D01*
X461170Y-541479D01*
G01X462650Y-541854D02*
X463503D01*
X463423Y-541562D01*
X463290Y-541396D01*
X463103Y-541312D01*
X462917Y-541354D01*
X462757Y-541479D01*
X462650Y-541771D01*
X462597Y-542021D01*
Y-542271D01*
X462650Y-542521D01*
X462783Y-542771D01*
X462943Y-542937D01*
X463130Y-542979D01*
X463317Y-542896D01*
X463503Y-542646D01*
G01X464770Y-542979D02*
Y-540479D01*
G01Y-541729D02*
X464903Y-541479D01*
X465063Y-541354D01*
X465223Y-541312D01*
X465463Y-541396D01*
X465623Y-541562D01*
X465730Y-541854D01*
Y-542187D01*
X465677Y-542521D01*
X465570Y-542771D01*
X465383Y-542937D01*
X465223Y-542979D01*
X465063Y-542937D01*
X464903Y-542812D01*
X464770Y-542604D01*
G01X467450Y-542979D02*
X467290Y-542937D01*
X467130Y-542771D01*
X467023Y-542479D01*
X466970Y-542146D01*
X467023Y-541812D01*
X467130Y-541521D01*
X467290Y-541354D01*
X467450Y-541312D01*
X467610Y-541354D01*
X467770Y-541521D01*
X467877Y-541812D01*
X467903Y-542146D01*
X467877Y-542479D01*
X467770Y-542771D01*
X467610Y-542937D01*
X467450Y-542979D01*
G01X470130D02*
Y-541312D01*
G01Y-541604D02*
X470023Y-541437D01*
X469863Y-541354D01*
X469677Y-541312D01*
X469490Y-541396D01*
X469330Y-541562D01*
X469223Y-541812D01*
X469170Y-542146D01*
X469223Y-542479D01*
X469330Y-542729D01*
X469490Y-542896D01*
X469677Y-542979D01*
X469863Y-542937D01*
X470023Y-542812D01*
X470130Y-542646D01*
G01X471477Y-542979D02*
Y-541312D01*
G01Y-541646D02*
X471610Y-541479D01*
X471743Y-541354D01*
X471930Y-541312D01*
X472063Y-541354D01*
X472223Y-541479D01*
G01X474530Y-540479D02*
Y-542979D01*
G01Y-542604D02*
X474423Y-542812D01*
X474263Y-542937D01*
X474077Y-542979D01*
X473863Y-542896D01*
X473703Y-542687D01*
X473597Y-542437D01*
X473570Y-542146D01*
X473597Y-541854D01*
X473703Y-541604D01*
X473863Y-541396D01*
X474077Y-541312D01*
X474263Y-541354D01*
X474397Y-541437D01*
X474530Y-541604D01*
G01X477917Y-542979D02*
Y-540479D01*
X478583D01*
X478797Y-540604D01*
X478930Y-540771D01*
X478983Y-541104D01*
X478930Y-541437D01*
X478770Y-541646D01*
X478583Y-541771D01*
X477917D01*
G01X478583D02*
X478983Y-542979D01*
G01X480250Y-541854D02*
X481103D01*
X481023Y-541562D01*
X480890Y-541396D01*
X480703Y-541312D01*
X480517Y-541354D01*
X480357Y-541479D01*
X480250Y-541771D01*
X480197Y-542021D01*
Y-542271D01*
X480250Y-542521D01*
X480383Y-542771D01*
X480543Y-542937D01*
X480730Y-542979D01*
X480917Y-542896D01*
X481103Y-542646D01*
G01X482370Y-541312D02*
X482850Y-542979D01*
X483330Y-541312D01*
G01X485050Y-543062D02*
X484997Y-543021D01*
Y-542937D01*
X485050Y-542896D01*
X485103Y-542937D01*
Y-543021D01*
X485050Y-543062D01*
G01X487250Y-542979D02*
X487437Y-542937D01*
X487650Y-542812D01*
X487783Y-542604D01*
X487837Y-542312D01*
X487783Y-542021D01*
X487623Y-541771D01*
X487383Y-541646D01*
X487117D01*
X486957Y-541562D01*
X486823Y-541354D01*
X486770Y-541062D01*
X486850Y-540771D01*
X487037Y-540562D01*
X487250Y-540479D01*
X487463Y-540562D01*
X487650Y-540771D01*
X487730Y-541062D01*
X487677Y-541354D01*
X487543Y-541562D01*
X487383Y-541646D01*
X487117D01*
X486877Y-541771D01*
X486717Y-542021D01*
X486663Y-542312D01*
X486717Y-542604D01*
X486850Y-542812D01*
X487063Y-542937D01*
X487250Y-542979D01*
G01X489663Y-541646D02*
X489770Y-541521D01*
X489850Y-541312D01*
X489903Y-541021D01*
X489850Y-540771D01*
X489743Y-540604D01*
X489557Y-540479D01*
X488837D01*
Y-542979D01*
X489717D01*
X489903Y-542812D01*
X490010Y-542562D01*
X490063Y-542271D01*
X490010Y-541979D01*
X489850Y-541729D01*
X489663Y-541646D01*
X488837D01*
G01X455550Y-516979D02*
Y-521979D01*
G01X454093Y-516979D02*
X457007D01*
G01X460650Y-521979D02*
X460270Y-521896D01*
X459890Y-521562D01*
X459637Y-520979D01*
X459510Y-520312D01*
X459637Y-519646D01*
X459890Y-519062D01*
X460270Y-518729D01*
X460650Y-518646D01*
X461030Y-518729D01*
X461410Y-519062D01*
X461663Y-519646D01*
X461727Y-520312D01*
X461663Y-520979D01*
X461410Y-521562D01*
X461030Y-521896D01*
X460650Y-521979D01*
G01X465750D02*
X465370Y-521896D01*
X464990Y-521562D01*
X464737Y-520979D01*
X464610Y-520312D01*
X464737Y-519646D01*
X464990Y-519062D01*
X465370Y-518729D01*
X465750Y-518646D01*
X466130Y-518729D01*
X466510Y-519062D01*
X466763Y-519646D01*
X466827Y-520312D01*
X466763Y-520979D01*
X466510Y-521562D01*
X466130Y-521896D01*
X465750Y-521979D01*
G01X470850D02*
Y-516979D01*
G01X475950Y-522146D02*
X475823Y-522062D01*
Y-521896D01*
X475950Y-521812D01*
X476077Y-521896D01*
Y-522062D01*
X475950Y-522146D01*
G01Y-519896D02*
X475823Y-519812D01*
Y-519646D01*
X475950Y-519562D01*
X476077Y-519646D01*
Y-519812D01*
X475950Y-519896D01*
G01X454283Y-496979D02*
Y-491979D01*
X455867D01*
X456373Y-492229D01*
X456690Y-492562D01*
X456817Y-493229D01*
X456690Y-493896D01*
X456310Y-494312D01*
X455867Y-494562D01*
X454283D01*
G01X455867D02*
X456817Y-496979D01*
G01X461917D02*
X459383D01*
Y-491979D01*
X461917D01*
G01X460903Y-494396D02*
X459383D01*
G01X464167Y-491979D02*
X465750Y-496979D01*
X467333Y-491979D01*
G01X470850Y-497146D02*
X470723Y-497062D01*
Y-496896D01*
X470850Y-496812D01*
X470977Y-496896D01*
Y-497062D01*
X470850Y-497146D01*
G01Y-494896D02*
X470723Y-494812D01*
Y-494646D01*
X470850Y-494562D01*
X470977Y-494646D01*
Y-494812D01*
X470850Y-494896D01*
G01X553929Y1668212D02*
X490879D01*
Y1736912D01*
X553929D01*
Y1668212D01*
G01X520906Y-278223D02*
Y-282873D01*
X508406D01*
Y-278223D01*
G01X520906Y-197623D02*
Y-192973D01*
X508406D01*
Y-197623D01*
G01X525276Y1170318D02*
Y-161701D01*
X513858D01*
X513996Y-183598D01*
G01X537490Y-278223D02*
Y-282873D01*
X524990D01*
Y-278223D01*
G01X537490Y-197623D02*
Y-192973D01*
X524990D01*
Y-197623D01*
G01X531240Y810121D02*
Y-183598D01*
G01X524488Y811122D02*
G02X537992I6752J0D01*
G02X524488I-6752J0D01*
G01X518523Y1171319D02*
G02X532027I6752J0D01*
G02X518523I-6752J0D01*
G01X532077Y1175353D02*
X539764Y1183524D01*
G01X531177Y1395413D02*
G02X543775I6299J0D01*
G02X531177I-6299J0D01*
G01X555891Y-278223D02*
Y-282873D01*
X543391D01*
Y-278223D01*
G01X555891Y-197623D02*
Y-192973D01*
X543391D01*
Y-197623D01*
G01X537477Y1394413D02*
Y-161702D01*
X549412D01*
X549452Y-183598D01*
G01X536966Y816584D02*
X544653Y824755D01*
G01X542672Y821214D02*
X541239Y822562D01*
G01D02*
X544653Y824755D01*
G01D02*
X542672Y821214D01*
G01X537783Y1179983D02*
X536350Y1181331D01*
G01D02*
X539764Y1183524D01*
G01D02*
X537783Y1179983D01*
G01X620858Y1668212D02*
X557808D01*
Y1736912D01*
X620858D01*
Y1668212D01*
G01X567250Y3397092D02*
Y3409592D01*
X561515Y3400634D01*
X569265D01*
G01X573760Y3397092D02*
Y3409592D01*
X577790Y3399175D01*
X581820Y3409592D01*
Y3397092D01*
G01X586160D02*
Y3409592D01*
X590190Y3399175D01*
X594220Y3409592D01*
Y3397092D01*
G01X580817Y-278220D02*
Y-282870D01*
X568317D01*
Y-278220D01*
G01X580817Y-197620D02*
Y-192970D01*
X568317D01*
Y-197620D01*
G01X574567Y990220D02*
Y-183595D01*
G01X567814Y991220D02*
G02X581318I6752J0D01*
G02X567814I-6752J0D01*
G01X579462Y999712D02*
X587149Y1007883D01*
G01X604152Y3390718D02*
X572656D01*
G01D02*
X612026D01*
G01X585168Y1004342D02*
X583735Y1005690D01*
G01D02*
X587149Y1007883D01*
G01D02*
X585168Y1004342D01*
G01X604152Y3315914D02*
X619900Y3323788D01*
G01X655333Y3335599D02*
X612026D01*
G01X655333Y3331662D02*
X612026D01*
G01X619900Y3323788D02*
X604152Y3331662D01*
G01Y3335599D02*
X619900Y3343474D01*
G01X604152Y3355285D02*
Y3398592D01*
G01X619900Y3343474D02*
X604152Y3351348D01*
G01X651396Y3390718D02*
X612026D01*
G01X619900Y3347410D02*
Y3398592D01*
G01Y3347410D02*
Y3426151D01*
G01Y3390718D02*
X651396D01*
G01X635952Y3292485D02*
Y3335792D01*
G01X667273Y-266421D02*
Y-271071D01*
X654773D01*
Y-266421D01*
G01X667273Y-198221D02*
Y-193571D01*
X654773D01*
Y-198221D01*
G01X661023Y630890D02*
Y-184196D01*
G01X650000Y631890D02*
G02X672047I11023J0D01*
G02X650000I-11024J0D01*
G01X659890Y3297892D02*
X647390D01*
X649890Y3296032D01*
G01X659890D02*
Y3299752D01*
G01Y3306262D02*
X647390D01*
X657807Y3310292D01*
X647390Y3314322D01*
X659890D01*
G01Y3318662D02*
X647390D01*
X657807Y3322692D01*
X647390Y3326722D01*
X659890D01*
G01X687142Y-278680D02*
Y-283330D01*
X674642D01*
Y-278680D01*
G01X687142Y-198080D02*
Y-193430D01*
X674642D01*
Y-198080D01*
G01X679890Y3333692D02*
X681890D01*
Y3331292D01*
X681290Y3330492D01*
X680590Y3329959D01*
X679590Y3329692D01*
X678590Y3329959D01*
X677890Y3330492D01*
X677290Y3331292D01*
X676890Y3332225D01*
X676690Y3333292D01*
Y3334225D01*
X676890Y3335025D01*
X677290Y3335959D01*
X677890Y3336759D01*
X678490Y3337292D01*
X679290Y3337692D01*
X679990D01*
X680790Y3337425D01*
X681390Y3336892D01*
G01X685290Y3329692D02*
Y3337692D01*
X687790D01*
X688590Y3337292D01*
X689090Y3336759D01*
X689290Y3335692D01*
X689090Y3334625D01*
X688490Y3333959D01*
X687790Y3333559D01*
X685290D01*
G01X687790D02*
X689290Y3329692D01*
G01X695290D02*
X694490Y3329825D01*
X693790Y3330359D01*
X693190Y3331159D01*
X692790Y3332092D01*
X692590Y3333159D01*
Y3334225D01*
X692790Y3335292D01*
X693190Y3336225D01*
X693790Y3337025D01*
X694490Y3337559D01*
X695290Y3337692D01*
X696090Y3337559D01*
X696790Y3337025D01*
X697390Y3336225D01*
X697790Y3335292D01*
X697990Y3334225D01*
Y3333159D01*
X697790Y3332092D01*
X697390Y3331159D01*
X696790Y3330359D01*
X696090Y3329825D01*
X695290Y3329692D01*
G01X701090Y3337692D02*
Y3331959D01*
X701490Y3330758D01*
X702290Y3329959D01*
X703290Y3329692D01*
X704290Y3329959D01*
X705090Y3330758D01*
X705490Y3331959D01*
Y3337692D01*
G01X709290Y3329692D02*
Y3337692D01*
X711690D01*
X712490Y3337292D01*
X713090Y3336359D01*
X713290Y3335292D01*
X713090Y3334225D01*
X712590Y3333425D01*
X711690Y3333025D01*
X709290D01*
G01X717190Y3330758D02*
X717990Y3330092D01*
X718890Y3329692D01*
X719690D01*
X720490Y3330092D01*
X721090Y3330758D01*
X721390Y3331692D01*
X721190Y3332625D01*
X720690Y3333425D01*
X719790Y3333959D01*
X718590Y3334225D01*
X717890Y3334759D01*
X717590Y3335692D01*
X717790Y3336625D01*
X718290Y3337292D01*
X718990Y3337692D01*
X719690D01*
X720390Y3337425D01*
X720990Y3336759D01*
G01X732790Y3329692D02*
X735290Y3337692D01*
X737790Y3329692D01*
G01X736890Y3332492D02*
X733690D01*
G01X702692Y-278451D02*
Y-283101D01*
X690192D01*
Y-278451D01*
G01X702692Y-197851D02*
Y-193201D01*
X690192D01*
Y-197851D01*
G01X704091Y1656953D02*
Y-162160D01*
X679977Y-161703D01*
X680138Y-184055D01*
G01X723870Y294362D02*
Y260110D01*
G02X684500I-19685J0D01*
G01Y294362D01*
G02X723870I19685J0D01*
G01X723156Y-278336D02*
Y-282986D01*
X710656D01*
Y-278336D01*
G01X723156Y-197736D02*
Y-193086D01*
X710656D01*
Y-197736D01*
G01X704185Y276236D02*
Y-172907D01*
X695984D01*
X696027Y-183826D01*
G01X707677Y1713961D02*
Y-172907D01*
X716678Y-172793D01*
X716700Y-183711D01*
G01X696654Y1714961D02*
G02X718701I11023J0D01*
G02X696654I-11024J0D01*
G01X713983Y311226D02*
X721670Y319397D01*
G01X719689Y315856D02*
X718256Y317204D01*
G01D02*
X721670Y319397D01*
G01D02*
X719689Y315856D01*
G01X743917Y605413D02*
G02X783287I19685J0D01*
G02X743917I-19685J0D01*
G01X769851Y-278221D02*
Y-282871D01*
X757351D01*
Y-278221D01*
G01X769851Y-197621D02*
Y-192971D01*
X757351D01*
Y-197621D01*
G01X763601Y604413D02*
Y-183596D01*
G01X768402Y628567D02*
X776089Y636738D01*
G01X774108Y633197D02*
X772675Y634545D01*
G01D02*
X776089Y636738D01*
G01D02*
X774108Y633197D01*
G01X791205Y-265451D02*
Y-270101D01*
X778705D01*
Y-265451D01*
G01X791205Y-197251D02*
Y-192601D01*
X778705D01*
Y-197251D01*
G01X800787Y86795D02*
Y-172818D01*
X785261Y-173124D01*
X785232Y-183226D01*
G01X789764Y87795D02*
G02X811811I11023J0D01*
G02X789764I-11023J0D01*
G01X811940Y-278192D02*
Y-282842D01*
X799440D01*
Y-278192D01*
G01X811940Y-197592D02*
Y-192942D01*
X799440D01*
Y-197592D01*
G01X805690Y1597425D02*
Y-183567D01*
G01X794864Y204724D02*
G02X816517I10827J0D01*
G02X794864I-10826J0D01*
G01X813680Y1719690D02*
Y1679290D01*
X1043280D01*
Y1719690D01*
X813680D01*
G01X849316Y-278191D02*
Y-282841D01*
X836816D01*
Y-278191D01*
G01X849316Y-197591D02*
Y-192941D01*
X836816D01*
Y-197591D01*
G01X833366Y1420331D02*
G02X849114I7874J0D01*
G02X833366I-7874J0D01*
G01X843066Y1419330D02*
Y-183566D01*
G01X854790Y1761368D02*
X850140D01*
Y1773868D01*
X854790D01*
G01X896260Y175197D02*
G02X904134I3937J0D01*
G02X896260I-3937J0D01*
G01X898860Y1472208D02*
X957915D01*
Y1440712D01*
X898860D01*
Y1472208D01*
G01X936673Y311614D02*
X920807D01*
G02X936673I7933J10039D01*
G01X923051Y334234D02*
X919818Y344977D01*
G01X921895Y341491D02*
X920011Y340924D01*
G01D02*
X919818Y344977D01*
G01D02*
X921895Y341491D01*
G01X920669Y757874D02*
G02X942717I11024J0D01*
G02X920669I-11024J0D01*
G01Y1072835D02*
G02X942717I11024J0D01*
G02X920669I-11024J0D01*
G01Y1387795D02*
G02X942717I11024J0D01*
G02X920669I-11024J0D01*
G01X922990Y1761368D02*
X927640D01*
Y1773868D01*
X922990D01*
G01X937942Y-278192D02*
Y-282842D01*
X925442D01*
Y-278192D01*
G01X937942Y-197592D02*
Y-192942D01*
X925442D01*
Y-197592D01*
G01X931692Y1386795D02*
Y-183567D01*
G01X940748Y155217D02*
G02X948622I3937J0D01*
G02X940748I-3937J0D01*
G01X945330Y1719380D02*
X1011750Y2045930D01*
X1009060Y2040540D01*
X1011750Y2039900D01*
X1011830Y2045850D01*
G01X946465Y1780118D02*
X1857480D01*
G01X1020738Y-278196D02*
Y-282846D01*
X1008238D01*
Y-278196D01*
G01X1020738Y-197596D02*
Y-192946D01*
X1008238D01*
Y-197596D01*
G01X1014488Y1419331D02*
Y-183571D01*
G01X1008366Y1420331D02*
G02X1024114I7874J0D01*
G02X1008366I-7874J0D01*
G01X1044038Y-277985D02*
Y-282635D01*
X1031538D01*
Y-277985D01*
G01X1044038Y-197385D02*
Y-192735D01*
X1031538D01*
Y-197385D01*
G01X1045865Y86795D02*
Y-161812D01*
X1037176Y-162424D01*
X1037273Y-183360D01*
G01X1034843Y87795D02*
G02X1056890I11024J0D01*
G02X1034843I-11023J0D01*
G01X1063908Y-278195D02*
Y-282845D01*
X1051408D01*
Y-278195D01*
G01X1063908Y-197595D02*
Y-192945D01*
X1051408D01*
Y-197595D01*
G01X1046832Y204724D02*
G02X1068486I10827J0D01*
G02X1046832I-10827J0D01*
G01X1057658Y1597425D02*
Y-183570D01*
G01X1074390Y605378D02*
G02X1113760I19685J0D01*
G02X1074390I-19685J0D01*
G01X1100324Y-278194D02*
Y-282844D01*
X1087824D01*
Y-278194D01*
G01X1100324Y-197594D02*
Y-192944D01*
X1087824D01*
Y-197594D01*
G01X1094074Y604380D02*
Y-183569D01*
G01X1096748Y626732D02*
X1104435Y634903D01*
G01X1102454Y631362D02*
X1101021Y632710D01*
G01D02*
X1104435Y634903D01*
G01D02*
X1102454Y631362D01*
G01X1143318Y-278197D02*
Y-282847D01*
X1130818D01*
Y-278197D01*
G01X1143318Y-197597D02*
Y-192947D01*
X1130818D01*
Y-197597D01*
G01X1173240Y294335D02*
Y260083D01*
G02X1133870I-19685J0D01*
G01Y294335D01*
G02X1173240I19685J0D01*
G01X1125512Y1653543D02*
G02X1142047I8267J0D01*
G02X1125512I-8268J0D01*
G01X1159805Y-241076D02*
Y-245726D01*
X1147305D01*
Y-241076D01*
G01X1159805Y-197676D02*
Y-193026D01*
X1147305D01*
Y-197676D01*
G01X1153453Y1656953D02*
Y-161701D01*
X1136840Y-161703D01*
X1136878Y-183572D01*
G01X1144685Y1714961D02*
G02X1166732I11023J0D01*
G02X1144685I-11024J0D01*
G01X1178761Y-278653D02*
Y-283303D01*
X1166261D01*
Y-278653D01*
G01X1178761Y-198053D02*
Y-193403D01*
X1166261D01*
Y-198053D01*
G01X1153555Y276208D02*
Y-183651D01*
G01X1155708Y1713961D02*
Y-161702D01*
X1172344D01*
X1172372Y-184028D01*
G01X1165842Y313060D02*
X1173529Y321231D01*
G01X1171548Y317690D02*
X1170115Y319038D01*
G01D02*
X1173529Y321231D01*
G01D02*
X1171548Y317690D01*
G01X1189386Y1677188D02*
X1188510Y1678950D01*
G01X1253888Y-265977D02*
Y-270627D01*
X1241388D01*
Y-265977D01*
G01X1253888Y-197777D02*
Y-193127D01*
X1241388D01*
Y-197777D01*
G01X1247638Y268488D02*
Y-183752D01*
G01X1241535Y269488D02*
G02X1253740I6103J0D01*
G02X1241535I-6102J0D01*
G01X1297630Y1668212D02*
X1234580D01*
Y1736912D01*
X1297630D01*
Y1668212D01*
G01X1269770Y-265822D02*
Y-270472D01*
X1257270D01*
Y-265822D01*
G01X1269770Y-197622D02*
Y-192972D01*
X1257270D01*
Y-197622D01*
G01X1271260Y630890D02*
Y-162159D01*
X1262148Y-161701D01*
X1262386Y-183597D01*
G01X1260236Y631890D02*
G02X1282283I11023J0D01*
G02X1260236I-11023J0D01*
G01X1289164Y-278196D02*
Y-282846D01*
X1276664D01*
Y-278196D01*
G01X1289164Y-197596D02*
Y-192946D01*
X1276664D01*
Y-197596D01*
G01X1276161Y991220D02*
G02X1289665I6752J0D01*
G02X1276161I-6752J0D01*
G01X1398120Y2010822D02*
X1280300Y1746222D01*
G01X1304892Y-278195D02*
Y-282845D01*
X1292392D01*
Y-278195D01*
G01X1304892Y-197595D02*
Y-192945D01*
X1292392D01*
Y-197595D01*
G01X1282914Y990220D02*
Y-183571D01*
G01X1284918Y998183D02*
X1292605Y1006354D01*
G01X1290624Y1002813D02*
X1289191Y1004161D01*
G01D02*
X1292605Y1006354D01*
G01D02*
X1290624Y1002813D01*
G01X1292342Y1391831D02*
G02X1304940I6299J0D01*
G02X1292342I-6299J0D01*
G01X1321674Y-278196D02*
Y-282846D01*
X1309174D01*
Y-278196D01*
G01X1321674Y-197596D02*
Y-192946D01*
X1309174D01*
Y-197596D01*
G01X1298642Y1390830D02*
Y-183570D01*
G01X1364559Y1668212D02*
X1301509D01*
Y1736912D01*
X1364559D01*
Y1668212D01*
G01X1338455Y-278167D02*
Y-282817D01*
X1325955D01*
Y-278167D01*
G01X1338455Y-197567D02*
Y-192917D01*
X1325955D01*
Y-197567D01*
G01X1326240Y810121D02*
Y-161700D01*
X1315880Y-161702D01*
X1315805Y-183571D01*
G01X1319488Y811122D02*
G02X1332992I6752J0D01*
G02X1319488I-6752J0D01*
G01X1325452Y1171319D02*
G02X1338956I6752J0D01*
G02X1325452I-6752J0D01*
G01X1332205Y1170318D02*
Y-183542D01*
G01X1332764Y814291D02*
X1340451Y822462D01*
G01X1338470Y818921D02*
X1337037Y820269D01*
G01X1340451Y822462D02*
X1338470Y818921D01*
G01X1337037Y820269D02*
X1340451Y822462D01*
G01X1335821Y1178254D02*
X1343508Y1186425D01*
G01X1341527Y1182884D02*
X1340094Y1184232D01*
G01D02*
X1343508Y1186425D01*
G01D02*
X1341527Y1182884D01*
G01X1410910Y2007452D02*
X1350320Y1749592D01*
G01X1400818Y-266283D02*
Y-270933D01*
X1388318D01*
Y-266283D01*
G01X1400818Y-198083D02*
Y-193433D01*
X1388318D01*
Y-198083D01*
G01X1405118Y111008D02*
Y-161811D01*
X1394262Y-162117D01*
X1394315Y-184058D01*
G01X1392521Y119069D02*
X1390441Y122553D01*
G01X1393915Y120457D02*
X1392521Y119069D01*
G01X1398355Y114603D02*
X1390441Y122553D01*
G01D02*
X1393915Y120457D01*
G01X1396643Y2003817D02*
X1398120Y2010822D01*
X1393902Y2005037D01*
X1396643Y2003817D01*
G01X1422686Y-278197D02*
Y-282847D01*
X1410186D01*
Y-278197D01*
G01X1422686Y-197597D02*
Y-192947D01*
X1410186D01*
Y-197597D01*
G01X1399016Y112008D02*
G02X1411220I6102J0D01*
G02X1399016I-6102J0D01*
G01X1422677Y1698268D02*
G02X1410197I-6240J0D01*
G02X1422677I6240J0D01*
G01X1410769Y2000294D02*
X1410910Y2007452D01*
X1407849Y2000981D01*
X1410769Y2000294D01*
G01X1416436Y1697267D02*
Y-183572D01*
G01X1443988Y2002528D02*
X1440540Y2008802D01*
X1441115Y2001666D01*
X1443988Y2002528D01*
G01X1440540Y2008802D02*
X1519310Y1746222D01*
G01X1468055Y-265822D02*
Y-270472D01*
X1455555D01*
Y-265822D01*
G01X1468055Y-197622D02*
Y-192972D01*
X1455555D01*
Y-197622D01*
G01X1450782Y1714961D02*
G02X1472829I11023J0D01*
G02X1450782I-11024J0D01*
G01X1462320Y2008443D02*
X1458040Y2014182D01*
X1459592Y2007193D01*
X1462320Y2008443D01*
G01X1458040Y2014182D02*
X1579900Y1748242D01*
G01X1485274Y-265977D02*
Y-270627D01*
X1472774D01*
Y-265977D01*
G01X1485274Y-197777D02*
Y-193127D01*
X1472774D01*
Y-197777D01*
G01X1461805Y1713961D02*
Y-183597D01*
G01X1503805Y-278197D02*
Y-282847D01*
X1491305D01*
Y-278197D01*
G01X1503805Y-197597D02*
Y-192947D01*
X1491305D01*
Y-197597D01*
G01X1499606Y86795D02*
Y-168921D01*
X1479330Y-168462D01*
X1479291Y-183752D01*
G01X1488583Y87795D02*
G02X1510630I11024J0D01*
G02X1488583I-11023J0D01*
G01X1519809Y-278196D02*
Y-282846D01*
X1507309D01*
Y-278196D01*
G01X1519809Y-197596D02*
Y-192946D01*
X1507309D01*
Y-197596D01*
G01X1501418Y1170318D02*
Y-171306D01*
X1496753D01*
X1496833Y-183572D01*
G01X1507382Y810121D02*
Y-171305D01*
X1510300Y-171363D01*
X1510624Y-183571D01*
G01X1500629Y811122D02*
G02X1514133I6752J0D01*
G02X1500629I-6752J0D01*
G01X1494665Y1171319D02*
G02X1508169I6752J0D01*
G02X1494665I-6752J0D01*
G01X1503969Y1178560D02*
X1511656Y1186731D01*
G01X1509675Y1183190D02*
X1508242Y1184538D01*
G01D02*
X1511656Y1186731D01*
G01X1507318Y1395413D02*
G02X1519917I6299J0D01*
G02X1507318I-6300J0D01*
G01X1561803Y1668212D02*
X1498753D01*
Y1736912D01*
X1561803D01*
Y1668212D01*
G01X1535928Y-278425D02*
Y-283075D01*
X1523428D01*
Y-278425D01*
G01X1535928Y-197825D02*
Y-193175D01*
X1523428D01*
Y-197825D01*
G01X1513618Y1394413D02*
Y-171419D01*
X1528939D01*
X1529013Y-183800D01*
G01X1512376Y815361D02*
X1520063Y823532D01*
G01X1518082Y819991D02*
X1516649Y821339D01*
G01D02*
X1520063Y823532D01*
G01D02*
X1518082Y819991D01*
G01X1511656Y1186731D02*
X1509675Y1183190D01*
G01X1556959Y-278196D02*
Y-282846D01*
X1544459D01*
Y-278196D01*
G01X1556959Y-197596D02*
Y-192946D01*
X1544459D01*
Y-197596D01*
G01X1550709Y990220D02*
Y-183571D01*
G01X1543956Y991220D02*
G02X1557460I6752J0D01*
G02X1543956I-6752J0D01*
G01X1556251Y996963D02*
X1563938Y1005134D01*
G01X1561957Y1001593D02*
X1560524Y1002941D01*
G01D02*
X1563938Y1005134D01*
G01D02*
X1561957Y1001593D01*
G01X1628732Y1668212D02*
X1565682D01*
Y1736912D01*
X1628732D01*
Y1668212D01*
G01X1700012Y294362D02*
Y260110D01*
G02X1660642I-19685J0D01*
G01Y294362D01*
G02X1700012I19685J0D01*
G01X1660547Y1644764D02*
Y1671142D01*
G02X1699917I19685J0D01*
G01Y1644764D01*
G02X1660547I-19685J0D01*
G01X1680327Y276236D02*
Y-171078D01*
X1698886D01*
X1698935Y-183599D01*
G01X1705595Y-265824D02*
Y-270474D01*
X1693095D01*
Y-265824D01*
G01X1705595Y-197624D02*
Y-192974D01*
X1693095D01*
Y-197624D01*
G01X1696578Y310002D02*
X1704265Y318173D01*
G01X1702284Y314632D02*
X1700851Y315980D01*
G01X1704265Y318173D02*
X1702284Y314632D01*
G01X1700851Y315980D02*
X1704265Y318173D01*
G01X1702815Y1663392D02*
X1719342Y1671611D01*
G01X1720059Y605413D02*
G02X1759429I19685J0D01*
G02X1720059I-19685J0D01*
G01X1719342Y1671611D02*
X1716255Y1668977D01*
G01X1715379Y1670739D02*
X1719342Y1671611D01*
G01X1716255Y1668977D02*
X1715379Y1670739D01*
G01X1745956Y-277968D02*
Y-282618D01*
X1733456D01*
Y-277968D01*
G01X1745956Y-197368D02*
Y-192718D01*
X1733456D01*
Y-197368D01*
G01X1739706Y604455D02*
Y-183343D01*
G01X1742436Y626119D02*
X1750123Y634290D01*
G01X1748142Y630749D02*
X1746709Y632097D01*
G01D02*
X1750123Y634290D01*
G01D02*
X1748142Y630749D01*
G01X1773179Y-265822D02*
Y-270472D01*
X1760679D01*
Y-265822D01*
G01X1773179Y-197622D02*
Y-192972D01*
X1760679D01*
Y-197622D01*
G01X1766929Y1713960D02*
Y-183597D01*
G01X1760827Y1714961D02*
G02X1773031I6102J0D01*
G02X1760827I-6102J0D01*
G01X1812549Y-265823D02*
Y-270473D01*
X1800049D01*
Y-265823D01*
G01X1812549Y-197623D02*
Y-192973D01*
X1800049D01*
Y-197623D01*
G01X1798425Y-17323D02*
X1857480D01*
Y-48819D01*
X1798425D01*
Y-17323D01*
G01X1799263Y-23873D02*
Y-20773D01*
X1800183D01*
X1800490Y-20928D01*
X1800720Y-21290D01*
X1800797Y-21703D01*
X1800720Y-22116D01*
X1800528Y-22426D01*
X1800183Y-22581D01*
X1799263D01*
G01X1803973Y-21031D02*
X1803743Y-20876D01*
X1803475Y-20773D01*
X1803168D01*
X1802823Y-20928D01*
X1802555Y-21186D01*
X1802363Y-21496D01*
X1802210Y-22013D01*
X1802172Y-22478D01*
X1802248Y-22943D01*
X1802363Y-23253D01*
X1802593Y-23563D01*
X1802862Y-23770D01*
X1803130Y-23873D01*
X1803398D01*
X1803667Y-23770D01*
X1803897Y-23615D01*
X1804088Y-23408D01*
G01X1806537Y-22220D02*
X1806690Y-22065D01*
X1806805Y-21806D01*
X1806882Y-21445D01*
X1806805Y-21135D01*
X1806652Y-20928D01*
X1806383Y-20773D01*
X1805348D01*
Y-23873D01*
X1806613D01*
X1806882Y-23666D01*
X1807035Y-23356D01*
X1807112Y-22995D01*
X1807035Y-22633D01*
X1806805Y-22323D01*
X1806537Y-22220D01*
X1805348D01*
G01X1811472Y-20773D02*
X1812430Y-23873D01*
X1813388Y-20773D01*
G01X1816297Y-23873D02*
X1814763D01*
Y-20773D01*
X1816297D01*
G01X1815683Y-22271D02*
X1814763D01*
G01X1817748Y-23873D02*
Y-20773D01*
X1819512Y-23873D01*
Y-20773D01*
G01X1820887Y-23873D02*
Y-20773D01*
X1821653D01*
X1821960Y-20928D01*
X1822190Y-21135D01*
X1822382Y-21445D01*
X1822535Y-21806D01*
X1822573Y-22323D01*
X1822535Y-22840D01*
X1822382Y-23201D01*
X1822190Y-23511D01*
X1821960Y-23718D01*
X1821653Y-23873D01*
X1820887D01*
G01X1824830D02*
X1824523Y-23821D01*
X1824255Y-23615D01*
X1824025Y-23305D01*
X1823872Y-22943D01*
X1823795Y-22530D01*
Y-22116D01*
X1823872Y-21703D01*
X1824025Y-21341D01*
X1824255Y-21031D01*
X1824523Y-20825D01*
X1824830Y-20773D01*
X1825137Y-20825D01*
X1825405Y-21031D01*
X1825635Y-21341D01*
X1825788Y-21703D01*
X1825865Y-22116D01*
Y-22530D01*
X1825788Y-22943D01*
X1825635Y-23305D01*
X1825405Y-23615D01*
X1825137Y-23821D01*
X1824830Y-23873D01*
G01X1827163D02*
Y-20773D01*
X1828122D01*
X1828428Y-20928D01*
X1828620Y-21135D01*
X1828697Y-21548D01*
X1828620Y-21961D01*
X1828390Y-22220D01*
X1828122Y-22375D01*
X1827163D01*
G01X1828122D02*
X1828697Y-23873D01*
G01X1799528Y1420331D02*
G02X1838898I19685J0D01*
G02X1799528I-19685J0D01*
G01X1795276Y1714961D02*
G02X1817323I11024J0D01*
G02X1795276I-11023J0D01*
G01X1806299Y1713961D02*
Y-183598D01*
G01X1816771Y1367897D02*
Y-154842D01*
X1833796D01*
X1833979Y-182429D01*
G01X1806563Y-25773D02*
Y-28873D01*
X1808097D01*
G01X1810430D02*
X1810123Y-28821D01*
X1809855Y-28615D01*
X1809625Y-28305D01*
X1809472Y-27943D01*
X1809395Y-27530D01*
Y-27116D01*
X1809472Y-26703D01*
X1809625Y-26341D01*
X1809855Y-26031D01*
X1810123Y-25825D01*
X1810430Y-25773D01*
X1810737Y-25825D01*
X1811005Y-26031D01*
X1811235Y-26341D01*
X1811388Y-26703D01*
X1811465Y-27116D01*
Y-27530D01*
X1811388Y-27943D01*
X1811235Y-28305D01*
X1811005Y-28615D01*
X1810737Y-28821D01*
X1810430Y-28873D01*
G01X1813760Y-27323D02*
X1814527D01*
Y-28253D01*
X1814297Y-28563D01*
X1814028Y-28770D01*
X1813645Y-28873D01*
X1813262Y-28770D01*
X1812993Y-28563D01*
X1812763Y-28253D01*
X1812610Y-27891D01*
X1812533Y-27478D01*
Y-27116D01*
X1812610Y-26806D01*
X1812763Y-26445D01*
X1812993Y-26135D01*
X1813223Y-25928D01*
X1813530Y-25773D01*
X1813798D01*
X1814105Y-25876D01*
X1814335Y-26083D01*
G01X1816630Y-28873D02*
X1816323Y-28821D01*
X1816055Y-28615D01*
X1815825Y-28305D01*
X1815672Y-27943D01*
X1815595Y-27530D01*
Y-27116D01*
X1815672Y-26703D01*
X1815825Y-26341D01*
X1816055Y-26031D01*
X1816323Y-25825D01*
X1816630Y-25773D01*
X1816937Y-25825D01*
X1817205Y-26031D01*
X1817435Y-26341D01*
X1817588Y-26703D01*
X1817665Y-27116D01*
Y-27530D01*
X1817588Y-27943D01*
X1817435Y-28305D01*
X1817205Y-28615D01*
X1816937Y-28821D01*
X1816630Y-28873D01*
G01X1805748Y631890D02*
G02X1827795I11024J0D01*
G02X1805748I-11023J0D01*
G01Y1368898D02*
G02X1827795I11024J0D01*
G02X1805748I-11023J0D01*
G01X1815046Y1440259D02*
X1822733Y1448430D01*
G01X1840961Y-277054D02*
Y-281704D01*
X1828461D01*
Y-277054D01*
G01X1840961Y-196454D02*
Y-191804D01*
X1828461D01*
Y-196454D01*
G01X1819208Y1419330D02*
Y-126261D01*
X1860549Y-126489D01*
X1860626Y-182428D01*
G01X1818898Y87795D02*
G02X1840945I11023J0D01*
G02X1818898I-11023J0D01*
G01X1835827Y133465D02*
Y127165D01*
G02X1823622I-6103J0D01*
G01Y133465D01*
G02X1835827I6102J0D01*
G01X1820752Y1444889D02*
X1819319Y1446237D01*
G01D02*
X1822733Y1448430D01*
G01D02*
X1820752Y1444889D01*
G01X1841067Y124745D02*
X1842619Y125953D01*
G01X1837371Y131095D02*
X1844260Y122242D01*
G01X1842619Y125953D02*
X1844260Y122242D01*
G01D02*
X1841067Y124745D01*
G01X1850480Y1778618D02*
X1857480Y1780118D01*
X1850480Y1781618D01*
Y1778618D01*
G01X1867029Y-277053D02*
Y-281703D01*
X1854529D01*
Y-277053D01*
G01X1867029Y-196453D02*
Y-191803D01*
X1854529D01*
Y-196453D01*
G01X1857480Y1750118D02*
Y1790118D01*
G01X1867480Y0D02*
X1946760D01*
G01X1867480Y1740118D02*
X1946760D01*
G01X1911233Y2878290D02*
Y2978290D01*
X2661433D01*
Y2878290D01*
X1911233D01*
G01Y2903290D02*
X2661433D01*
G01X1911233Y2928290D02*
X2661433D01*
G01X1911233Y2953290D02*
X2661433D01*
G01X1912480Y3094672D02*
Y3194672D01*
X2662680D01*
Y3094672D01*
X1912480D01*
G01Y3119672D02*
X2662680D01*
G01X1912480Y3144672D02*
X2662680D01*
G01X1912480Y3169672D02*
X2662680D01*
G01X1910550Y3337122D02*
Y3487122D01*
X2660750D01*
Y3337122D01*
X1910550D01*
G01Y3362122D02*
X2660750D01*
G01X1910550Y3387122D02*
X2660750D01*
G01X1910550Y3412122D02*
X2660750D01*
G01X1910550Y3437122D02*
X2660750D01*
G01X1910550Y3462122D02*
X2660750D01*
G01X1910000Y3626862D02*
Y3776862D01*
X2660200D01*
Y3626862D01*
X1910000D01*
G01Y3651862D02*
X2660200D01*
G01X1910000Y3676862D02*
X2660200D01*
G01X1910000Y3701862D02*
X2660200D01*
G01X1910000Y3726862D02*
X2660200D01*
G01X1910000Y3751862D02*
X2660200D01*
G01X1924080Y2637412D02*
Y2737412D01*
X2674280D01*
Y2637412D01*
X1924080D01*
G01Y2662412D02*
X2674280D01*
G01X1924080Y2687412D02*
X2674280D01*
G01X1924080Y2712412D02*
X2674280D01*
G01X1936760Y726135D02*
Y0D01*
G01X1935260Y7000D02*
X1936760Y0D01*
X1938260Y7000D01*
X1935260D01*
G01X1955510Y743710D02*
Y739060D01*
X1943010D01*
Y743710D01*
G01X1955510Y824310D02*
Y828960D01*
X1943010D01*
Y824310D01*
G01X1936760Y841585D02*
Y1740118D01*
G01X1938260Y1733118D02*
X1936760Y1740118D01*
X1935260Y1733118D01*
X1938260D01*
G01X2001133Y2928290D02*
Y2878290D01*
G01X2002380Y3144672D02*
Y3094672D01*
G01X2000450Y3437122D02*
Y3337122D01*
G01X1999900Y3726862D02*
Y3626862D01*
G01X2013980Y2687412D02*
Y2637412D01*
G01X2042519Y-17323D02*
X2101574D01*
Y-48819D01*
X2042519D01*
Y-17323D01*
G01X2043357Y-23873D02*
Y-20773D01*
X2044277D01*
X2044584Y-20928D01*
X2044814Y-21290D01*
X2044891Y-21703D01*
X2044814Y-22116D01*
X2044622Y-22426D01*
X2044277Y-22581D01*
X2043357D01*
G01X2048067Y-21031D02*
X2047837Y-20876D01*
X2047569Y-20773D01*
X2047262D01*
X2046917Y-20928D01*
X2046649Y-21186D01*
X2046457Y-21496D01*
X2046304Y-22013D01*
X2046266Y-22478D01*
X2046342Y-22943D01*
X2046457Y-23253D01*
X2046687Y-23563D01*
X2046956Y-23770D01*
X2047224Y-23873D01*
X2047492D01*
X2047761Y-23770D01*
X2047991Y-23615D01*
X2048182Y-23408D01*
G01X2050631Y-22220D02*
X2050784Y-22065D01*
X2050899Y-21806D01*
X2050976Y-21445D01*
X2050899Y-21135D01*
X2050746Y-20928D01*
X2050477Y-20773D01*
X2049442D01*
Y-23873D01*
X2050707D01*
X2050976Y-23666D01*
X2051129Y-23356D01*
X2051206Y-22995D01*
X2051129Y-22633D01*
X2050899Y-22323D01*
X2050631Y-22220D01*
X2049442D01*
G01X2055566Y-20773D02*
X2056524Y-23873D01*
X2057482Y-20773D01*
G01X2060391Y-23873D02*
X2058857D01*
Y-20773D01*
X2060391D01*
G01X2059777Y-22271D02*
X2058857D01*
G01X2061842Y-23873D02*
Y-20773D01*
X2063606Y-23873D01*
Y-20773D01*
G01X2064981Y-23873D02*
Y-20773D01*
X2065747D01*
X2066054Y-20928D01*
X2066284Y-21135D01*
X2066476Y-21445D01*
X2066629Y-21806D01*
X2066667Y-22323D01*
X2066629Y-22840D01*
X2066476Y-23201D01*
X2066284Y-23511D01*
X2066054Y-23718D01*
X2065747Y-23873D01*
X2064981D01*
G01X2068924D02*
X2068617Y-23821D01*
X2068349Y-23615D01*
X2068119Y-23305D01*
X2067966Y-22943D01*
X2067889Y-22530D01*
Y-22116D01*
X2067966Y-21703D01*
X2068119Y-21341D01*
X2068349Y-21031D01*
X2068617Y-20825D01*
X2068924Y-20773D01*
X2069231Y-20825D01*
X2069499Y-21031D01*
X2069729Y-21341D01*
X2069882Y-21703D01*
X2069959Y-22116D01*
Y-22530D01*
X2069882Y-22943D01*
X2069729Y-23305D01*
X2069499Y-23615D01*
X2069231Y-23821D01*
X2068924Y-23873D01*
G01X2071257D02*
Y-20773D01*
X2072216D01*
X2072522Y-20928D01*
X2072714Y-21135D01*
X2072791Y-21548D01*
X2072714Y-21961D01*
X2072484Y-22220D01*
X2072216Y-22375D01*
X2071257D01*
G01X2072216D02*
X2072791Y-23873D01*
G01X2050657Y-25773D02*
Y-28873D01*
X2052191D01*
G01X2054524D02*
X2054217Y-28821D01*
X2053949Y-28615D01*
X2053719Y-28305D01*
X2053566Y-27943D01*
X2053489Y-27530D01*
Y-27116D01*
X2053566Y-26703D01*
X2053719Y-26341D01*
X2053949Y-26031D01*
X2054217Y-25825D01*
X2054524Y-25773D01*
X2054831Y-25825D01*
X2055099Y-26031D01*
X2055329Y-26341D01*
X2055482Y-26703D01*
X2055559Y-27116D01*
Y-27530D01*
X2055482Y-27943D01*
X2055329Y-28305D01*
X2055099Y-28615D01*
X2054831Y-28821D01*
X2054524Y-28873D01*
G01X2057854Y-27323D02*
X2058621D01*
Y-28253D01*
X2058391Y-28563D01*
X2058122Y-28770D01*
X2057739Y-28873D01*
X2057356Y-28770D01*
X2057087Y-28563D01*
X2056857Y-28253D01*
X2056704Y-27891D01*
X2056627Y-27478D01*
Y-27116D01*
X2056704Y-26806D01*
X2056857Y-26445D01*
X2057087Y-26135D01*
X2057317Y-25928D01*
X2057624Y-25773D01*
X2057892D01*
X2058199Y-25876D01*
X2058429Y-26083D01*
G01X2060724Y-28873D02*
X2060417Y-28821D01*
X2060149Y-28615D01*
X2059919Y-28305D01*
X2059766Y-27943D01*
X2059689Y-27530D01*
Y-27116D01*
X2059766Y-26703D01*
X2059919Y-26341D01*
X2060149Y-26031D01*
X2060417Y-25825D01*
X2060724Y-25773D01*
X2061031Y-25825D01*
X2061299Y-26031D01*
X2061529Y-26341D01*
X2061682Y-26703D01*
X2061759Y-27116D01*
Y-27530D01*
X2061682Y-27943D01*
X2061529Y-28305D01*
X2061299Y-28615D01*
X2061031Y-28821D01*
X2060724Y-28873D01*
G01X2082322Y1679828D02*
Y1620773D01*
X2050826D01*
Y1679828D01*
X2082322D01*
G01X2127000Y3726862D02*
Y3626862D01*
G01X2141080Y2687412D02*
Y2637412D01*
G01X2128233Y2928290D02*
Y2878290D01*
G01X2129480Y3144672D02*
Y3094672D01*
G01X2127550Y3437122D02*
Y3337122D01*
G01X2329733Y2928290D02*
Y2878290D01*
G01X2330980Y3144672D02*
Y3094672D01*
G01X2329050Y3437122D02*
Y3337122D01*
G01X2328500Y3726862D02*
Y3626862D01*
G01X2342580Y2687412D02*
Y2637412D01*
G01X2456833Y2928290D02*
Y2878290D01*
G01X2458080Y3144672D02*
Y3094672D01*
G01X2456150Y3437122D02*
Y3337122D01*
G01X2455600Y3726862D02*
Y3626862D01*
G01X2469680Y2687412D02*
Y2637412D01*
G01X2582700Y3726862D02*
Y3626862D01*
G01X2596780Y2687412D02*
Y2637412D01*
G01X2583933Y2928290D02*
Y2878290D01*
G01X2585180Y3144672D02*
Y3094672D01*
G01X2583250Y3437122D02*
Y3337122D01*
G01X2777371Y-220821D02*
Y2099979D01*
X3676371D01*
Y-220821D01*
X2777371D01*
G01Y-161721D02*
X3676371D01*
G01X2777371Y-102621D02*
X3676371D01*
G01X2777371Y-43521D02*
X3676371D01*
G01X2777371Y15579D02*
X3676371D01*
G01X2777371Y74679D02*
X3676371D01*
G01X2777371Y133779D02*
X3676371D01*
G01X2777371Y192879D02*
X3676371D01*
G01X2777371Y251979D02*
X3676371D01*
G01X2777371Y311079D02*
X3676371D01*
G01X2777371Y370179D02*
X3676371D01*
G01X2777371Y429279D02*
X3676371D01*
G01X2777371Y488379D02*
X3676371D01*
G01X2777371Y547479D02*
X3676371D01*
G01X2777371Y606579D02*
X3676371D01*
G01X2777371Y665679D02*
X3676371D01*
G01X2777371Y724779D02*
X3676371D01*
G01X2777371Y783879D02*
X3676371D01*
G01X2777371Y842979D02*
X3676371D01*
G01X2777371Y902079D02*
X3676371D01*
G01X2777371Y961179D02*
X3676371D01*
G01X2777371Y1020279D02*
X3676371D01*
G01X2777371Y1079379D02*
X3676371D01*
G01X2777371Y1138479D02*
X3676371D01*
G01X2777371Y1197579D02*
X3676371D01*
G01X2777371Y1256679D02*
X3676371D01*
G01X2777371Y1315779D02*
X3676371D01*
G01X2777371Y1374879D02*
X3676371D01*
G01X2777371Y1433979D02*
X3676371D01*
G01X2777371Y1493079D02*
X3676371D01*
G01X2777371Y1552179D02*
X3676371D01*
G01X2777371Y1611279D02*
X3676371D01*
G01X2777371Y1670379D02*
X3676371D01*
G01X2777371Y1729479D02*
X3676371D01*
G01X2777371Y1788579D02*
X3676371D01*
G01X2777371Y1847679D02*
X3676371D01*
G01X2777371Y1906779D02*
X3676371D01*
G01X2777371Y1965879D02*
X3676371D01*
G01X2777371Y2024979D02*
X3676371D01*
G01X2777371Y2049979D02*
X3676371D01*
G01X2777371Y2074979D02*
X3676371D01*
G01X2786880Y2604182D02*
Y2704182D01*
X3537080D01*
Y2604182D01*
X2786880D01*
G01Y2629182D02*
X3537080D01*
G01X2786880Y2654182D02*
X3537080D01*
G01X2786880Y2679182D02*
X3537080D01*
G01X2787876Y2868099D02*
Y2993099D01*
X3538076D01*
Y2868099D01*
X2787876D01*
G01Y2893099D02*
X3538076D01*
G01X2787876Y2918099D02*
X3538076D01*
G01X2787876Y2943099D02*
X3538076D01*
G01X2787876Y2968099D02*
X3538076D01*
G01X2787886Y3118669D02*
Y3243669D01*
X3538086D01*
Y3118669D01*
X2787886D01*
G01Y3143669D02*
X3538086D01*
G01X2787886Y3168669D02*
X3538086D01*
G01X2787886Y3193669D02*
X3538086D01*
G01X2787886Y3218669D02*
X3538086D01*
G01X2783540Y3374675D02*
Y3499675D01*
X3533740D01*
Y3374675D01*
X2783540D01*
G01Y3399675D02*
X3533740D01*
G01X2783540Y3424675D02*
X3533740D01*
G01X2783540Y3449675D02*
X3533740D01*
G01X2783540Y3474675D02*
X3533740D01*
G01X2788645Y3635137D02*
Y3785137D01*
X3538845D01*
Y3635137D01*
X2788645D01*
G01Y3660137D02*
X3538845D01*
G01X2788645Y3685137D02*
X3538845D01*
G01X2788645Y3710137D02*
X3538845D01*
G01X2788645Y3735137D02*
X3538845D01*
G01X2788645Y3760137D02*
X3538845D01*
G01X2867271Y2049979D02*
Y-220821D01*
G01X2873440Y3449675D02*
Y3374675D01*
G01X2876780Y2654182D02*
Y2604182D01*
G01X2877776Y2943099D02*
Y2868099D01*
G01X2877786Y3193669D02*
Y3118669D01*
G01X2878545Y3735137D02*
Y3635137D01*
G01X3003880Y2654182D02*
Y2604182D01*
G01X3004876Y2943099D02*
Y2868099D01*
G01X3004886Y3193669D02*
Y3118669D01*
G01X3000540Y3449675D02*
Y3374675D01*
G01X3005645Y3735137D02*
Y3635137D01*
G01X3068771Y2049979D02*
Y-220821D01*
G01X3205380Y2654182D02*
Y2604182D01*
G01X3206376Y2943099D02*
Y2868099D01*
G01X3206386Y3193669D02*
Y3118669D01*
G01X3202040Y3449675D02*
Y3374675D01*
G01X3207145Y3735137D02*
Y3635137D01*
G01X3270271Y2049979D02*
Y-220821D01*
G01X3329140Y3449675D02*
Y3374675D01*
G01X3332480Y2654182D02*
Y2604182D01*
G01X3333476Y2943099D02*
Y2868099D01*
G01X3333486Y3193669D02*
Y3118669D01*
G01X3334245Y3735137D02*
Y3635137D01*
G01X3459580Y2654182D02*
Y2604182D01*
G01X3460576Y2943099D02*
Y2868099D01*
G01X3460586Y3193669D02*
Y3118669D01*
G01X3456240Y3449675D02*
Y3374675D01*
G01X3461345Y3735137D02*
Y3635137D01*
G01X3471771Y2049979D02*
Y-220821D01*
G01X3598871Y2049979D02*
Y-220821D01*
G01X3637670Y3685522D02*
Y3785522D01*
X4387870D01*
Y3685522D01*
X3637670D01*
G01Y3710522D02*
X4387870D01*
G01X3637670Y3735522D02*
X4387870D01*
G01X3637670Y3760522D02*
X4387870D01*
G01X3727570Y3735522D02*
Y3685522D01*
G01X3854670Y3735522D02*
Y3685522D01*
G01X4056170Y3735522D02*
Y3685522D01*
G01X4183270Y3735522D02*
Y3685522D01*
G01X4310370Y3735522D02*
Y3685522D01*
G01X-984580Y-698988D02*
Y4193602D01*
X5868320D01*
Y-698988D01*
X-984580D01*
G01X-409470Y1165068D02*
Y1177568D01*
X-411330Y1175068D01*
G01Y1165068D02*
X-407610D01*
G01X-397070D02*
Y1177568D01*
X-398930Y1175068D01*
G01Y1165068D02*
X-395210D01*
G01X-384980D02*
X-384670Y1167776D01*
X-384205Y1170068D01*
X-383585Y1172151D01*
X-382810Y1174443D01*
X-381570Y1177568D01*
X-387770D01*
G01X-372270Y1165068D02*
Y1177568D01*
X-374130Y1175068D01*
G01Y1165068D02*
X-370410D01*
G01X-363280Y1167568D02*
X-362350Y1166109D01*
X-361110Y1165276D01*
X-359715Y1165068D01*
X-358475Y1165276D01*
X-357235Y1166318D01*
X-356460Y1167568D01*
X-356305Y1168818D01*
X-356615Y1170276D01*
X-357700Y1171318D01*
X-358785Y1171735D01*
X-360180D01*
G01X-358785D02*
X-357855Y1172360D01*
X-357080Y1173401D01*
X-356770Y1174651D01*
X-357080Y1175901D01*
X-357855Y1176943D01*
X-359250Y1177568D01*
X-360645Y1177360D01*
X-362040Y1176526D01*
G01X-347470Y1164651D02*
X-347780Y1164860D01*
Y1165276D01*
X-347470Y1165485D01*
X-347160Y1165276D01*
Y1164860D01*
X-347470Y1164651D01*
G01X-335070Y1165068D02*
Y1177568D01*
X-336930Y1175068D01*
G01Y1165068D02*
X-333210D01*
G01X-322670D02*
X-321585Y1165276D01*
X-320345Y1165901D01*
X-319570Y1166943D01*
X-319260Y1168401D01*
X-319570Y1169859D01*
X-320500Y1171110D01*
X-321895Y1171735D01*
X-323445D01*
X-324375Y1172151D01*
X-325150Y1173193D01*
X-325460Y1174651D01*
X-324995Y1176110D01*
X-323910Y1177151D01*
X-322670Y1177568D01*
X-321430Y1177151D01*
X-320345Y1176110D01*
X-319880Y1174651D01*
X-320190Y1173193D01*
X-320965Y1172151D01*
X-321895Y1171735D01*
X-323445D01*
X-324840Y1171110D01*
X-325770Y1169859D01*
X-326080Y1168401D01*
X-325770Y1166943D01*
X-324995Y1165901D01*
X-323755Y1165276D01*
X-322670Y1165068D01*
G01X-416690Y1420790D02*
Y1433290D01*
X-418550Y1430790D01*
G01Y1420790D02*
X-414830D01*
G01X-407700Y1423290D02*
X-406770Y1421831D01*
X-405530Y1420998D01*
X-404135Y1420790D01*
X-402895Y1420998D01*
X-401655Y1422040D01*
X-400880Y1423290D01*
X-400725Y1424540D01*
X-401035Y1425998D01*
X-402120Y1427040D01*
X-403205Y1427457D01*
X-404600D01*
G01X-403205D02*
X-402275Y1428082D01*
X-401500Y1429123D01*
X-401190Y1430373D01*
X-401500Y1431623D01*
X-402275Y1432665D01*
X-403670Y1433290D01*
X-405065Y1433082D01*
X-406460Y1432248D01*
G01X-394525Y1422248D02*
X-393440Y1421207D01*
X-392200Y1420790D01*
X-390960Y1421207D01*
X-389875Y1422456D01*
X-389100Y1424332D01*
X-388790Y1426207D01*
Y1428498D01*
X-389100Y1430373D01*
X-389875Y1432040D01*
X-390805Y1432873D01*
X-391890Y1433290D01*
X-393130Y1432873D01*
X-394060Y1432040D01*
X-394680Y1430790D01*
X-394990Y1429123D01*
X-394680Y1427665D01*
X-393905Y1426207D01*
X-392975Y1425373D01*
X-391890Y1425165D01*
X-390650Y1425581D01*
X-389720Y1426623D01*
X-388790Y1428498D01*
G01X-382900Y1422665D02*
X-381970Y1421623D01*
X-380885Y1420998D01*
X-379490Y1420790D01*
X-378095Y1421207D01*
X-377010Y1422040D01*
X-376235Y1423498D01*
X-376080Y1425165D01*
X-376390Y1426832D01*
X-377165Y1427873D01*
X-378250Y1428707D01*
X-379335Y1428915D01*
X-380420Y1428707D01*
X-381815Y1427873D01*
X-381350Y1433290D01*
X-377165D01*
G01X-365230Y1420790D02*
Y1433290D01*
X-370965Y1424332D01*
X-363215D01*
G01X-354690Y1420373D02*
X-355000Y1420582D01*
Y1420998D01*
X-354690Y1421207D01*
X-354380Y1420998D01*
Y1420582D01*
X-354690Y1420373D01*
G01X-342290Y1420790D02*
Y1433290D01*
X-344150Y1430790D01*
G01Y1420790D02*
X-340430D01*
G01X-333300Y1423290D02*
X-332370Y1421831D01*
X-331130Y1420998D01*
X-329735Y1420790D01*
X-328495Y1420998D01*
X-327255Y1422040D01*
X-326480Y1423290D01*
X-326325Y1424540D01*
X-326635Y1425998D01*
X-327720Y1427040D01*
X-328805Y1427457D01*
X-330200D01*
G01X-328805D02*
X-327875Y1428082D01*
X-327100Y1429123D01*
X-326790Y1430373D01*
X-327100Y1431623D01*
X-327875Y1432665D01*
X-329270Y1433290D01*
X-330665Y1433082D01*
X-332060Y1432248D01*
G01X-415490Y1450870D02*
Y1463370D01*
X-417350Y1460870D01*
G01Y1450870D02*
X-413630D01*
G01X-401230D02*
Y1463370D01*
X-406965Y1454412D01*
X-399215D01*
G01X-393635Y1461287D02*
X-392705Y1462536D01*
X-391620Y1463162D01*
X-390380Y1463370D01*
X-388830Y1462953D01*
X-387745Y1461912D01*
X-387435Y1460662D01*
X-387590Y1459411D01*
X-388210Y1458370D01*
X-391310Y1456287D01*
X-392705Y1454828D01*
X-393635Y1452745D01*
X-393945Y1450870D01*
X-387435D01*
G01X-378290Y1463370D02*
X-379530Y1462953D01*
X-380460Y1461912D01*
X-381080Y1460662D01*
X-381545Y1458995D01*
X-381700Y1457120D01*
X-381545Y1455245D01*
X-381080Y1453578D01*
X-380460Y1452328D01*
X-379530Y1451287D01*
X-378290Y1450870D01*
X-377050Y1451287D01*
X-376120Y1452328D01*
X-375500Y1453578D01*
X-375035Y1455245D01*
X-374880Y1457120D01*
X-375035Y1458995D01*
X-375500Y1460662D01*
X-376120Y1461912D01*
X-377050Y1462953D01*
X-378290Y1463370D01*
G01X-369300Y1453370D02*
X-368370Y1451911D01*
X-367130Y1451078D01*
X-365735Y1450870D01*
X-364495Y1451078D01*
X-363255Y1452120D01*
X-362480Y1453370D01*
X-362325Y1454620D01*
X-362635Y1456078D01*
X-363720Y1457120D01*
X-364805Y1457537D01*
X-366200D01*
G01X-364805D02*
X-363875Y1458162D01*
X-363100Y1459203D01*
X-362790Y1460453D01*
X-363100Y1461703D01*
X-363875Y1462745D01*
X-365270Y1463370D01*
X-366665Y1463162D01*
X-368060Y1462328D01*
G01X-353490Y1450453D02*
X-353800Y1450662D01*
Y1451078D01*
X-353490Y1451287D01*
X-353180Y1451078D01*
Y1450662D01*
X-353490Y1450453D01*
G01X-344500Y1453370D02*
X-343570Y1451911D01*
X-342330Y1451078D01*
X-340935Y1450870D01*
X-339695Y1451078D01*
X-338455Y1452120D01*
X-337680Y1453370D01*
X-337525Y1454620D01*
X-337835Y1456078D01*
X-338920Y1457120D01*
X-340005Y1457537D01*
X-341400D01*
G01X-340005D02*
X-339075Y1458162D01*
X-338300Y1459203D01*
X-337990Y1460453D01*
X-338300Y1461703D01*
X-339075Y1462745D01*
X-340470Y1463370D01*
X-341865Y1463162D01*
X-343260Y1462328D01*
G01X-328690Y1463370D02*
X-329930Y1462953D01*
X-330860Y1461912D01*
X-331480Y1460662D01*
X-331945Y1458995D01*
X-332100Y1457120D01*
X-331945Y1455245D01*
X-331480Y1453578D01*
X-330860Y1452328D01*
X-329930Y1451287D01*
X-328690Y1450870D01*
X-327450Y1451287D01*
X-326520Y1452328D01*
X-325900Y1453578D01*
X-325435Y1455245D01*
X-325280Y1457120D01*
X-325435Y1458995D01*
X-325900Y1460662D01*
X-326520Y1461912D01*
X-327450Y1462953D01*
X-328690Y1463370D01*
G01X-414290Y1679470D02*
Y1691970D01*
X-416150Y1689470D01*
G01Y1679470D02*
X-412430D01*
G01X-404835Y1684678D02*
X-403750Y1686137D01*
X-402820Y1686970D01*
X-401580Y1687387D01*
X-400495Y1686970D01*
X-399720Y1686137D01*
X-399100Y1684887D01*
X-398945Y1683428D01*
X-399100Y1682178D01*
X-399720Y1680928D01*
X-400650Y1679887D01*
X-401735Y1679470D01*
X-402975Y1679887D01*
X-404060Y1681136D01*
X-404680Y1683012D01*
X-404835Y1685095D01*
X-404525Y1687803D01*
X-404060Y1689262D01*
X-403285Y1690720D01*
X-402200Y1691762D01*
X-401115Y1691970D01*
X-400030Y1691553D01*
X-399255Y1690512D01*
G01X-392125Y1680928D02*
X-391040Y1679887D01*
X-389800Y1679470D01*
X-388560Y1679887D01*
X-387475Y1681136D01*
X-386700Y1683012D01*
X-386390Y1684887D01*
Y1687178D01*
X-386700Y1689053D01*
X-387475Y1690720D01*
X-388405Y1691553D01*
X-389490Y1691970D01*
X-390730Y1691553D01*
X-391660Y1690720D01*
X-392280Y1689470D01*
X-392590Y1687803D01*
X-392280Y1686345D01*
X-391505Y1684887D01*
X-390575Y1684053D01*
X-389490Y1683845D01*
X-388250Y1684261D01*
X-387320Y1685303D01*
X-386390Y1687178D01*
G01X-377090Y1679470D02*
X-376005Y1679678D01*
X-374765Y1680303D01*
X-373990Y1681345D01*
X-373680Y1682803D01*
X-373990Y1684261D01*
X-374920Y1685512D01*
X-376315Y1686137D01*
X-377865D01*
X-378795Y1686553D01*
X-379570Y1687595D01*
X-379880Y1689053D01*
X-379415Y1690512D01*
X-378330Y1691553D01*
X-377090Y1691970D01*
X-375850Y1691553D01*
X-374765Y1690512D01*
X-374300Y1689053D01*
X-374610Y1687595D01*
X-375385Y1686553D01*
X-376315Y1686137D01*
X-377865D01*
X-379260Y1685512D01*
X-380190Y1684261D01*
X-380500Y1682803D01*
X-380190Y1681345D01*
X-379415Y1680303D01*
X-378175Y1679678D01*
X-377090Y1679470D01*
G01X-367635Y1689887D02*
X-366705Y1691136D01*
X-365620Y1691762D01*
X-364380Y1691970D01*
X-362830Y1691553D01*
X-361745Y1690512D01*
X-361435Y1689262D01*
X-361590Y1688011D01*
X-362210Y1686970D01*
X-365310Y1684887D01*
X-366705Y1683428D01*
X-367635Y1681345D01*
X-367945Y1679470D01*
X-361435D01*
G01X-352290Y1679053D02*
X-352600Y1679262D01*
Y1679678D01*
X-352290Y1679887D01*
X-351980Y1679678D01*
Y1679262D01*
X-352290Y1679053D01*
G01X-342835Y1684678D02*
X-341750Y1686137D01*
X-340820Y1686970D01*
X-339580Y1687387D01*
X-338495Y1686970D01*
X-337720Y1686137D01*
X-337100Y1684887D01*
X-336945Y1683428D01*
X-337100Y1682178D01*
X-337720Y1680928D01*
X-338650Y1679887D01*
X-339735Y1679470D01*
X-340975Y1679887D01*
X-342060Y1681136D01*
X-342680Y1683012D01*
X-342835Y1685095D01*
X-342525Y1687803D01*
X-342060Y1689262D01*
X-341285Y1690720D01*
X-340200Y1691762D01*
X-339115Y1691970D01*
X-338030Y1691553D01*
X-337255Y1690512D01*
G01X-327800Y1679470D02*
X-327490Y1682178D01*
X-327025Y1684470D01*
X-326405Y1686553D01*
X-325630Y1688845D01*
X-324390Y1691970D01*
X-330590D01*
G01X-401405Y565708D02*
X-400320Y567167D01*
X-399390Y568000D01*
X-398150Y568417D01*
X-397065Y568000D01*
X-396290Y567167D01*
X-395670Y565917D01*
X-395515Y564458D01*
X-395670Y563208D01*
X-396290Y561958D01*
X-397220Y560917D01*
X-398305Y560500D01*
X-399545Y560917D01*
X-400630Y562166D01*
X-401250Y564042D01*
X-401405Y566125D01*
X-401095Y568833D01*
X-400630Y570292D01*
X-399855Y571750D01*
X-398770Y572792D01*
X-397685Y573000D01*
X-396600Y572583D01*
X-395825Y571542D01*
G01X-386060Y573000D02*
X-387300Y572583D01*
X-388230Y571542D01*
X-388850Y570292D01*
X-389315Y568625D01*
X-389470Y566750D01*
X-389315Y564875D01*
X-388850Y563208D01*
X-388230Y561958D01*
X-387300Y560917D01*
X-386060Y560500D01*
X-384820Y560917D01*
X-383890Y561958D01*
X-383270Y563208D01*
X-382805Y564875D01*
X-382650Y566750D01*
X-382805Y568625D01*
X-383270Y570292D01*
X-383890Y571542D01*
X-384820Y572583D01*
X-386060Y573000D01*
G01X-377070Y562375D02*
X-376140Y561333D01*
X-375055Y560708D01*
X-373660Y560500D01*
X-372265Y560917D01*
X-371180Y561750D01*
X-370405Y563208D01*
X-370250Y564875D01*
X-370560Y566542D01*
X-371335Y567583D01*
X-372420Y568417D01*
X-373505Y568625D01*
X-374590Y568417D01*
X-375985Y567583D01*
X-375520Y573000D01*
X-371335D01*
G01X-364670Y563000D02*
X-363740Y561541D01*
X-362500Y560708D01*
X-361105Y560500D01*
X-359865Y560708D01*
X-358625Y561750D01*
X-357850Y563000D01*
X-357695Y564250D01*
X-358005Y565708D01*
X-359090Y566750D01*
X-360175Y567167D01*
X-361570D01*
G01X-360175D02*
X-359245Y567792D01*
X-358470Y568833D01*
X-358160Y570083D01*
X-358470Y571333D01*
X-359245Y572375D01*
X-360640Y573000D01*
X-362035Y572792D01*
X-363430Y571958D01*
G01X-348860Y560083D02*
X-349170Y560292D01*
Y560708D01*
X-348860Y560917D01*
X-348550Y560708D01*
Y560292D01*
X-348860Y560083D01*
G01X-336460Y560500D02*
X-335375Y560708D01*
X-334135Y561333D01*
X-333360Y562375D01*
X-333050Y563833D01*
X-333360Y565291D01*
X-334290Y566542D01*
X-335685Y567167D01*
X-337235D01*
X-338165Y567583D01*
X-338940Y568625D01*
X-339250Y570083D01*
X-338785Y571542D01*
X-337700Y572583D01*
X-336460Y573000D01*
X-335220Y572583D01*
X-334135Y571542D01*
X-333670Y570083D01*
X-333980Y568625D01*
X-334755Y567583D01*
X-335685Y567167D01*
X-337235D01*
X-338630Y566542D01*
X-339560Y565291D01*
X-339870Y563833D01*
X-339560Y562375D01*
X-338785Y561333D01*
X-337545Y560708D01*
X-336460Y560500D01*
G01X-324060Y573000D02*
X-325300Y572583D01*
X-326230Y571542D01*
X-326850Y570292D01*
X-327315Y568625D01*
X-327470Y566750D01*
X-327315Y564875D01*
X-326850Y563208D01*
X-326230Y561958D01*
X-325300Y560917D01*
X-324060Y560500D01*
X-322820Y560917D01*
X-321890Y561958D01*
X-321270Y563208D01*
X-320805Y564875D01*
X-320650Y566750D01*
X-320805Y568625D01*
X-321270Y570292D01*
X-321890Y571542D01*
X-322820Y572583D01*
X-324060Y573000D01*
G01X-398995Y604413D02*
X-397910Y605872D01*
X-396980Y606705D01*
X-395740Y607122D01*
X-394655Y606705D01*
X-393880Y605872D01*
X-393260Y604622D01*
X-393105Y603163D01*
X-393260Y601913D01*
X-393880Y600663D01*
X-394810Y599622D01*
X-395895Y599205D01*
X-397135Y599622D01*
X-398220Y600871D01*
X-398840Y602747D01*
X-398995Y604830D01*
X-398685Y607538D01*
X-398220Y608997D01*
X-397445Y610455D01*
X-396360Y611497D01*
X-395275Y611705D01*
X-394190Y611288D01*
X-393415Y610247D01*
G01X-383650Y611705D02*
X-384890Y611288D01*
X-385820Y610247D01*
X-386440Y608997D01*
X-386905Y607330D01*
X-387060Y605455D01*
X-386905Y603580D01*
X-386440Y601913D01*
X-385820Y600663D01*
X-384890Y599622D01*
X-383650Y599205D01*
X-382410Y599622D01*
X-381480Y600663D01*
X-380860Y601913D01*
X-380395Y603580D01*
X-380240Y605455D01*
X-380395Y607330D01*
X-380860Y608997D01*
X-381480Y610247D01*
X-382410Y611288D01*
X-383650Y611705D01*
G01X-374660Y601080D02*
X-373730Y600038D01*
X-372645Y599413D01*
X-371250Y599205D01*
X-369855Y599622D01*
X-368770Y600455D01*
X-367995Y601913D01*
X-367840Y603580D01*
X-368150Y605247D01*
X-368925Y606288D01*
X-370010Y607122D01*
X-371095Y607330D01*
X-372180Y607122D01*
X-373575Y606288D01*
X-373110Y611705D01*
X-368925D01*
G01X-356990Y599205D02*
Y611705D01*
X-362725Y602747D01*
X-354975D01*
G01X-346450Y598788D02*
X-346760Y598997D01*
Y599413D01*
X-346450Y599622D01*
X-346140Y599413D01*
Y598997D01*
X-346450Y598788D01*
G01X-337460Y601080D02*
X-336530Y600038D01*
X-335445Y599413D01*
X-334050Y599205D01*
X-332655Y599622D01*
X-331570Y600455D01*
X-330795Y601913D01*
X-330640Y603580D01*
X-330950Y605247D01*
X-331725Y606288D01*
X-332810Y607122D01*
X-333895Y607330D01*
X-334980Y607122D01*
X-336375Y606288D01*
X-335910Y611705D01*
X-331725D01*
G01X-325060Y601080D02*
X-324130Y600038D01*
X-323045Y599413D01*
X-321650Y599205D01*
X-320255Y599622D01*
X-319170Y600455D01*
X-318395Y601913D01*
X-318240Y603580D01*
X-318550Y605247D01*
X-319325Y606288D01*
X-320410Y607122D01*
X-321495Y607330D01*
X-322580Y607122D01*
X-323975Y606288D01*
X-323510Y611705D01*
X-319325D01*
G01X-393650Y804871D02*
X-392565Y805079D01*
X-391325Y805704D01*
X-390550Y806746D01*
X-390240Y808204D01*
X-390550Y809662D01*
X-391480Y810913D01*
X-392875Y811538D01*
X-394425D01*
X-395355Y811954D01*
X-396130Y812996D01*
X-396440Y814454D01*
X-395975Y815913D01*
X-394890Y816954D01*
X-393650Y817371D01*
X-392410Y816954D01*
X-391325Y815913D01*
X-390860Y814454D01*
X-391170Y812996D01*
X-391945Y811954D01*
X-392875Y811538D01*
X-394425D01*
X-395820Y810913D01*
X-396750Y809662D01*
X-397060Y808204D01*
X-396750Y806746D01*
X-395975Y805704D01*
X-394735Y805079D01*
X-393650Y804871D01*
G01X-381250D02*
Y817371D01*
X-383110Y814871D01*
G01Y804871D02*
X-379390D01*
G01X-368850D02*
Y817371D01*
X-370710Y814871D01*
G01Y804871D02*
X-366990D01*
G01X-356450D02*
Y817371D01*
X-358310Y814871D01*
G01Y804871D02*
X-354590D01*
G01X-344050Y804454D02*
X-344360Y804663D01*
Y805079D01*
X-344050Y805288D01*
X-343740Y805079D01*
Y804663D01*
X-344050Y804454D01*
G01X-334595Y815288D02*
X-333665Y816537D01*
X-332580Y817163D01*
X-331340Y817371D01*
X-329790Y816954D01*
X-328705Y815913D01*
X-328395Y814663D01*
X-328550Y813412D01*
X-329170Y812371D01*
X-332270Y810288D01*
X-333665Y808829D01*
X-334595Y806746D01*
X-334905Y804871D01*
X-328395D01*
G01X-319250D02*
Y817371D01*
X-321110Y814871D01*
G01Y804871D02*
X-317390D01*
G01X-403505Y986428D02*
X-402420Y985387D01*
X-401180Y984970D01*
X-399940Y985387D01*
X-398855Y986636D01*
X-398080Y988512D01*
X-397770Y990387D01*
Y992678D01*
X-398080Y994553D01*
X-398855Y996220D01*
X-399785Y997053D01*
X-400870Y997470D01*
X-402110Y997053D01*
X-403040Y996220D01*
X-403660Y994970D01*
X-403970Y993303D01*
X-403660Y991845D01*
X-402885Y990387D01*
X-401955Y989553D01*
X-400870Y989345D01*
X-399630Y989761D01*
X-398700Y990803D01*
X-397770Y992678D01*
G01X-391105Y986428D02*
X-390020Y985387D01*
X-388780Y984970D01*
X-387540Y985387D01*
X-386455Y986636D01*
X-385680Y988512D01*
X-385370Y990387D01*
Y992678D01*
X-385680Y994553D01*
X-386455Y996220D01*
X-387385Y997053D01*
X-388470Y997470D01*
X-389710Y997053D01*
X-390640Y996220D01*
X-391260Y994970D01*
X-391570Y993303D01*
X-391260Y991845D01*
X-390485Y990387D01*
X-389555Y989553D01*
X-388470Y989345D01*
X-387230Y989761D01*
X-386300Y990803D01*
X-385370Y992678D01*
G01X-376070Y984970D02*
Y997470D01*
X-377930Y994970D01*
G01Y984970D02*
X-374210D01*
G01X-366615Y995387D02*
X-365685Y996636D01*
X-364600Y997262D01*
X-363360Y997470D01*
X-361810Y997053D01*
X-360725Y996012D01*
X-360415Y994762D01*
X-360570Y993511D01*
X-361190Y992470D01*
X-364290Y990387D01*
X-365685Y988928D01*
X-366615Y986845D01*
X-366925Y984970D01*
X-360415D01*
G01X-351270Y984553D02*
X-351580Y984762D01*
Y985178D01*
X-351270Y985387D01*
X-350960Y985178D01*
Y984762D01*
X-351270Y984553D01*
G01X-341815Y995387D02*
X-340885Y996636D01*
X-339800Y997262D01*
X-338560Y997470D01*
X-337010Y997053D01*
X-335925Y996012D01*
X-335615Y994762D01*
X-335770Y993511D01*
X-336390Y992470D01*
X-339490Y990387D01*
X-340885Y988928D01*
X-341815Y986845D01*
X-342125Y984970D01*
X-335615D01*
G01X-326470Y997470D02*
X-327710Y997053D01*
X-328640Y996012D01*
X-329260Y994762D01*
X-329725Y993095D01*
X-329880Y991220D01*
X-329725Y989345D01*
X-329260Y987678D01*
X-328640Y986428D01*
X-327710Y985387D01*
X-326470Y984970D01*
X-325230Y985387D01*
X-324300Y986428D01*
X-323680Y987678D01*
X-323215Y989345D01*
X-323060Y991220D01*
X-323215Y993095D01*
X-323680Y994762D01*
X-324300Y996012D01*
X-325230Y997053D01*
X-326470Y997470D01*
G01X-378960Y105758D02*
Y118258D01*
X-380820Y115758D01*
G01Y105758D02*
X-377100D01*
G01X-366560D02*
Y118258D01*
X-368420Y115758D01*
G01Y105758D02*
X-364700D01*
G01X-357105Y116175D02*
X-356175Y117424D01*
X-355090Y118050D01*
X-353850Y118258D01*
X-352300Y117841D01*
X-351215Y116800D01*
X-350905Y115550D01*
X-351060Y114299D01*
X-351680Y113258D01*
X-354780Y111175D01*
X-356175Y109716D01*
X-357105Y107633D01*
X-357415Y105758D01*
X-350905D01*
G01X-341760Y118258D02*
X-343000Y117841D01*
X-343930Y116800D01*
X-344550Y115550D01*
X-345015Y113883D01*
X-345170Y112008D01*
X-345015Y110133D01*
X-344550Y108466D01*
X-343930Y107216D01*
X-343000Y106175D01*
X-341760Y105758D01*
X-340520Y106175D01*
X-339590Y107216D01*
X-338970Y108466D01*
X-338505Y110133D01*
X-338350Y112008D01*
X-338505Y113883D01*
X-338970Y115550D01*
X-339590Y116800D01*
X-340520Y117841D01*
X-341760Y118258D01*
G01X-329360Y105341D02*
X-329670Y105550D01*
Y105966D01*
X-329360Y106175D01*
X-329050Y105966D01*
Y105550D01*
X-329360Y105341D01*
G01X-316960Y118258D02*
X-318200Y117841D01*
X-319130Y116800D01*
X-319750Y115550D01*
X-320215Y113883D01*
X-320370Y112008D01*
X-320215Y110133D01*
X-319750Y108466D01*
X-319130Y107216D01*
X-318200Y106175D01*
X-316960Y105758D01*
X-315720Y106175D01*
X-314790Y107216D01*
X-314170Y108466D01*
X-313705Y110133D01*
X-313550Y112008D01*
X-313705Y113883D01*
X-314170Y115550D01*
X-314790Y116800D01*
X-315720Y117841D01*
X-316960Y118258D01*
G01X-304560Y105758D02*
X-303475Y105966D01*
X-302235Y106591D01*
X-301460Y107633D01*
X-301150Y109091D01*
X-301460Y110549D01*
X-302390Y111800D01*
X-303785Y112425D01*
X-305335D01*
X-306265Y112841D01*
X-307040Y113883D01*
X-307350Y115341D01*
X-306885Y116800D01*
X-305800Y117841D01*
X-304560Y118258D01*
X-303320Y117841D01*
X-302235Y116800D01*
X-301770Y115341D01*
X-302080Y113883D01*
X-302855Y112841D01*
X-303785Y112425D01*
X-305335D01*
X-306730Y111800D01*
X-307660Y110549D01*
X-307970Y109091D01*
X-307660Y107633D01*
X-306885Y106591D01*
X-305645Y105966D01*
X-304560Y105758D01*
G01X-378360Y178986D02*
Y191486D01*
X-380220Y188986D01*
G01Y178986D02*
X-376500D01*
G01X-365960D02*
X-364875Y179194D01*
X-363635Y179819D01*
X-362860Y180861D01*
X-362550Y182319D01*
X-362860Y183777D01*
X-363790Y185028D01*
X-365185Y185653D01*
X-366735D01*
X-367665Y186069D01*
X-368440Y187111D01*
X-368750Y188569D01*
X-368285Y190028D01*
X-367200Y191069D01*
X-365960Y191486D01*
X-364720Y191069D01*
X-363635Y190028D01*
X-363170Y188569D01*
X-363480Y187111D01*
X-364255Y186069D01*
X-365185Y185653D01*
X-366735D01*
X-368130Y185028D01*
X-369060Y183777D01*
X-369370Y182319D01*
X-369060Y180861D01*
X-368285Y179819D01*
X-367045Y179194D01*
X-365960Y178986D01*
G01X-356970Y180861D02*
X-356040Y179819D01*
X-354955Y179194D01*
X-353560Y178986D01*
X-352165Y179403D01*
X-351080Y180236D01*
X-350305Y181694D01*
X-350150Y183361D01*
X-350460Y185028D01*
X-351235Y186069D01*
X-352320Y186903D01*
X-353405Y187111D01*
X-354490Y186903D01*
X-355885Y186069D01*
X-355420Y191486D01*
X-351235D01*
G01X-344105Y189403D02*
X-343175Y190652D01*
X-342090Y191278D01*
X-340850Y191486D01*
X-339300Y191069D01*
X-338215Y190028D01*
X-337905Y188778D01*
X-338060Y187527D01*
X-338680Y186486D01*
X-341780Y184403D01*
X-343175Y182944D01*
X-344105Y180861D01*
X-344415Y178986D01*
X-337905D01*
G01X-328760Y178569D02*
X-329070Y178778D01*
Y179194D01*
X-328760Y179403D01*
X-328450Y179194D01*
Y178778D01*
X-328760Y178569D01*
G01X-319770Y181486D02*
X-318840Y180027D01*
X-317600Y179194D01*
X-316205Y178986D01*
X-314965Y179194D01*
X-313725Y180236D01*
X-312950Y181486D01*
X-312795Y182736D01*
X-313105Y184194D01*
X-314190Y185236D01*
X-315275Y185653D01*
X-316670D01*
G01X-315275D02*
X-314345Y186278D01*
X-313570Y187319D01*
X-313260Y188569D01*
X-313570Y189819D01*
X-314345Y190861D01*
X-315740Y191486D01*
X-317135Y191278D01*
X-318530Y190444D01*
G01X-306905Y184194D02*
X-305820Y185653D01*
X-304890Y186486D01*
X-303650Y186903D01*
X-302565Y186486D01*
X-301790Y185653D01*
X-301170Y184403D01*
X-301015Y182944D01*
X-301170Y181694D01*
X-301790Y180444D01*
X-302720Y179403D01*
X-303805Y178986D01*
X-305045Y179403D01*
X-306130Y180652D01*
X-306750Y182528D01*
X-306905Y184611D01*
X-306595Y187319D01*
X-306130Y188778D01*
X-305355Y190236D01*
X-304270Y191278D01*
X-303185Y191486D01*
X-302100Y191069D01*
X-301325Y190028D01*
G01X-381905Y273655D02*
X-380975Y274904D01*
X-379890Y275530D01*
X-378650Y275738D01*
X-377100Y275321D01*
X-376015Y274280D01*
X-375705Y273030D01*
X-375860Y271779D01*
X-376480Y270738D01*
X-379580Y268655D01*
X-380975Y267196D01*
X-381905Y265113D01*
X-382215Y263238D01*
X-375705D01*
G01X-369505Y268446D02*
X-368420Y269905D01*
X-367490Y270738D01*
X-366250Y271155D01*
X-365165Y270738D01*
X-364390Y269905D01*
X-363770Y268655D01*
X-363615Y267196D01*
X-363770Y265946D01*
X-364390Y264696D01*
X-365320Y263655D01*
X-366405Y263238D01*
X-367645Y263655D01*
X-368730Y264904D01*
X-369350Y266780D01*
X-369505Y268863D01*
X-369195Y271571D01*
X-368730Y273030D01*
X-367955Y274488D01*
X-366870Y275530D01*
X-365785Y275738D01*
X-364700Y275321D01*
X-363925Y274280D01*
G01X-356795Y264696D02*
X-355710Y263655D01*
X-354470Y263238D01*
X-353230Y263655D01*
X-352145Y264904D01*
X-351370Y266780D01*
X-351060Y268655D01*
Y270946D01*
X-351370Y272821D01*
X-352145Y274488D01*
X-353075Y275321D01*
X-354160Y275738D01*
X-355400Y275321D01*
X-356330Y274488D01*
X-356950Y273238D01*
X-357260Y271571D01*
X-356950Y270113D01*
X-356175Y268655D01*
X-355245Y267821D01*
X-354160Y267613D01*
X-352920Y268029D01*
X-351990Y269071D01*
X-351060Y270946D01*
G01X-339900Y263238D02*
Y275738D01*
X-345635Y266780D01*
X-337885D01*
G01X-329360Y262821D02*
X-329670Y263030D01*
Y263446D01*
X-329360Y263655D01*
X-329050Y263446D01*
Y263030D01*
X-329360Y262821D01*
G01X-316960Y263238D02*
X-315875Y263446D01*
X-314635Y264071D01*
X-313860Y265113D01*
X-313550Y266571D01*
X-313860Y268029D01*
X-314790Y269280D01*
X-316185Y269905D01*
X-317735D01*
X-318665Y270321D01*
X-319440Y271363D01*
X-319750Y272821D01*
X-319285Y274280D01*
X-318200Y275321D01*
X-316960Y275738D01*
X-315720Y275321D01*
X-314635Y274280D01*
X-314170Y272821D01*
X-314480Y271363D01*
X-315255Y270321D01*
X-316185Y269905D01*
X-317735D01*
X-319130Y269280D01*
X-320060Y268029D01*
X-320370Y266571D01*
X-320060Y265113D01*
X-319285Y264071D01*
X-318045Y263446D01*
X-316960Y263238D01*
G01X-304560D02*
X-303475Y263446D01*
X-302235Y264071D01*
X-301460Y265113D01*
X-301150Y266571D01*
X-301460Y268029D01*
X-302390Y269280D01*
X-303785Y269905D01*
X-305335D01*
X-306265Y270321D01*
X-307040Y271363D01*
X-307350Y272821D01*
X-306885Y274280D01*
X-305800Y275321D01*
X-304560Y275738D01*
X-303320Y275321D01*
X-302235Y274280D01*
X-301770Y272821D01*
X-302080Y271363D01*
X-302855Y270321D01*
X-303785Y269905D01*
X-305335D01*
X-306730Y269280D01*
X-307660Y268029D01*
X-307970Y266571D01*
X-307660Y265113D01*
X-306885Y264071D01*
X-305645Y263446D01*
X-304560Y263238D01*
G01X-383175Y297937D02*
X-382245Y299186D01*
X-381160Y299812D01*
X-379920Y300020D01*
X-378370Y299603D01*
X-377285Y298562D01*
X-376975Y297312D01*
X-377130Y296061D01*
X-377750Y295020D01*
X-380850Y292937D01*
X-382245Y291478D01*
X-383175Y289395D01*
X-383485Y287520D01*
X-376975D01*
G01X-368140D02*
X-367830Y290228D01*
X-367365Y292520D01*
X-366745Y294603D01*
X-365970Y296895D01*
X-364730Y300020D01*
X-370930D01*
G01X-355740Y287520D02*
X-355430Y290228D01*
X-354965Y292520D01*
X-354345Y294603D01*
X-353570Y296895D01*
X-352330Y300020D01*
X-358530D01*
G01X-345975Y297937D02*
X-345045Y299186D01*
X-343960Y299812D01*
X-342720Y300020D01*
X-341170Y299603D01*
X-340085Y298562D01*
X-339775Y297312D01*
X-339930Y296061D01*
X-340550Y295020D01*
X-343650Y292937D01*
X-345045Y291478D01*
X-345975Y289395D01*
X-346285Y287520D01*
X-339775D01*
G01X-330630Y287103D02*
X-330940Y287312D01*
Y287728D01*
X-330630Y287937D01*
X-330320Y287728D01*
Y287312D01*
X-330630Y287103D01*
G01X-321640Y290020D02*
X-320710Y288561D01*
X-319470Y287728D01*
X-318075Y287520D01*
X-316835Y287728D01*
X-315595Y288770D01*
X-314820Y290020D01*
X-314665Y291270D01*
X-314975Y292728D01*
X-316060Y293770D01*
X-317145Y294187D01*
X-318540D01*
G01X-317145D02*
X-316215Y294812D01*
X-315440Y295853D01*
X-315130Y297103D01*
X-315440Y298353D01*
X-316215Y299395D01*
X-317610Y300020D01*
X-319005Y299812D01*
X-320400Y298978D01*
G01X-308775Y292728D02*
X-307690Y294187D01*
X-306760Y295020D01*
X-305520Y295437D01*
X-304435Y295020D01*
X-303660Y294187D01*
X-303040Y292937D01*
X-302885Y291478D01*
X-303040Y290228D01*
X-303660Y288978D01*
X-304590Y287937D01*
X-305675Y287520D01*
X-306915Y287937D01*
X-308000Y289186D01*
X-308620Y291062D01*
X-308775Y293145D01*
X-308465Y295853D01*
X-308000Y297312D01*
X-307225Y298770D01*
X-306140Y299812D01*
X-305055Y300020D01*
X-303970Y299603D01*
X-303195Y298562D01*
G01X-369020Y317903D02*
X-368090Y316444D01*
X-366850Y315611D01*
X-365455Y315403D01*
X-364215Y315611D01*
X-362975Y316653D01*
X-362200Y317903D01*
X-362045Y319153D01*
X-362355Y320611D01*
X-363440Y321653D01*
X-364525Y322070D01*
X-365920D01*
G01X-364525D02*
X-363595Y322695D01*
X-362820Y323736D01*
X-362510Y324986D01*
X-362820Y326236D01*
X-363595Y327278D01*
X-364990Y327903D01*
X-366385Y327695D01*
X-367780Y326861D01*
G01X-356155Y325820D02*
X-355225Y327069D01*
X-354140Y327695D01*
X-352900Y327903D01*
X-351350Y327486D01*
X-350265Y326445D01*
X-349955Y325195D01*
X-350110Y323944D01*
X-350730Y322903D01*
X-353830Y320820D01*
X-355225Y319361D01*
X-356155Y317278D01*
X-356465Y315403D01*
X-349955D01*
G01X-340810D02*
Y327903D01*
X-342670Y325403D01*
G01Y315403D02*
X-338950D01*
G01X-331355Y320611D02*
X-330270Y322070D01*
X-329340Y322903D01*
X-328100Y323320D01*
X-327015Y322903D01*
X-326240Y322070D01*
X-325620Y320820D01*
X-325465Y319361D01*
X-325620Y318111D01*
X-326240Y316861D01*
X-327170Y315820D01*
X-328255Y315403D01*
X-329495Y315820D01*
X-330580Y317069D01*
X-331200Y318945D01*
X-331355Y321028D01*
X-331045Y323736D01*
X-330580Y325195D01*
X-329805Y326653D01*
X-328720Y327695D01*
X-327635Y327903D01*
X-326550Y327486D01*
X-325775Y326445D01*
G01X-316010Y314986D02*
X-316320Y315195D01*
Y315611D01*
X-316010Y315820D01*
X-315700Y315611D01*
Y315195D01*
X-316010Y314986D01*
G01X-307020Y317278D02*
X-306090Y316236D01*
X-305005Y315611D01*
X-303610Y315403D01*
X-302215Y315820D01*
X-301130Y316653D01*
X-300355Y318111D01*
X-300200Y319778D01*
X-300510Y321445D01*
X-301285Y322486D01*
X-302370Y323320D01*
X-303455Y323528D01*
X-304540Y323320D01*
X-305935Y322486D01*
X-305470Y327903D01*
X-301285D01*
G01X-294620Y317903D02*
X-293690Y316444D01*
X-292450Y315611D01*
X-291055Y315403D01*
X-289815Y315611D01*
X-288575Y316653D01*
X-287800Y317903D01*
X-287645Y319153D01*
X-287955Y320611D01*
X-289040Y321653D01*
X-290125Y322070D01*
X-291520D01*
G01X-290125D02*
X-289195Y322695D01*
X-288420Y323736D01*
X-288110Y324986D01*
X-288420Y326236D01*
X-289195Y327278D01*
X-290590Y327903D01*
X-291985Y327695D01*
X-293380Y326861D01*
G01X-344055Y208891D02*
X-343125Y210140D01*
X-342040Y210766D01*
X-340800Y210974D01*
X-339250Y210557D01*
X-338165Y209516D01*
X-337855Y208266D01*
X-338010Y207015D01*
X-338630Y205974D01*
X-341730Y203891D01*
X-343125Y202432D01*
X-344055Y200349D01*
X-344365Y198474D01*
X-337855D01*
G01X-328710Y210974D02*
X-329950Y210557D01*
X-330880Y209516D01*
X-331500Y208266D01*
X-331965Y206599D01*
X-332120Y204724D01*
X-331965Y202849D01*
X-331500Y201182D01*
X-330880Y199932D01*
X-329950Y198891D01*
X-328710Y198474D01*
X-327470Y198891D01*
X-326540Y199932D01*
X-325920Y201182D01*
X-325455Y202849D01*
X-325300Y204724D01*
X-325455Y206599D01*
X-325920Y208266D01*
X-326540Y209516D01*
X-327470Y210557D01*
X-328710Y210974D01*
G01X-314450Y198474D02*
Y210974D01*
X-320185Y202016D01*
X-312435D01*
G01X-304220Y198474D02*
X-303910Y201182D01*
X-303445Y203474D01*
X-302825Y205557D01*
X-302050Y207849D01*
X-300810Y210974D01*
X-307010D01*
G01X-291510Y198057D02*
X-291820Y198266D01*
Y198682D01*
X-291510Y198891D01*
X-291200Y198682D01*
Y198266D01*
X-291510Y198057D01*
G01X-282055Y208891D02*
X-281125Y210140D01*
X-280040Y210766D01*
X-278800Y210974D01*
X-277250Y210557D01*
X-276165Y209516D01*
X-275855Y208266D01*
X-276010Y207015D01*
X-276630Y205974D01*
X-279730Y203891D01*
X-281125Y202432D01*
X-282055Y200349D01*
X-282365Y198474D01*
X-275855D01*
G01X-264850D02*
Y210974D01*
X-270585Y202016D01*
X-262835D01*
G01X-294815Y995387D02*
X-293885Y996636D01*
X-292800Y997262D01*
X-291560Y997470D01*
X-290010Y997053D01*
X-288925Y996012D01*
X-288615Y994762D01*
X-288770Y993511D01*
X-289390Y992470D01*
X-292490Y990387D01*
X-293885Y988928D01*
X-294815Y986845D01*
X-295125Y984970D01*
X-288615D01*
G01X-282880Y986845D02*
X-281950Y985803D01*
X-280865Y985178D01*
X-279470Y984970D01*
X-278075Y985387D01*
X-276990Y986220D01*
X-276215Y987678D01*
X-276060Y989345D01*
X-276370Y991012D01*
X-277145Y992053D01*
X-278230Y992887D01*
X-279315Y993095D01*
X-280400Y992887D01*
X-281795Y992053D01*
X-281330Y997470D01*
X-277145D01*
G01X-267070Y984970D02*
Y997470D01*
X-268930Y994970D01*
G01Y984970D02*
X-265210D01*
G01X-254670Y984553D02*
X-254980Y984762D01*
Y985178D01*
X-254670Y985387D01*
X-254360Y985178D01*
Y984762D01*
X-254670Y984553D01*
G01X-242580Y984970D02*
X-242270Y987678D01*
X-241805Y989970D01*
X-241185Y992053D01*
X-240410Y994345D01*
X-239170Y997470D01*
X-245370D01*
G01X-230180Y984970D02*
X-229870Y987678D01*
X-229405Y989970D01*
X-228785Y992053D01*
X-228010Y994345D01*
X-226770Y997470D01*
X-232970D01*
G01X-298700Y1423290D02*
X-297770Y1421831D01*
X-296530Y1420998D01*
X-295135Y1420790D01*
X-293895Y1420998D01*
X-292655Y1422040D01*
X-291880Y1423290D01*
X-291725Y1424540D01*
X-292035Y1425998D01*
X-293120Y1427040D01*
X-294205Y1427457D01*
X-295600D01*
G01X-294205D02*
X-293275Y1428082D01*
X-292500Y1429123D01*
X-292190Y1430373D01*
X-292500Y1431623D01*
X-293275Y1432665D01*
X-294670Y1433290D01*
X-296065Y1433082D01*
X-297460Y1432248D01*
G01X-286300Y1422665D02*
X-285370Y1421623D01*
X-284285Y1420998D01*
X-282890Y1420790D01*
X-281495Y1421207D01*
X-280410Y1422040D01*
X-279635Y1423498D01*
X-279480Y1425165D01*
X-279790Y1426832D01*
X-280565Y1427873D01*
X-281650Y1428707D01*
X-282735Y1428915D01*
X-283820Y1428707D01*
X-285215Y1427873D01*
X-284750Y1433290D01*
X-280565D01*
G01X-268630Y1420790D02*
Y1433290D01*
X-274365Y1424332D01*
X-266615D01*
G01X-258090Y1420373D02*
X-258400Y1420582D01*
Y1420998D01*
X-258090Y1421207D01*
X-257780Y1420998D01*
Y1420582D01*
X-258090Y1420373D01*
G01X-243830Y1420790D02*
Y1433290D01*
X-249565Y1424332D01*
X-241815D01*
G01X-236700Y1423290D02*
X-235770Y1421831D01*
X-234530Y1420998D01*
X-233135Y1420790D01*
X-231895Y1420998D01*
X-230655Y1422040D01*
X-229880Y1423290D01*
X-229725Y1424540D01*
X-230035Y1425998D01*
X-231120Y1427040D01*
X-232205Y1427457D01*
X-233600D01*
G01X-232205D02*
X-231275Y1428082D01*
X-230500Y1429123D01*
X-230190Y1430373D01*
X-230500Y1431623D01*
X-231275Y1432665D01*
X-232670Y1433290D01*
X-234065Y1433082D01*
X-235460Y1432248D01*
G01X-297500Y1453370D02*
X-296570Y1451911D01*
X-295330Y1451078D01*
X-293935Y1450870D01*
X-292695Y1451078D01*
X-291455Y1452120D01*
X-290680Y1453370D01*
X-290525Y1454620D01*
X-290835Y1456078D01*
X-291920Y1457120D01*
X-293005Y1457537D01*
X-294400D01*
G01X-293005D02*
X-292075Y1458162D01*
X-291300Y1459203D01*
X-290990Y1460453D01*
X-291300Y1461703D01*
X-292075Y1462745D01*
X-293470Y1463370D01*
X-294865Y1463162D01*
X-296260Y1462328D01*
G01X-284635Y1456078D02*
X-283550Y1457537D01*
X-282620Y1458370D01*
X-281380Y1458787D01*
X-280295Y1458370D01*
X-279520Y1457537D01*
X-278900Y1456287D01*
X-278745Y1454828D01*
X-278900Y1453578D01*
X-279520Y1452328D01*
X-280450Y1451287D01*
X-281535Y1450870D01*
X-282775Y1451287D01*
X-283860Y1452536D01*
X-284480Y1454412D01*
X-284635Y1456495D01*
X-284325Y1459203D01*
X-283860Y1460662D01*
X-283085Y1462120D01*
X-282000Y1463162D01*
X-280915Y1463370D01*
X-279830Y1462953D01*
X-279055Y1461912D01*
G01X-269290Y1463370D02*
X-270530Y1462953D01*
X-271460Y1461912D01*
X-272080Y1460662D01*
X-272545Y1458995D01*
X-272700Y1457120D01*
X-272545Y1455245D01*
X-272080Y1453578D01*
X-271460Y1452328D01*
X-270530Y1451287D01*
X-269290Y1450870D01*
X-268050Y1451287D01*
X-267120Y1452328D01*
X-266500Y1453578D01*
X-266035Y1455245D01*
X-265880Y1457120D01*
X-266035Y1458995D01*
X-266500Y1460662D01*
X-267120Y1461912D01*
X-268050Y1462953D01*
X-269290Y1463370D01*
G01X-256890Y1450453D02*
X-257200Y1450662D01*
Y1451078D01*
X-256890Y1451287D01*
X-256580Y1451078D01*
Y1450662D01*
X-256890Y1450453D01*
G01X-244800Y1450870D02*
X-244490Y1453578D01*
X-244025Y1455870D01*
X-243405Y1457953D01*
X-242630Y1460245D01*
X-241390Y1463370D01*
X-247590D01*
G01X-235035Y1456078D02*
X-233950Y1457537D01*
X-233020Y1458370D01*
X-231780Y1458787D01*
X-230695Y1458370D01*
X-229920Y1457537D01*
X-229300Y1456287D01*
X-229145Y1454828D01*
X-229300Y1453578D01*
X-229920Y1452328D01*
X-230850Y1451287D01*
X-231935Y1450870D01*
X-233175Y1451287D01*
X-234260Y1452536D01*
X-234880Y1454412D01*
X-235035Y1456495D01*
X-234725Y1459203D01*
X-234260Y1460662D01*
X-233485Y1462120D01*
X-232400Y1463162D01*
X-231315Y1463370D01*
X-230230Y1462953D01*
X-229455Y1461912D01*
G01X-291030Y1679470D02*
Y1691970D01*
X-296765Y1683012D01*
X-289015D01*
G01X-283900Y1681970D02*
X-282970Y1680511D01*
X-281730Y1679678D01*
X-280335Y1679470D01*
X-279095Y1679678D01*
X-277855Y1680720D01*
X-277080Y1681970D01*
X-276925Y1683220D01*
X-277235Y1684678D01*
X-278320Y1685720D01*
X-279405Y1686137D01*
X-280800D01*
G01X-279405D02*
X-278475Y1686762D01*
X-277700Y1687803D01*
X-277390Y1689053D01*
X-277700Y1690303D01*
X-278475Y1691345D01*
X-279870Y1691970D01*
X-281265Y1691762D01*
X-282660Y1690928D01*
G01X-268090Y1679470D02*
Y1691970D01*
X-269950Y1689470D01*
G01Y1679470D02*
X-266230D01*
G01X-255690Y1679053D02*
X-256000Y1679262D01*
Y1679678D01*
X-255690Y1679887D01*
X-255380Y1679678D01*
Y1679262D01*
X-255690Y1679053D01*
G01X-246700Y1681970D02*
X-245770Y1680511D01*
X-244530Y1679678D01*
X-243135Y1679470D01*
X-241895Y1679678D01*
X-240655Y1680720D01*
X-239880Y1681970D01*
X-239725Y1683220D01*
X-240035Y1684678D01*
X-241120Y1685720D01*
X-242205Y1686137D01*
X-243600D01*
G01X-242205D02*
X-241275Y1686762D01*
X-240500Y1687803D01*
X-240190Y1689053D01*
X-240500Y1690303D01*
X-241275Y1691345D01*
X-242670Y1691970D01*
X-244065Y1691762D01*
X-245460Y1690928D01*
G01X-233835Y1684678D02*
X-232750Y1686137D01*
X-231820Y1686970D01*
X-230580Y1687387D01*
X-229495Y1686970D01*
X-228720Y1686137D01*
X-228100Y1684887D01*
X-227945Y1683428D01*
X-228100Y1682178D01*
X-228720Y1680928D01*
X-229650Y1679887D01*
X-230735Y1679470D01*
X-231975Y1679887D01*
X-233060Y1681136D01*
X-233680Y1683012D01*
X-233835Y1685095D01*
X-233525Y1687803D01*
X-233060Y1689262D01*
X-232285Y1690720D01*
X-231200Y1691762D01*
X-230115Y1691970D01*
X-229030Y1691553D01*
X-228255Y1690512D01*
G01X-289460Y560500D02*
Y573000D01*
X-291320Y570500D01*
G01Y560500D02*
X-287600D01*
G01X-280470Y562375D02*
X-279540Y561333D01*
X-278455Y560708D01*
X-277060Y560500D01*
X-275665Y560917D01*
X-274580Y561750D01*
X-273805Y563208D01*
X-273650Y564875D01*
X-273960Y566542D01*
X-274735Y567583D01*
X-275820Y568417D01*
X-276905Y568625D01*
X-277990Y568417D01*
X-279385Y567583D01*
X-278920Y573000D01*
X-274735D01*
G01X-268070Y563000D02*
X-267140Y561541D01*
X-265900Y560708D01*
X-264505Y560500D01*
X-263265Y560708D01*
X-262025Y561750D01*
X-261250Y563000D01*
X-261095Y564250D01*
X-261405Y565708D01*
X-262490Y566750D01*
X-263575Y567167D01*
X-264970D01*
G01X-263575D02*
X-262645Y567792D01*
X-261870Y568833D01*
X-261560Y570083D01*
X-261870Y571333D01*
X-262645Y572375D01*
X-264040Y573000D01*
X-265435Y572792D01*
X-266830Y571958D01*
G01X-252260Y560083D02*
X-252570Y560292D01*
Y560708D01*
X-252260Y560917D01*
X-251950Y560708D01*
Y560292D01*
X-252260Y560083D01*
G01X-240170Y560500D02*
X-239860Y563208D01*
X-239395Y565500D01*
X-238775Y567583D01*
X-238000Y569875D01*
X-236760Y573000D01*
X-242960D01*
G01X-227770Y560500D02*
X-227460Y563208D01*
X-226995Y565500D01*
X-226375Y567583D01*
X-225600Y569875D01*
X-224360Y573000D01*
X-230560D01*
G01X-287050Y599205D02*
Y611705D01*
X-288910Y609205D01*
G01Y599205D02*
X-285190D01*
G01X-278060Y601080D02*
X-277130Y600038D01*
X-276045Y599413D01*
X-274650Y599205D01*
X-273255Y599622D01*
X-272170Y600455D01*
X-271395Y601913D01*
X-271240Y603580D01*
X-271550Y605247D01*
X-272325Y606288D01*
X-273410Y607122D01*
X-274495Y607330D01*
X-275580Y607122D01*
X-276975Y606288D01*
X-276510Y611705D01*
X-272325D01*
G01X-265660Y601705D02*
X-264730Y600246D01*
X-263490Y599413D01*
X-262095Y599205D01*
X-260855Y599413D01*
X-259615Y600455D01*
X-258840Y601705D01*
X-258685Y602955D01*
X-258995Y604413D01*
X-260080Y605455D01*
X-261165Y605872D01*
X-262560D01*
G01X-261165D02*
X-260235Y606497D01*
X-259460Y607538D01*
X-259150Y608788D01*
X-259460Y610038D01*
X-260235Y611080D01*
X-261630Y611705D01*
X-263025Y611497D01*
X-264420Y610663D01*
G01X-249850Y598788D02*
X-250160Y598997D01*
Y599413D01*
X-249850Y599622D01*
X-249540Y599413D01*
Y598997D01*
X-249850Y598788D01*
G01X-237760Y599205D02*
X-237450Y601913D01*
X-236985Y604205D01*
X-236365Y606288D01*
X-235590Y608580D01*
X-234350Y611705D01*
X-240550D01*
G01X-227685Y600663D02*
X-226600Y599622D01*
X-225360Y599205D01*
X-224120Y599622D01*
X-223035Y600871D01*
X-222260Y602747D01*
X-221950Y604622D01*
Y606913D01*
X-222260Y608788D01*
X-223035Y610455D01*
X-223965Y611288D01*
X-225050Y611705D01*
X-226290Y611288D01*
X-227220Y610455D01*
X-227840Y609205D01*
X-228150Y607538D01*
X-227840Y606080D01*
X-227065Y604622D01*
X-226135Y603788D01*
X-225050Y603580D01*
X-223810Y603996D01*
X-222880Y605038D01*
X-221950Y606913D01*
G01X-287595Y815288D02*
X-286665Y816537D01*
X-285580Y817163D01*
X-284340Y817371D01*
X-282790Y816954D01*
X-281705Y815913D01*
X-281395Y814663D01*
X-281550Y813412D01*
X-282170Y812371D01*
X-285270Y810288D01*
X-286665Y808829D01*
X-287595Y806746D01*
X-287905Y804871D01*
X-281395D01*
G01X-272250Y817371D02*
X-273490Y816954D01*
X-274420Y815913D01*
X-275040Y814663D01*
X-275505Y812996D01*
X-275660Y811121D01*
X-275505Y809246D01*
X-275040Y807579D01*
X-274420Y806329D01*
X-273490Y805288D01*
X-272250Y804871D01*
X-271010Y805288D01*
X-270080Y806329D01*
X-269460Y807579D01*
X-268995Y809246D01*
X-268840Y811121D01*
X-268995Y812996D01*
X-269460Y814663D01*
X-270080Y815913D01*
X-271010Y816954D01*
X-272250Y817371D01*
G01X-262795Y810079D02*
X-261710Y811538D01*
X-260780Y812371D01*
X-259540Y812788D01*
X-258455Y812371D01*
X-257680Y811538D01*
X-257060Y810288D01*
X-256905Y808829D01*
X-257060Y807579D01*
X-257680Y806329D01*
X-258610Y805288D01*
X-259695Y804871D01*
X-260935Y805288D01*
X-262020Y806537D01*
X-262640Y808413D01*
X-262795Y810496D01*
X-262485Y813204D01*
X-262020Y814663D01*
X-261245Y816121D01*
X-260160Y817163D01*
X-259075Y817371D01*
X-257990Y816954D01*
X-257215Y815913D01*
G01X-247450Y804454D02*
X-247760Y804663D01*
Y805079D01*
X-247450Y805288D01*
X-247140Y805079D01*
Y804663D01*
X-247450Y804454D01*
G01X-235050Y817371D02*
X-236290Y816954D01*
X-237220Y815913D01*
X-237840Y814663D01*
X-238305Y812996D01*
X-238460Y811121D01*
X-238305Y809246D01*
X-237840Y807579D01*
X-237220Y806329D01*
X-236290Y805288D01*
X-235050Y804871D01*
X-233810Y805288D01*
X-232880Y806329D01*
X-232260Y807579D01*
X-231795Y809246D01*
X-231640Y811121D01*
X-231795Y812996D01*
X-232260Y814663D01*
X-232880Y815913D01*
X-233810Y816954D01*
X-235050Y817371D01*
G01X-225595Y815288D02*
X-224665Y816537D01*
X-223580Y817163D01*
X-222340Y817371D01*
X-220790Y816954D01*
X-219705Y815913D01*
X-219395Y814663D01*
X-219550Y813412D01*
X-220170Y812371D01*
X-223270Y810288D01*
X-224665Y808829D01*
X-225595Y806746D01*
X-225905Y804871D01*
X-219395D01*
G01X-291015Y1175485D02*
X-290085Y1176734D01*
X-289000Y1177360D01*
X-287760Y1177568D01*
X-286210Y1177151D01*
X-285125Y1176110D01*
X-284815Y1174860D01*
X-284970Y1173609D01*
X-285590Y1172568D01*
X-288690Y1170485D01*
X-290085Y1169026D01*
X-291015Y1166943D01*
X-291325Y1165068D01*
X-284815D01*
G01X-278305Y1166526D02*
X-277220Y1165485D01*
X-275980Y1165068D01*
X-274740Y1165485D01*
X-273655Y1166734D01*
X-272880Y1168610D01*
X-272570Y1170485D01*
Y1172776D01*
X-272880Y1174651D01*
X-273655Y1176318D01*
X-274585Y1177151D01*
X-275670Y1177568D01*
X-276910Y1177151D01*
X-277840Y1176318D01*
X-278460Y1175068D01*
X-278770Y1173401D01*
X-278460Y1171943D01*
X-277685Y1170485D01*
X-276755Y1169651D01*
X-275670Y1169443D01*
X-274430Y1169859D01*
X-273500Y1170901D01*
X-272570Y1172776D01*
G01X-263580Y1165068D02*
X-263270Y1167776D01*
X-262805Y1170068D01*
X-262185Y1172151D01*
X-261410Y1174443D01*
X-260170Y1177568D01*
X-266370D01*
G01X-250870Y1164651D02*
X-251180Y1164860D01*
Y1165276D01*
X-250870Y1165485D01*
X-250560Y1165276D01*
Y1164860D01*
X-250870Y1164651D01*
G01X-241880Y1166943D02*
X-240950Y1165901D01*
X-239865Y1165276D01*
X-238470Y1165068D01*
X-237075Y1165485D01*
X-235990Y1166318D01*
X-235215Y1167776D01*
X-235060Y1169443D01*
X-235370Y1171110D01*
X-236145Y1172151D01*
X-237230Y1172985D01*
X-238315Y1173193D01*
X-239400Y1172985D01*
X-240795Y1172151D01*
X-240330Y1177568D01*
X-236145D01*
G01X-226070Y1165068D02*
Y1177568D01*
X-227930Y1175068D01*
G01Y1165068D02*
X-224210D01*
G01X-272905Y116175D02*
X-271975Y117424D01*
X-270890Y118050D01*
X-269650Y118258D01*
X-268100Y117841D01*
X-267015Y116800D01*
X-266705Y115550D01*
X-266860Y114299D01*
X-267480Y113258D01*
X-270580Y111175D01*
X-271975Y109716D01*
X-272905Y107633D01*
X-273215Y105758D01*
X-266705D01*
G01X-257560D02*
X-256475Y105966D01*
X-255235Y106591D01*
X-254460Y107633D01*
X-254150Y109091D01*
X-254460Y110549D01*
X-255390Y111800D01*
X-256785Y112425D01*
X-258335D01*
X-259265Y112841D01*
X-260040Y113883D01*
X-260350Y115341D01*
X-259885Y116800D01*
X-258800Y117841D01*
X-257560Y118258D01*
X-256320Y117841D01*
X-255235Y116800D01*
X-254770Y115341D01*
X-255080Y113883D01*
X-255855Y112841D01*
X-256785Y112425D01*
X-258335D01*
X-259730Y111800D01*
X-260660Y110549D01*
X-260970Y109091D01*
X-260660Y107633D01*
X-259885Y106591D01*
X-258645Y105966D01*
X-257560Y105758D01*
G01X-245160Y105341D02*
X-245470Y105550D01*
Y105966D01*
X-245160Y106175D01*
X-244850Y105966D01*
Y105550D01*
X-245160Y105341D01*
G01X-230900Y105758D02*
Y118258D01*
X-236635Y109300D01*
X-228885D01*
G01X-223770Y107633D02*
X-222840Y106591D01*
X-221755Y105966D01*
X-220360Y105758D01*
X-218965Y106175D01*
X-217880Y107008D01*
X-217105Y108466D01*
X-216950Y110133D01*
X-217260Y111800D01*
X-218035Y112841D01*
X-219120Y113675D01*
X-220205Y113883D01*
X-221290Y113675D01*
X-222685Y112841D01*
X-222220Y118258D01*
X-218035D01*
G01X-267500Y178986D02*
Y191486D01*
X-273235Y182528D01*
X-265485D01*
G01X-257270Y178986D02*
X-256960Y181694D01*
X-256495Y183986D01*
X-255875Y186069D01*
X-255100Y188361D01*
X-253860Y191486D01*
X-260060D01*
G01X-244560Y178569D02*
X-244870Y178778D01*
Y179194D01*
X-244560Y179403D01*
X-244250Y179194D01*
Y178778D01*
X-244560Y178569D01*
G01X-232160Y191486D02*
X-233400Y191069D01*
X-234330Y190028D01*
X-234950Y188778D01*
X-235415Y187111D01*
X-235570Y185236D01*
X-235415Y183361D01*
X-234950Y181694D01*
X-234330Y180444D01*
X-233400Y179403D01*
X-232160Y178986D01*
X-230920Y179403D01*
X-229990Y180444D01*
X-229370Y181694D01*
X-228905Y183361D01*
X-228750Y185236D01*
X-228905Y187111D01*
X-229370Y188778D01*
X-229990Y190028D01*
X-230920Y191069D01*
X-232160Y191486D01*
G01X-223170Y180861D02*
X-222240Y179819D01*
X-221155Y179194D01*
X-219760Y178986D01*
X-218365Y179403D01*
X-217280Y180236D01*
X-216505Y181694D01*
X-216350Y183361D01*
X-216660Y185028D01*
X-217435Y186069D01*
X-218520Y186903D01*
X-219605Y187111D01*
X-220690Y186903D01*
X-222085Y186069D01*
X-221620Y191486D01*
X-217435D01*
G01X-272905Y268446D02*
X-271820Y269905D01*
X-270890Y270738D01*
X-269650Y271155D01*
X-268565Y270738D01*
X-267790Y269905D01*
X-267170Y268655D01*
X-267015Y267196D01*
X-267170Y265946D01*
X-267790Y264696D01*
X-268720Y263655D01*
X-269805Y263238D01*
X-271045Y263655D01*
X-272130Y264904D01*
X-272750Y266780D01*
X-272905Y268863D01*
X-272595Y271571D01*
X-272130Y273030D01*
X-271355Y274488D01*
X-270270Y275530D01*
X-269185Y275738D01*
X-268100Y275321D01*
X-267325Y274280D01*
G01X-257560Y263238D02*
X-256475Y263446D01*
X-255235Y264071D01*
X-254460Y265113D01*
X-254150Y266571D01*
X-254460Y268029D01*
X-255390Y269280D01*
X-256785Y269905D01*
X-258335D01*
X-259265Y270321D01*
X-260040Y271363D01*
X-260350Y272821D01*
X-259885Y274280D01*
X-258800Y275321D01*
X-257560Y275738D01*
X-256320Y275321D01*
X-255235Y274280D01*
X-254770Y272821D01*
X-255080Y271363D01*
X-255855Y270321D01*
X-256785Y269905D01*
X-258335D01*
X-259730Y269280D01*
X-260660Y268029D01*
X-260970Y266571D01*
X-260660Y265113D01*
X-259885Y264071D01*
X-258645Y263446D01*
X-257560Y263238D01*
G01X-245160Y262821D02*
X-245470Y263030D01*
Y263446D01*
X-245160Y263655D01*
X-244850Y263446D01*
Y263030D01*
X-245160Y262821D01*
G01X-230900Y263238D02*
Y275738D01*
X-236635Y266780D01*
X-228885D01*
G01X-223770Y265113D02*
X-222840Y264071D01*
X-221755Y263446D01*
X-220360Y263238D01*
X-218965Y263655D01*
X-217880Y264488D01*
X-217105Y265946D01*
X-216950Y267613D01*
X-217260Y269280D01*
X-218035Y270321D01*
X-219120Y271155D01*
X-220205Y271363D01*
X-221290Y271155D01*
X-222685Y270321D01*
X-222220Y275738D01*
X-218035D01*
G01X-271540Y287520D02*
X-271230Y290228D01*
X-270765Y292520D01*
X-270145Y294603D01*
X-269370Y296895D01*
X-268130Y300020D01*
X-274330D01*
G01X-258830D02*
X-260070Y299603D01*
X-261000Y298562D01*
X-261620Y297312D01*
X-262085Y295645D01*
X-262240Y293770D01*
X-262085Y291895D01*
X-261620Y290228D01*
X-261000Y288978D01*
X-260070Y287937D01*
X-258830Y287520D01*
X-257590Y287937D01*
X-256660Y288978D01*
X-256040Y290228D01*
X-255575Y291895D01*
X-255420Y293770D01*
X-255575Y295645D01*
X-256040Y297312D01*
X-256660Y298562D01*
X-257590Y299603D01*
X-258830Y300020D01*
G01X-246430Y287103D02*
X-246740Y287312D01*
Y287728D01*
X-246430Y287937D01*
X-246120Y287728D01*
Y287312D01*
X-246430Y287103D01*
G01X-232170Y287520D02*
Y300020D01*
X-237905Y291062D01*
X-230155D01*
G01X-224575Y297937D02*
X-223645Y299186D01*
X-222560Y299812D01*
X-221320Y300020D01*
X-219770Y299603D01*
X-218685Y298562D01*
X-218375Y297312D01*
X-218530Y296061D01*
X-219150Y295020D01*
X-222250Y292937D01*
X-223645Y291478D01*
X-224575Y289395D01*
X-224885Y287520D01*
X-218375D01*
G01X-256610Y315403D02*
X-255525Y315611D01*
X-254285Y316236D01*
X-253510Y317278D01*
X-253200Y318736D01*
X-253510Y320194D01*
X-254440Y321445D01*
X-255835Y322070D01*
X-257385D01*
X-258315Y322486D01*
X-259090Y323528D01*
X-259400Y324986D01*
X-258935Y326445D01*
X-257850Y327486D01*
X-256610Y327903D01*
X-255370Y327486D01*
X-254285Y326445D01*
X-253820Y324986D01*
X-254130Y323528D01*
X-254905Y322486D01*
X-255835Y322070D01*
X-257385D01*
X-258780Y321445D01*
X-259710Y320194D01*
X-260020Y318736D01*
X-259710Y317278D01*
X-258935Y316236D01*
X-257695Y315611D01*
X-256610Y315403D01*
G01X-244210D02*
Y327903D01*
X-246070Y325403D01*
G01Y315403D02*
X-242350D01*
G01X-231810Y314986D02*
X-232120Y315195D01*
Y315611D01*
X-231810Y315820D01*
X-231500Y315611D01*
Y315195D01*
X-231810Y314986D01*
G01X-219720Y315403D02*
X-219410Y318111D01*
X-218945Y320403D01*
X-218325Y322486D01*
X-217550Y324778D01*
X-216310Y327903D01*
X-222510D01*
G01X-235520Y200349D02*
X-234590Y199307D01*
X-233505Y198682D01*
X-232110Y198474D01*
X-230715Y198891D01*
X-229630Y199724D01*
X-228855Y201182D01*
X-228700Y202849D01*
X-229010Y204516D01*
X-229785Y205557D01*
X-230870Y206391D01*
X-231955Y206599D01*
X-233040Y206391D01*
X-234435Y205557D01*
X-233970Y210974D01*
X-229785D01*
G01X-222655Y208891D02*
X-221725Y210140D01*
X-220640Y210766D01*
X-219400Y210974D01*
X-217850Y210557D01*
X-216765Y209516D01*
X-216455Y208266D01*
X-216610Y207015D01*
X-217230Y205974D01*
X-220330Y203891D01*
X-221725Y202432D01*
X-222655Y200349D01*
X-222965Y198474D01*
X-216455D01*
G01X-221760Y-6250D02*
X-223000Y-6667D01*
X-223930Y-7708D01*
X-224550Y-8958D01*
X-225015Y-10625D01*
X-225170Y-12500D01*
X-225015Y-14375D01*
X-224550Y-16042D01*
X-223930Y-17292D01*
X-223000Y-18333D01*
X-221760Y-18750D01*
X-220520Y-18333D01*
X-219590Y-17292D01*
X-218970Y-16042D01*
X-218505Y-14375D01*
X-218350Y-12500D01*
X-218505Y-10625D01*
X-218970Y-8958D01*
X-219590Y-7708D01*
X-220520Y-6667D01*
X-221760Y-6250D01*
G01X-221910Y18750D02*
X-223150Y18333D01*
X-224080Y17292D01*
X-224700Y16042D01*
X-225165Y14375D01*
X-225320Y12500D01*
X-225165Y10625D01*
X-224700Y8958D01*
X-224080Y7708D01*
X-223150Y6667D01*
X-221910Y6250D01*
X-220670Y6667D01*
X-219740Y7708D01*
X-219120Y8958D01*
X-218655Y10625D01*
X-218500Y12500D01*
X-218655Y14375D01*
X-219120Y16042D01*
X-219740Y17292D01*
X-220670Y18333D01*
X-221910Y18750D01*
G01X-6250Y-231060D02*
X-5833Y-232300D01*
X-4792Y-233230D01*
X-3542Y-233850D01*
X-1875Y-234315D01*
X0Y-234470D01*
X1875Y-234315D01*
X3542Y-233850D01*
X4792Y-233230D01*
X5833Y-232300D01*
X6250Y-231060D01*
X5833Y-229820D01*
X4792Y-228890D01*
X3542Y-228270D01*
X1875Y-227805D01*
X0Y-227650D01*
X-1875Y-227805D01*
X-3542Y-228270D01*
X-4792Y-228890D01*
X-5833Y-229820D01*
X-6250Y-231060D01*
G01Y-196460D02*
X-5833Y-197700D01*
X-4792Y-198630D01*
X-3542Y-199250D01*
X-1875Y-199715D01*
X0Y-199870D01*
X1875Y-199715D01*
X3542Y-199250D01*
X4792Y-198630D01*
X5833Y-197700D01*
X6250Y-196460D01*
X5833Y-195220D01*
X4792Y-194290D01*
X3542Y-193670D01*
X1875Y-193205D01*
X0Y-193050D01*
X-1875Y-193205D01*
X-3542Y-193670D01*
X-4792Y-194290D01*
X-5833Y-195220D01*
X-6250Y-196460D01*
G01X7723Y-521204D02*
X7253Y-520889D01*
X6705Y-520679D01*
X6078D01*
X5373Y-520994D01*
X4825Y-521519D01*
X4433Y-522149D01*
X4120Y-523199D01*
X4042Y-524144D01*
X4198Y-525089D01*
X4433Y-525719D01*
X4903Y-526349D01*
X5452Y-526769D01*
X6000Y-526979D01*
X6548D01*
X7097Y-526769D01*
X7567Y-526454D01*
X7958Y-526034D01*
G01X11360Y-520679D02*
X13240D01*
G01X12300D02*
Y-526979D01*
G01X11360D02*
X13240D01*
G01X18600Y-520679D02*
Y-526979D01*
G01X16798Y-520679D02*
X20402D01*
G01X24900Y-526979D02*
Y-524144D01*
X23333Y-520679D01*
G01X26467D02*
X24900Y-524144D01*
G01X35777Y-525719D02*
X36247Y-526454D01*
X36873Y-526874D01*
X37578Y-526979D01*
X38205Y-526874D01*
X38832Y-526349D01*
X39223Y-525719D01*
X39302Y-525089D01*
X39145Y-524354D01*
X38597Y-523829D01*
X38048Y-523619D01*
X37343D01*
G01X38048D02*
X38518Y-523304D01*
X38910Y-522779D01*
X39067Y-522149D01*
X38910Y-521519D01*
X38518Y-520994D01*
X37813Y-520679D01*
X37108Y-520784D01*
X36403Y-521204D01*
G01X42077Y-525719D02*
X42547Y-526454D01*
X43173Y-526874D01*
X43878Y-526979D01*
X44505Y-526874D01*
X45132Y-526349D01*
X45523Y-525719D01*
X45602Y-525089D01*
X45445Y-524354D01*
X44897Y-523829D01*
X44348Y-523619D01*
X43643D01*
G01X44348D02*
X44818Y-523304D01*
X45210Y-522779D01*
X45367Y-522149D01*
X45210Y-521519D01*
X44818Y-520994D01*
X44113Y-520679D01*
X43408Y-520784D01*
X42703Y-521204D01*
G01X48377Y-525719D02*
X48847Y-526454D01*
X49473Y-526874D01*
X50178Y-526979D01*
X50805Y-526874D01*
X51432Y-526349D01*
X51823Y-525719D01*
X51902Y-525089D01*
X51745Y-524354D01*
X51197Y-523829D01*
X50648Y-523619D01*
X49943D01*
G01X50648D02*
X51118Y-523304D01*
X51510Y-522779D01*
X51667Y-522149D01*
X51510Y-521519D01*
X51118Y-520994D01*
X50413Y-520679D01*
X49708Y-520784D01*
X49003Y-521204D01*
G01X56243Y-526979D02*
X56400Y-525614D01*
X56635Y-524459D01*
X56948Y-523409D01*
X57340Y-522254D01*
X57967Y-520679D01*
X54833D01*
G01X62543Y-526979D02*
X62700Y-525614D01*
X62935Y-524459D01*
X63248Y-523409D01*
X63640Y-522254D01*
X64267Y-520679D01*
X61133D01*
G01X68843Y-528134D02*
X69157Y-526769D01*
G01X75300Y-520679D02*
Y-526979D01*
G01X73498Y-520679D02*
X77102D01*
G01X79642Y-526979D02*
X81600Y-520679D01*
X83558Y-526979D01*
G01X82853Y-524774D02*
X80347D01*
G01X86960Y-520679D02*
X88840D01*
G01X87900D02*
Y-526979D01*
G01X86960D02*
X88840D01*
G01X91850Y-520679D02*
X92947Y-526979D01*
X94200Y-520679D01*
X95453Y-526979D01*
X96550Y-520679D01*
G01X98542Y-526979D02*
X100500Y-520679D01*
X102458Y-526979D01*
G01X101753Y-524774D02*
X99247D01*
G01X104998Y-526979D02*
Y-520679D01*
X108602Y-526979D01*
Y-520679D01*
G01X119008Y-529079D02*
X118225Y-528029D01*
X117833Y-526979D01*
Y-522779D01*
X118225Y-521729D01*
X119008Y-520679D01*
G01X130433Y-526979D02*
Y-520679D01*
X132392D01*
X133018Y-520994D01*
X133410Y-521414D01*
X133567Y-522254D01*
X133410Y-523094D01*
X132940Y-523619D01*
X132392Y-523934D01*
X130433D01*
G01X132392D02*
X133567Y-526979D01*
G01X138300Y-527189D02*
X138143Y-527084D01*
Y-526874D01*
X138300Y-526769D01*
X138457Y-526874D01*
Y-527084D01*
X138300Y-527189D01*
G01X144600Y-526979D02*
X143973Y-526874D01*
X143425Y-526454D01*
X142955Y-525824D01*
X142642Y-525089D01*
X142485Y-524249D01*
Y-523409D01*
X142642Y-522569D01*
X142955Y-521834D01*
X143425Y-521204D01*
X143973Y-520784D01*
X144600Y-520679D01*
X145227Y-520784D01*
X145775Y-521204D01*
X146245Y-521834D01*
X146558Y-522569D01*
X146715Y-523409D01*
Y-524249D01*
X146558Y-525089D01*
X146245Y-525824D01*
X145775Y-526454D01*
X145227Y-526874D01*
X144600Y-526979D01*
G01X150900Y-527189D02*
X150743Y-527084D01*
Y-526874D01*
X150900Y-526769D01*
X151057Y-526874D01*
Y-527084D01*
X150900Y-527189D01*
G01X158923Y-521204D02*
X158453Y-520889D01*
X157905Y-520679D01*
X157278D01*
X156573Y-520994D01*
X156025Y-521519D01*
X155633Y-522149D01*
X155320Y-523199D01*
X155242Y-524144D01*
X155398Y-525089D01*
X155633Y-525719D01*
X156103Y-526349D01*
X156652Y-526769D01*
X157200Y-526979D01*
X157748D01*
X158297Y-526769D01*
X158767Y-526454D01*
X159158Y-526034D01*
G01X163500Y-527189D02*
X163343Y-527084D01*
Y-526874D01*
X163500Y-526769D01*
X163657Y-526874D01*
Y-527084D01*
X163500Y-527189D01*
G01X170192Y-529079D02*
X170975Y-528029D01*
X171367Y-526979D01*
Y-522779D01*
X170975Y-521729D01*
X170192Y-520679D01*
G01X6470Y-513829D02*
X8037D01*
Y-515719D01*
X7567Y-516349D01*
X7018Y-516769D01*
X6235Y-516979D01*
X5452Y-516769D01*
X4903Y-516349D01*
X4433Y-515719D01*
X4120Y-514984D01*
X3963Y-514144D01*
Y-513409D01*
X4120Y-512779D01*
X4433Y-512044D01*
X4903Y-511414D01*
X5373Y-510994D01*
X6000Y-510679D01*
X6548D01*
X7175Y-510889D01*
X7645Y-511309D01*
G01X10577Y-510679D02*
Y-515194D01*
X10890Y-516139D01*
X11517Y-516769D01*
X12300Y-516979D01*
X13083Y-516769D01*
X13710Y-516139D01*
X14023Y-515194D01*
Y-510679D01*
G01X17660D02*
X19540D01*
G01X18600D02*
Y-516979D01*
G01X17660D02*
X19540D01*
G01X23255Y-516139D02*
X23882Y-516664D01*
X24587Y-516979D01*
X25213D01*
X25840Y-516664D01*
X26310Y-516139D01*
X26545Y-515404D01*
X26388Y-514669D01*
X25997Y-514039D01*
X25292Y-513619D01*
X24352Y-513409D01*
X23803Y-512989D01*
X23568Y-512254D01*
X23725Y-511519D01*
X24117Y-510994D01*
X24665Y-510679D01*
X25213D01*
X25762Y-510889D01*
X26232Y-511414D01*
G01X29555Y-516979D02*
Y-510679D01*
G01X32845D02*
Y-516979D01*
G01Y-513829D02*
X29555D01*
G01X35542Y-516979D02*
X37500Y-510679D01*
X39458Y-516979D01*
G01X38753Y-514774D02*
X36247D01*
G01X41998Y-516979D02*
Y-510679D01*
X45602Y-516979D01*
Y-510679D01*
G01X54677Y-516979D02*
Y-510679D01*
X56243D01*
X56870Y-510994D01*
X57340Y-511414D01*
X57732Y-512044D01*
X58045Y-512779D01*
X58123Y-513829D01*
X58045Y-514879D01*
X57732Y-515614D01*
X57340Y-516244D01*
X56870Y-516664D01*
X56243Y-516979D01*
X54677D01*
G01X61760Y-510679D02*
X63640D01*
G01X62700D02*
Y-516979D01*
G01X61760D02*
X63640D01*
G01X67355Y-516139D02*
X67982Y-516664D01*
X68687Y-516979D01*
X69313D01*
X69940Y-516664D01*
X70410Y-516139D01*
X70645Y-515404D01*
X70488Y-514669D01*
X70097Y-514039D01*
X69392Y-513619D01*
X68452Y-513409D01*
X67903Y-512989D01*
X67668Y-512254D01*
X67825Y-511519D01*
X68217Y-510994D01*
X68765Y-510679D01*
X69313D01*
X69862Y-510889D01*
X70332Y-511414D01*
G01X75300Y-510679D02*
Y-516979D01*
G01X73498Y-510679D02*
X77102D01*
G01X81600Y-517189D02*
X81443Y-517084D01*
Y-516874D01*
X81600Y-516769D01*
X81757Y-516874D01*
Y-517084D01*
X81600Y-517189D01*
G01X87743Y-518134D02*
X88057Y-516769D01*
G01X94200Y-510679D02*
Y-516979D01*
G01X92398Y-510679D02*
X96002D01*
G01X98542Y-516979D02*
X100500Y-510679D01*
X102458Y-516979D01*
G01X101753Y-514774D02*
X99247D01*
G01X106800Y-516979D02*
X106173Y-516874D01*
X105625Y-516454D01*
X105155Y-515824D01*
X104842Y-515089D01*
X104685Y-514249D01*
Y-513409D01*
X104842Y-512569D01*
X105155Y-511834D01*
X105625Y-511204D01*
X106173Y-510784D01*
X106800Y-510679D01*
X107427Y-510784D01*
X107975Y-511204D01*
X108445Y-511834D01*
X108758Y-512569D01*
X108915Y-513409D01*
Y-514249D01*
X108758Y-515089D01*
X108445Y-515824D01*
X107975Y-516454D01*
X107427Y-516874D01*
X106800Y-516979D01*
G01X113100D02*
Y-514144D01*
X111533Y-510679D01*
G01X114667D02*
X113100Y-514144D01*
G01X117677Y-510679D02*
Y-515194D01*
X117990Y-516139D01*
X118617Y-516769D01*
X119400Y-516979D01*
X120183Y-516769D01*
X120810Y-516139D01*
X121123Y-515194D01*
Y-510679D01*
G01X123742Y-516979D02*
X125700Y-510679D01*
X127658Y-516979D01*
G01X126953Y-514774D02*
X124447D01*
G01X130198Y-516979D02*
Y-510679D01*
X133802Y-516979D01*
Y-510679D01*
G01X4198Y-506979D02*
Y-500679D01*
X7802Y-506979D01*
Y-500679D01*
G01X12300Y-506979D02*
X11673Y-506874D01*
X11125Y-506454D01*
X10655Y-505824D01*
X10342Y-505089D01*
X10185Y-504249D01*
Y-503409D01*
X10342Y-502569D01*
X10655Y-501834D01*
X11125Y-501204D01*
X11673Y-500784D01*
X12300Y-500679D01*
X12927Y-500784D01*
X13475Y-501204D01*
X13945Y-501834D01*
X14258Y-502569D01*
X14415Y-503409D01*
Y-504249D01*
X14258Y-505089D01*
X13945Y-505824D01*
X13475Y-506454D01*
X12927Y-506874D01*
X12300Y-506979D01*
G01X18600Y-507189D02*
X18443Y-507084D01*
Y-506874D01*
X18600Y-506769D01*
X18757Y-506874D01*
Y-507084D01*
X18600Y-507189D01*
G01X23412Y-501729D02*
X23882Y-501099D01*
X24430Y-500784D01*
X25057Y-500679D01*
X25840Y-500889D01*
X26388Y-501414D01*
X26545Y-502044D01*
X26467Y-502674D01*
X26153Y-503199D01*
X24587Y-504249D01*
X23882Y-504984D01*
X23412Y-506034D01*
X23255Y-506979D01*
X26545D01*
G01X31200D02*
Y-500679D01*
X30260Y-501939D01*
G01Y-506979D02*
X32140D01*
G01X37500D02*
Y-500679D01*
X36560Y-501939D01*
G01Y-506979D02*
X38440D01*
G01X43643Y-508134D02*
X43957Y-506769D01*
G01X47750Y-500679D02*
X48847Y-506979D01*
X50100Y-500679D01*
X51353Y-506979D01*
X52450Y-500679D01*
G01X57967Y-506979D02*
X54833D01*
Y-500679D01*
X57967D01*
G01X56713Y-503724D02*
X54833D01*
G01X60898Y-506979D02*
Y-500679D01*
X64502Y-506979D01*
Y-500679D01*
G01X67355Y-506979D02*
Y-500679D01*
G01X70645D02*
Y-506979D01*
G01Y-503829D02*
X67355D01*
G01X73577Y-500679D02*
Y-505194D01*
X73890Y-506139D01*
X74517Y-506769D01*
X75300Y-506979D01*
X76083Y-506769D01*
X76710Y-506139D01*
X77023Y-505194D01*
Y-500679D01*
G01X79642Y-506979D02*
X81600Y-500679D01*
X83558Y-506979D01*
G01X82853Y-504774D02*
X80347D01*
G01X92712Y-501729D02*
X93182Y-501099D01*
X93730Y-500784D01*
X94357Y-500679D01*
X95140Y-500889D01*
X95688Y-501414D01*
X95845Y-502044D01*
X95767Y-502674D01*
X95453Y-503199D01*
X93887Y-504249D01*
X93182Y-504984D01*
X92712Y-506034D01*
X92555Y-506979D01*
X95845D01*
G01X98698D02*
Y-500679D01*
X102302Y-506979D01*
Y-500679D01*
G01X105077Y-506979D02*
Y-500679D01*
X106643D01*
X107270Y-500994D01*
X107740Y-501414D01*
X108132Y-502044D01*
X108445Y-502779D01*
X108523Y-503829D01*
X108445Y-504879D01*
X108132Y-505614D01*
X107740Y-506244D01*
X107270Y-506664D01*
X106643Y-506979D01*
X105077D01*
G01X117833D02*
Y-500679D01*
X119792D01*
X120418Y-500994D01*
X120810Y-501414D01*
X120967Y-502254D01*
X120810Y-503094D01*
X120340Y-503619D01*
X119792Y-503934D01*
X117833D01*
G01X119792D02*
X120967Y-506979D01*
G01X123977D02*
Y-500679D01*
X125543D01*
X126170Y-500994D01*
X126640Y-501414D01*
X127032Y-502044D01*
X127345Y-502779D01*
X127423Y-503829D01*
X127345Y-504879D01*
X127032Y-505614D01*
X126640Y-506244D01*
X126170Y-506664D01*
X125543Y-506979D01*
X123977D01*
G01X132000Y-507189D02*
X131843Y-507084D01*
Y-506874D01*
X132000Y-506769D01*
X132157Y-506874D01*
Y-507084D01*
X132000Y-507189D01*
G01X28300Y-494279D02*
X25780Y-493862D01*
X23575Y-492196D01*
X21685Y-489696D01*
X20425Y-486779D01*
X19795Y-483446D01*
Y-480112D01*
X20425Y-476779D01*
X21685Y-473862D01*
X23575Y-471363D01*
X25780Y-469696D01*
X28300Y-469279D01*
X30820Y-469696D01*
X33025Y-471363D01*
X34915Y-473862D01*
X36175Y-476779D01*
X36805Y-480112D01*
Y-483446D01*
X36175Y-486779D01*
X34915Y-489696D01*
X33025Y-492196D01*
X30820Y-493862D01*
X28300Y-494279D01*
G01X30820Y-487612D02*
X34600Y-494279D01*
G01X48145Y-477613D02*
Y-489279D01*
X49405Y-492196D01*
X51295Y-493862D01*
X53500Y-494279D01*
X55705Y-493862D01*
X57595Y-492196D01*
X58855Y-489279D01*
G01Y-494279D02*
Y-477613D01*
G01X84370Y-494279D02*
Y-477613D01*
G01Y-480529D02*
X83110Y-478863D01*
X81220Y-478029D01*
X79015Y-477613D01*
X76810Y-478446D01*
X74920Y-480112D01*
X73660Y-482613D01*
X73030Y-485946D01*
X73660Y-489279D01*
X74920Y-491780D01*
X76810Y-493446D01*
X79015Y-494279D01*
X81220Y-493862D01*
X83110Y-492613D01*
X84370Y-490946D01*
G01X98545Y-494279D02*
Y-477613D01*
G01Y-481779D02*
X99805Y-479696D01*
X101695Y-478029D01*
X104215Y-477613D01*
X106420Y-478029D01*
X108310Y-479696D01*
X109255Y-482613D01*
Y-494279D01*
G01X129100Y-469279D02*
Y-494279D01*
G01X124690Y-477613D02*
X133510D01*
G01X159970Y-494279D02*
Y-477613D01*
G01Y-480529D02*
X158710Y-478863D01*
X156820Y-478029D01*
X154615Y-477613D01*
X152410Y-478446D01*
X150520Y-480112D01*
X149260Y-482613D01*
X148630Y-485946D01*
X149260Y-489279D01*
X150520Y-491780D01*
X152410Y-493446D01*
X154615Y-494279D01*
X156820Y-493862D01*
X158710Y-492613D01*
X159970Y-490946D01*
G01X28274Y-328361D02*
X15774D01*
X18274Y-330221D01*
G01X28274D02*
Y-326501D01*
G01X25774Y-319371D02*
X27233Y-318441D01*
X28066Y-317201D01*
X28274Y-315806D01*
X28066Y-314566D01*
X27024Y-313326D01*
X25774Y-312551D01*
X24524Y-312396D01*
X23066Y-312706D01*
X22024Y-313791D01*
X21607Y-314876D01*
Y-316271D01*
G01Y-314876D02*
X20982Y-313946D01*
X19941Y-313171D01*
X18691Y-312861D01*
X17441Y-313171D01*
X16399Y-313946D01*
X15774Y-315341D01*
X15982Y-316736D01*
X16816Y-318131D01*
G01X28274Y-303871D02*
X25566Y-303561D01*
X23274Y-303096D01*
X21191Y-302476D01*
X18899Y-301701D01*
X15774Y-300461D01*
Y-306661D01*
G01X28691Y-291161D02*
X28482Y-291471D01*
X28066D01*
X27857Y-291161D01*
X28066Y-290851D01*
X28482D01*
X28691Y-291161D01*
G01X28274Y-279071D02*
X25566Y-278761D01*
X23274Y-278296D01*
X21191Y-277676D01*
X18899Y-276901D01*
X15774Y-275661D01*
Y-281861D01*
G01X26816Y-268996D02*
X27857Y-267911D01*
X28274Y-266671D01*
X27857Y-265431D01*
X26608Y-264346D01*
X24732Y-263571D01*
X22857Y-263261D01*
X20566D01*
X18691Y-263571D01*
X17024Y-264346D01*
X16191Y-265276D01*
X15774Y-266361D01*
X16191Y-267601D01*
X17024Y-268531D01*
X18274Y-269151D01*
X19941Y-269461D01*
X21399Y-269151D01*
X22857Y-268376D01*
X23691Y-267446D01*
X23899Y-266361D01*
X23483Y-265121D01*
X22441Y-264191D01*
X20566Y-263261D01*
G01X25774Y-235171D02*
X27233Y-234241D01*
X28066Y-233001D01*
X28274Y-231606D01*
X28066Y-230366D01*
X27024Y-229126D01*
X25774Y-228351D01*
X24524Y-228196D01*
X23066Y-228506D01*
X22024Y-229591D01*
X21607Y-230676D01*
Y-232071D01*
G01Y-230676D02*
X20982Y-229746D01*
X19941Y-228971D01*
X18691Y-228661D01*
X17441Y-228971D01*
X16399Y-229746D01*
X15774Y-231141D01*
X15982Y-232536D01*
X16816Y-233931D01*
G01X28691Y-219361D02*
X28482Y-219671D01*
X28066D01*
X27857Y-219361D01*
X28066Y-219051D01*
X28482D01*
X28691Y-219361D01*
G01X26399Y-210371D02*
X27441Y-209441D01*
X28066Y-208356D01*
X28274Y-206961D01*
X27857Y-205566D01*
X27024Y-204481D01*
X25566Y-203706D01*
X23899Y-203551D01*
X22232Y-203861D01*
X21191Y-204636D01*
X20357Y-205721D01*
X20149Y-206806D01*
X20357Y-207891D01*
X21191Y-209286D01*
X15774Y-208821D01*
Y-204636D01*
G01X38145Y1450622D02*
Y1458122D01*
X42439Y1450622D01*
Y1458122D01*
G01X45925Y1450622D02*
Y1458122D01*
X48165D01*
X48912Y1457747D01*
X49472Y1456872D01*
X49659Y1455872D01*
X49472Y1454872D01*
X49005Y1454122D01*
X48165Y1453747D01*
X45925D01*
G01X55292Y1458122D02*
Y1450622D01*
G01X53145Y1458122D02*
X57439D01*
G01X60832Y1450622D02*
Y1458122D01*
G01X64752D02*
Y1450622D01*
G01Y1454372D02*
X60832D01*
G01X59249Y-343320D02*
X60708Y-342390D01*
X61541Y-341150D01*
X61749Y-339755D01*
X61541Y-338515D01*
X60499Y-337275D01*
X59249Y-336500D01*
X57999Y-336345D01*
X56541Y-336655D01*
X55499Y-337740D01*
X55082Y-338825D01*
Y-340220D01*
G01Y-338825D02*
X54457Y-337895D01*
X53416Y-337120D01*
X52166Y-336810D01*
X50916Y-337120D01*
X49874Y-337895D01*
X49249Y-339290D01*
X49457Y-340685D01*
X50291Y-342080D01*
G01X61749Y-327510D02*
X61541Y-326425D01*
X60916Y-325185D01*
X59874Y-324410D01*
X58416Y-324100D01*
X56958Y-324410D01*
X55707Y-325340D01*
X55082Y-326735D01*
Y-328285D01*
X54666Y-329215D01*
X53624Y-329990D01*
X52166Y-330300D01*
X50707Y-329835D01*
X49666Y-328750D01*
X49249Y-327510D01*
X49666Y-326270D01*
X50707Y-325185D01*
X52166Y-324720D01*
X53624Y-325030D01*
X54666Y-325805D01*
X55082Y-326735D01*
Y-328285D01*
X55707Y-329680D01*
X56958Y-330610D01*
X58416Y-330920D01*
X59874Y-330610D01*
X60916Y-329835D01*
X61541Y-328595D01*
X61749Y-327510D01*
G01X59249Y-318520D02*
X60708Y-317590D01*
X61541Y-316350D01*
X61749Y-314955D01*
X61541Y-313715D01*
X60499Y-312475D01*
X59249Y-311700D01*
X57999Y-311545D01*
X56541Y-311855D01*
X55499Y-312940D01*
X55082Y-314025D01*
Y-315420D01*
G01Y-314025D02*
X54457Y-313095D01*
X53416Y-312320D01*
X52166Y-312010D01*
X50916Y-312320D01*
X49874Y-313095D01*
X49249Y-314490D01*
X49457Y-315885D01*
X50291Y-317280D01*
G01X62166Y-302710D02*
X61957Y-303020D01*
X61541D01*
X61332Y-302710D01*
X61541Y-302400D01*
X61957D01*
X62166Y-302710D01*
G01X61749Y-288450D02*
X49249D01*
X58207Y-294185D01*
Y-286435D01*
G01X56541Y-280855D02*
X55082Y-279770D01*
X54249Y-278840D01*
X53832Y-277600D01*
X54249Y-276515D01*
X55082Y-275740D01*
X56332Y-275120D01*
X57791Y-274965D01*
X59041Y-275120D01*
X60291Y-275740D01*
X61332Y-276670D01*
X61749Y-277755D01*
X61332Y-278995D01*
X60083Y-280080D01*
X58207Y-280700D01*
X56124Y-280855D01*
X53416Y-280545D01*
X51957Y-280080D01*
X50499Y-279305D01*
X49457Y-278220D01*
X49249Y-277135D01*
X49666Y-276050D01*
X50707Y-275275D01*
G01X60291Y-245945D02*
X61332Y-244860D01*
X61749Y-243620D01*
X61332Y-242380D01*
X60083Y-241295D01*
X58207Y-240520D01*
X56332Y-240210D01*
X54041D01*
X52166Y-240520D01*
X50499Y-241295D01*
X49666Y-242225D01*
X49249Y-243310D01*
X49666Y-244550D01*
X50499Y-245480D01*
X51749Y-246100D01*
X53416Y-246410D01*
X54874Y-246100D01*
X56332Y-245325D01*
X57166Y-244395D01*
X57374Y-243310D01*
X56958Y-242070D01*
X55916Y-241140D01*
X54041Y-240210D01*
G01X62166Y-230910D02*
X61957Y-231220D01*
X61541D01*
X61332Y-230910D01*
X61541Y-230600D01*
X61957D01*
X62166Y-230910D01*
G01X61749Y-218820D02*
X59041Y-218510D01*
X56749Y-218045D01*
X54666Y-217425D01*
X52374Y-216650D01*
X49249Y-215410D01*
Y-221610D01*
G01X61749Y-204250D02*
X49249D01*
X58207Y-209985D01*
Y-202235D01*
G01X78256Y-350365D02*
X65756D01*
X74714Y-356100D01*
Y-348350D01*
G01X65756Y-339825D02*
X66173Y-341065D01*
X67214Y-341995D01*
X68464Y-342615D01*
X70131Y-343080D01*
X72006Y-343235D01*
X73881Y-343080D01*
X75548Y-342615D01*
X76798Y-341995D01*
X77839Y-341065D01*
X78256Y-339825D01*
X77839Y-338585D01*
X76798Y-337655D01*
X75548Y-337035D01*
X73881Y-336570D01*
X72006Y-336415D01*
X70131Y-336570D01*
X68464Y-337035D01*
X67214Y-337655D01*
X66173Y-338585D01*
X65756Y-339825D01*
G01X78256Y-327735D02*
X75548Y-327425D01*
X73256Y-326960D01*
X71173Y-326340D01*
X68881Y-325565D01*
X65756Y-324325D01*
Y-330525D01*
G01X78673Y-315025D02*
X78464Y-315335D01*
X78048D01*
X77839Y-315025D01*
X78048Y-314715D01*
X78464D01*
X78673Y-315025D01*
G01X65756Y-302625D02*
X66173Y-303865D01*
X67214Y-304795D01*
X68464Y-305415D01*
X70131Y-305880D01*
X72006Y-306035D01*
X73881Y-305880D01*
X75548Y-305415D01*
X76798Y-304795D01*
X77839Y-303865D01*
X78256Y-302625D01*
X77839Y-301385D01*
X76798Y-300455D01*
X75548Y-299835D01*
X73881Y-299370D01*
X72006Y-299215D01*
X70131Y-299370D01*
X68464Y-299835D01*
X67214Y-300455D01*
X66173Y-301385D01*
X65756Y-302625D01*
G01X78256Y-290225D02*
X78048Y-289140D01*
X77423Y-287900D01*
X76381Y-287125D01*
X74923Y-286815D01*
X73465Y-287125D01*
X72214Y-288055D01*
X71589Y-289450D01*
Y-291000D01*
X71173Y-291930D01*
X70131Y-292705D01*
X68673Y-293015D01*
X67214Y-292550D01*
X66173Y-291465D01*
X65756Y-290225D01*
X66173Y-288985D01*
X67214Y-287900D01*
X68673Y-287435D01*
X70131Y-287745D01*
X71173Y-288520D01*
X71589Y-289450D01*
Y-291000D01*
X72214Y-292395D01*
X73465Y-293325D01*
X74923Y-293635D01*
X76381Y-293325D01*
X77423Y-292550D01*
X78048Y-291310D01*
X78256Y-290225D01*
G01Y-255625D02*
X65756D01*
X68256Y-257485D01*
G01X78256D02*
Y-253765D01*
G01X65756Y-243225D02*
X66173Y-244465D01*
X67214Y-245395D01*
X68464Y-246015D01*
X70131Y-246480D01*
X72006Y-246635D01*
X73881Y-246480D01*
X75548Y-246015D01*
X76798Y-245395D01*
X77839Y-244465D01*
X78256Y-243225D01*
X77839Y-241985D01*
X76798Y-241055D01*
X75548Y-240435D01*
X73881Y-239970D01*
X72006Y-239815D01*
X70131Y-239970D01*
X68464Y-240435D01*
X67214Y-241055D01*
X66173Y-241985D01*
X65756Y-243225D01*
G01X78673Y-230825D02*
X78464Y-231135D01*
X78048D01*
X77839Y-230825D01*
X78048Y-230515D01*
X78464D01*
X78673Y-230825D01*
G01X75756Y-221835D02*
X77215Y-220905D01*
X78048Y-219665D01*
X78256Y-218270D01*
X78048Y-217030D01*
X77006Y-215790D01*
X75756Y-215015D01*
X74506Y-214860D01*
X73048Y-215170D01*
X72006Y-216255D01*
X71589Y-217340D01*
Y-218735D01*
G01Y-217340D02*
X70964Y-216410D01*
X69923Y-215635D01*
X68673Y-215325D01*
X67423Y-215635D01*
X66381Y-216410D01*
X65756Y-217805D01*
X65964Y-219200D01*
X66798Y-220595D01*
G01X78256Y-204165D02*
X65756D01*
X74714Y-209900D01*
Y-202150D01*
G01X70445Y109760D02*
Y103460D01*
G01X68643Y109760D02*
X72247D01*
G01X76745Y103460D02*
X76118Y103565D01*
X75570Y103985D01*
X75100Y104615D01*
X74787Y105350D01*
X74630Y106190D01*
Y107030D01*
X74787Y107870D01*
X75100Y108605D01*
X75570Y109235D01*
X76118Y109655D01*
X76745Y109760D01*
X77372Y109655D01*
X77920Y109235D01*
X78390Y108605D01*
X78703Y107870D01*
X78860Y107030D01*
Y106190D01*
X78703Y105350D01*
X78390Y104615D01*
X77920Y103985D01*
X77372Y103565D01*
X76745Y103460D01*
G01X81478Y109760D02*
Y103460D01*
X84612D01*
G01X90912D02*
X87778D01*
Y109760D01*
X90912D01*
G01X89658Y106715D02*
X87778D01*
G01X94078Y103460D02*
Y109760D01*
X96037D01*
X96663Y109445D01*
X97055Y109025D01*
X97212Y108185D01*
X97055Y107345D01*
X96585Y106820D01*
X96037Y106505D01*
X94078D01*
G01X96037D02*
X97212Y103460D01*
G01X99987D02*
X101945Y109760D01*
X103903Y103460D01*
G01X103198Y105665D02*
X100692D01*
G01X106443Y103460D02*
Y109760D01*
X110047Y103460D01*
Y109760D01*
G01X116268Y109235D02*
X115798Y109550D01*
X115250Y109760D01*
X114623D01*
X113918Y109445D01*
X113370Y108920D01*
X112978Y108290D01*
X112665Y107240D01*
X112587Y106295D01*
X112743Y105350D01*
X112978Y104720D01*
X113448Y104090D01*
X113997Y103670D01*
X114545Y103460D01*
X115093D01*
X115642Y103670D01*
X116112Y103985D01*
X116503Y104405D01*
G01X122412Y103460D02*
X119278D01*
Y109760D01*
X122412D01*
G01X121158Y106715D02*
X119278D01*
G01X127145Y103250D02*
X126988Y103355D01*
Y103565D01*
X127145Y103670D01*
X127302Y103565D01*
Y103355D01*
X127145Y103250D01*
G01Y106085D02*
X126988Y106190D01*
Y106400D01*
X127145Y106505D01*
X127302Y106400D01*
Y106190D01*
X127145Y106085D01*
G01X132583Y105560D02*
X134463D01*
G01X133445Y106925D02*
Y104195D01*
G01X138257Y108710D02*
X138727Y109340D01*
X139275Y109655D01*
X139902Y109760D01*
X140685Y109550D01*
X141233Y109025D01*
X141390Y108395D01*
X141312Y107765D01*
X140998Y107240D01*
X139432Y106190D01*
X138727Y105455D01*
X138257Y104405D01*
X138100Y103460D01*
X141390D01*
G01X144635Y103250D02*
X147455Y109760D01*
G01X151327Y105560D02*
X153363D01*
G01X157157Y108710D02*
X157627Y109340D01*
X158175Y109655D01*
X158802Y109760D01*
X159585Y109550D01*
X160133Y109025D01*
X160290Y108395D01*
X160212Y107765D01*
X159898Y107240D01*
X158332Y106190D01*
X157627Y105455D01*
X157157Y104405D01*
X157000Y103460D01*
X160290D01*
G01X168895D02*
Y107660D01*
G01Y106505D02*
X169130Y107030D01*
X169522Y107450D01*
X170070Y107660D01*
X170618Y107450D01*
X171010Y107030D01*
X171245Y106505D01*
Y103460D01*
G01Y106505D02*
X171480Y107030D01*
X171872Y107450D01*
X172420Y107660D01*
X172968Y107450D01*
X173360Y107030D01*
X173595Y106400D01*
Y103460D01*
G01X177545Y107660D02*
Y103460D01*
G01Y109340D02*
X177388Y109445D01*
Y109655D01*
X177545Y109760D01*
X177702Y109655D01*
Y109445D01*
X177545Y109340D01*
G01X183845Y103460D02*
Y109760D01*
G01X94115Y-318692D02*
X95157Y-317762D01*
X95782Y-316677D01*
X95990Y-315282D01*
X95573Y-313887D01*
X94740Y-312802D01*
X93282Y-312027D01*
X91615Y-311872D01*
X89948Y-312182D01*
X88907Y-312957D01*
X88073Y-314042D01*
X87865Y-315127D01*
X88073Y-316212D01*
X88907Y-317607D01*
X83490Y-317142D01*
Y-312957D01*
G01X95990Y-302882D02*
X83490D01*
X85990Y-304742D01*
G01X95990D02*
Y-301022D01*
G01Y-290482D02*
X83490D01*
X85990Y-292342D01*
G01X95990D02*
Y-288622D01*
G01X96407Y-278082D02*
X96198Y-278392D01*
X95782D01*
X95573Y-278082D01*
X95782Y-277772D01*
X96198D01*
X96407Y-278082D01*
G01X95990Y-265682D02*
X95782Y-264597D01*
X95157Y-263357D01*
X94115Y-262582D01*
X92657Y-262272D01*
X91199Y-262582D01*
X89948Y-263512D01*
X89323Y-264907D01*
Y-266457D01*
X88907Y-267387D01*
X87865Y-268162D01*
X86407Y-268472D01*
X84948Y-268007D01*
X83907Y-266922D01*
X83490Y-265682D01*
X83907Y-264442D01*
X84948Y-263357D01*
X86407Y-262892D01*
X87865Y-263202D01*
X88907Y-263977D01*
X89323Y-264907D01*
Y-266457D01*
X89948Y-267852D01*
X91199Y-268782D01*
X92657Y-269092D01*
X94115Y-268782D01*
X95157Y-268007D01*
X95782Y-266767D01*
X95990Y-265682D01*
G01Y-253282D02*
X83490D01*
X85990Y-255142D01*
G01X95990D02*
Y-251422D01*
G01Y-218682D02*
X83490D01*
X85990Y-220542D01*
G01X95990D02*
Y-216822D01*
G01X93490Y-209692D02*
X94949Y-208762D01*
X95782Y-207522D01*
X95990Y-206127D01*
X95782Y-204887D01*
X94740Y-203647D01*
X93490Y-202872D01*
X92240Y-202717D01*
X90782Y-203027D01*
X89740Y-204112D01*
X89323Y-205197D01*
Y-206592D01*
G01Y-205197D02*
X88698Y-204267D01*
X87657Y-203492D01*
X86407Y-203182D01*
X85157Y-203492D01*
X84115Y-204267D01*
X83490Y-205662D01*
X83698Y-207057D01*
X84532Y-208452D01*
G01X82501Y114618D02*
Y122118D01*
X86795Y114618D01*
Y122118D01*
G01X90281Y114618D02*
Y122118D01*
X92521D01*
X93268Y121743D01*
X93828Y120868D01*
X94015Y119868D01*
X93828Y118868D01*
X93361Y118118D01*
X92521Y117743D01*
X90281D01*
G01X99648Y122118D02*
Y114618D01*
G01X97501Y122118D02*
X101795D01*
G01X105188Y114618D02*
Y122118D01*
G01X109108D02*
Y114618D01*
G01Y118368D02*
X105188D01*
G01X124182Y-365663D02*
X111682D01*
X114182Y-367523D01*
G01X124182D02*
Y-363803D01*
G01Y-353263D02*
X111682D01*
X114182Y-355123D01*
G01X124182D02*
Y-351403D01*
G01Y-341173D02*
X121474Y-340863D01*
X119182Y-340398D01*
X117099Y-339778D01*
X114807Y-339003D01*
X111682Y-337763D01*
Y-343963D01*
G01X122724Y-331098D02*
X123765Y-330013D01*
X124182Y-328773D01*
X123765Y-327533D01*
X122516Y-326448D01*
X120640Y-325673D01*
X118765Y-325363D01*
X116474D01*
X114599Y-325673D01*
X112932Y-326448D01*
X112099Y-327378D01*
X111682Y-328463D01*
X112099Y-329703D01*
X112932Y-330633D01*
X114182Y-331253D01*
X115849Y-331563D01*
X117307Y-331253D01*
X118765Y-330478D01*
X119599Y-329548D01*
X119807Y-328463D01*
X119391Y-327223D01*
X118349Y-326293D01*
X116474Y-325363D01*
G01X124599Y-316063D02*
X124390Y-316373D01*
X123974D01*
X123765Y-316063D01*
X123974Y-315753D01*
X124390D01*
X124599Y-316063D01*
G01X121682Y-307073D02*
X123141Y-306143D01*
X123974Y-304903D01*
X124182Y-303508D01*
X123974Y-302268D01*
X122932Y-301028D01*
X121682Y-300253D01*
X120432Y-300098D01*
X118974Y-300408D01*
X117932Y-301493D01*
X117515Y-302578D01*
Y-303973D01*
G01Y-302578D02*
X116890Y-301648D01*
X115849Y-300873D01*
X114599Y-300563D01*
X113349Y-300873D01*
X112307Y-301648D01*
X111682Y-303043D01*
X111890Y-304438D01*
X112724Y-305833D01*
G01X113765Y-294208D02*
X112516Y-293278D01*
X111890Y-292193D01*
X111682Y-290953D01*
X112099Y-289403D01*
X113140Y-288318D01*
X114390Y-288008D01*
X115641Y-288163D01*
X116682Y-288783D01*
X118765Y-291883D01*
X120224Y-293278D01*
X122307Y-294208D01*
X124182Y-294518D01*
Y-288008D01*
G01X113765Y-259608D02*
X112516Y-258678D01*
X111890Y-257593D01*
X111682Y-256353D01*
X112099Y-254803D01*
X113140Y-253718D01*
X114390Y-253408D01*
X115641Y-253563D01*
X116682Y-254183D01*
X118765Y-257283D01*
X120224Y-258678D01*
X122307Y-259608D01*
X124182Y-259918D01*
Y-253408D01*
G01X122724Y-246898D02*
X123765Y-245813D01*
X124182Y-244573D01*
X123765Y-243333D01*
X122516Y-242248D01*
X120640Y-241473D01*
X118765Y-241163D01*
X116474D01*
X114599Y-241473D01*
X112932Y-242248D01*
X112099Y-243178D01*
X111682Y-244263D01*
X112099Y-245503D01*
X112932Y-246433D01*
X114182Y-247053D01*
X115849Y-247363D01*
X117307Y-247053D01*
X118765Y-246278D01*
X119599Y-245348D01*
X119807Y-244263D01*
X119391Y-243023D01*
X118349Y-242093D01*
X116474Y-241163D01*
G01X124599Y-231863D02*
X124390Y-232173D01*
X123974D01*
X123765Y-231863D01*
X123974Y-231553D01*
X124390D01*
X124599Y-231863D01*
G01X122724Y-222098D02*
X123765Y-221013D01*
X124182Y-219773D01*
X123765Y-218533D01*
X122516Y-217448D01*
X120640Y-216673D01*
X118765Y-216363D01*
X116474D01*
X114599Y-216673D01*
X112932Y-217448D01*
X112099Y-218378D01*
X111682Y-219463D01*
X112099Y-220703D01*
X112932Y-221633D01*
X114182Y-222253D01*
X115849Y-222563D01*
X117307Y-222253D01*
X118765Y-221478D01*
X119599Y-220548D01*
X119807Y-219463D01*
X119391Y-218223D01*
X118349Y-217293D01*
X116474Y-216363D01*
G01X122307Y-210473D02*
X123349Y-209543D01*
X123974Y-208458D01*
X124182Y-207063D01*
X123765Y-205668D01*
X122932Y-204583D01*
X121474Y-203808D01*
X119807Y-203653D01*
X118140Y-203963D01*
X117099Y-204738D01*
X116265Y-205823D01*
X116057Y-206908D01*
X116265Y-207993D01*
X117099Y-209388D01*
X111682Y-208923D01*
Y-204738D01*
G01X139036Y620124D02*
Y627624D01*
X143330Y620124D01*
Y627624D01*
G01X146816Y620124D02*
Y627624D01*
X149056D01*
X149803Y627249D01*
X150363Y626374D01*
X150550Y625374D01*
X150363Y624374D01*
X149896Y623624D01*
X149056Y623249D01*
X146816D01*
G01X156183Y627624D02*
Y620124D01*
G01X154036Y627624D02*
X158330D01*
G01X161723Y620124D02*
Y627624D01*
G01X165643D02*
Y620124D01*
G01Y623874D02*
X161723D01*
G01X185809Y322655D02*
Y330155D01*
X190103Y322655D01*
Y330155D01*
G01X193589Y322655D02*
Y330155D01*
X195829D01*
X196576Y329780D01*
X197136Y328905D01*
X197323Y327905D01*
X197136Y326905D01*
X196669Y326155D01*
X195829Y325780D01*
X193589D01*
G01X202956Y330155D02*
Y322655D01*
G01X200809Y330155D02*
X205103D01*
G01X208496Y322655D02*
Y330155D01*
G01X212416D02*
Y322655D01*
G01Y326405D02*
X208496D01*
G01X199650Y-473979D02*
Y-481979D01*
X203650D01*
G01X211450D02*
Y-476646D01*
G01Y-477579D02*
X211050Y-477046D01*
X210450Y-476779D01*
X209750Y-476646D01*
X209050Y-476912D01*
X208450Y-477446D01*
X208050Y-478246D01*
X207850Y-479312D01*
X208050Y-480379D01*
X208450Y-481179D01*
X209050Y-481712D01*
X209750Y-481979D01*
X210450Y-481846D01*
X211050Y-481446D01*
X211450Y-480913D01*
G01X215550Y-484379D02*
X216150Y-484646D01*
X216950Y-484379D01*
X217450Y-483846D01*
X217850Y-483179D01*
X218450Y-481046D01*
X219750Y-476646D01*
G01X216550D02*
X218450Y-481046D01*
G01X224150Y-478379D02*
X227350D01*
X227050Y-477446D01*
X226550Y-476912D01*
X225850Y-476646D01*
X225150Y-476779D01*
X224550Y-477179D01*
X224150Y-478112D01*
X223950Y-478913D01*
Y-479712D01*
X224150Y-480512D01*
X224650Y-481312D01*
X225250Y-481846D01*
X225950Y-481979D01*
X226650Y-481712D01*
X227350Y-480913D01*
G01X232250Y-481979D02*
Y-476646D01*
G01Y-477712D02*
X232750Y-477179D01*
X233250Y-476779D01*
X233950Y-476646D01*
X234450Y-476779D01*
X235050Y-477179D01*
G01X195279Y1689189D02*
Y1696689D01*
X199573Y1689189D01*
Y1696689D01*
G01X203059Y1689189D02*
Y1696689D01*
X205299D01*
X206046Y1696314D01*
X206606Y1695439D01*
X206793Y1694439D01*
X206606Y1693439D01*
X206139Y1692689D01*
X205299Y1692314D01*
X203059D01*
G01X212426Y1696689D02*
Y1689189D01*
G01X210279Y1696689D02*
X214573D01*
G01X217966Y1689189D02*
Y1696689D01*
G01X221886D02*
Y1689189D01*
G01Y1692939D02*
X217966D01*
G01X223350Y-531979D02*
Y-523979D01*
X227950Y-531979D01*
Y-523979D01*
G01X233650Y-526646D02*
Y-531979D01*
G01Y-524512D02*
X233450Y-524379D01*
Y-524112D01*
X233650Y-523979D01*
X233850Y-524112D01*
Y-524379D01*
X233650Y-524512D01*
G01X239950Y-531979D02*
Y-526646D01*
G01Y-527979D02*
X240350Y-527312D01*
X240950Y-526779D01*
X241750Y-526646D01*
X242450Y-526779D01*
X243050Y-527312D01*
X243350Y-528246D01*
Y-531979D01*
G01X251450D02*
Y-526646D01*
G01Y-527579D02*
X251050Y-527046D01*
X250450Y-526779D01*
X249750Y-526646D01*
X249050Y-526912D01*
X248450Y-527446D01*
X248050Y-528246D01*
X247850Y-529312D01*
X248050Y-530379D01*
X248450Y-531179D01*
X249050Y-531712D01*
X249750Y-531979D01*
X250450Y-531846D01*
X251050Y-531446D01*
X251450Y-530913D01*
G01X217279Y-508436D02*
Y-500436D01*
X221079D01*
G01X219679Y-504303D02*
X217279D01*
G01X224679Y-508436D02*
X227179Y-500436D01*
X229679Y-508436D01*
G01X228779Y-505636D02*
X225579D01*
G01X235979Y-504169D02*
X236379Y-503769D01*
X236679Y-503103D01*
X236879Y-502169D01*
X236679Y-501369D01*
X236279Y-500836D01*
X235579Y-500436D01*
X232879D01*
Y-508436D01*
X236179D01*
X236879Y-507903D01*
X237279Y-507103D01*
X237479Y-506169D01*
X237279Y-505236D01*
X236679Y-504436D01*
X235979Y-504169D01*
X232879D01*
G01X219896Y200669D02*
Y208169D01*
X224190Y200669D01*
Y208169D01*
G01X227676Y200669D02*
Y208169D01*
X229916D01*
X230663Y207794D01*
X231223Y206919D01*
X231410Y205919D01*
X231223Y204919D01*
X230756Y204169D01*
X229916Y203794D01*
X227676D01*
G01X237043Y208169D02*
Y200669D01*
G01X234896Y208169D02*
X239190D01*
G01X242583Y200669D02*
Y208169D01*
G01X246503D02*
Y200669D01*
G01Y204419D02*
X242583D01*
G01X233406Y1644448D02*
G03I-2500J0D01*
G01X241280Y1648385D02*
G03I-2500J0D01*
G01X233406Y1658621D02*
G03I-2500J0D01*
G01X241280Y1662558D02*
G03I-2500J0D01*
G01X233406Y1672795D02*
G03I-2500J0D01*
G01X241280Y1676732D02*
G03I-2500J0D01*
G01X233406Y1686968D02*
G03I-2500J0D01*
G01X241280Y1690905D02*
G03I-2500J0D01*
G01X233406Y1715314D02*
G03I-2500J0D01*
G01Y1701141D02*
G03I-2500J0D01*
G01X241280Y1705078D02*
G03I-2500J0D01*
G01X233406Y1729488D02*
G03I-2500J0D01*
G01X241280Y1719251D02*
G03I-2500J0D01*
G01Y1733425D02*
G03I-2500J0D01*
G01X246159Y-368400D02*
X244910Y-367470D01*
X244284Y-366385D01*
X244076Y-365145D01*
X244493Y-363595D01*
X245534Y-362510D01*
X246784Y-362200D01*
X248035Y-362355D01*
X249076Y-362975D01*
X251159Y-366075D01*
X252618Y-367470D01*
X254701Y-368400D01*
X256576Y-368710D01*
Y-362200D01*
G01X254701Y-356465D02*
X255743Y-355535D01*
X256368Y-354450D01*
X256576Y-353055D01*
X256159Y-351660D01*
X255326Y-350575D01*
X253868Y-349800D01*
X252201Y-349645D01*
X250534Y-349955D01*
X249493Y-350730D01*
X248659Y-351815D01*
X248451Y-352900D01*
X248659Y-353985D01*
X249493Y-355380D01*
X244076Y-354915D01*
Y-350730D01*
G01Y-340655D02*
X244493Y-341895D01*
X245534Y-342825D01*
X246784Y-343445D01*
X248451Y-343910D01*
X250326Y-344065D01*
X252201Y-343910D01*
X253868Y-343445D01*
X255118Y-342825D01*
X256159Y-341895D01*
X256576Y-340655D01*
X256159Y-339415D01*
X255118Y-338485D01*
X253868Y-337865D01*
X252201Y-337400D01*
X250326Y-337245D01*
X248451Y-337400D01*
X246784Y-337865D01*
X245534Y-338485D01*
X244493Y-339415D01*
X244076Y-340655D01*
G01X254076Y-331665D02*
X255535Y-330735D01*
X256368Y-329495D01*
X256576Y-328100D01*
X256368Y-326860D01*
X255326Y-325620D01*
X254076Y-324845D01*
X252826Y-324690D01*
X251368Y-325000D01*
X250326Y-326085D01*
X249909Y-327170D01*
Y-328565D01*
G01Y-327170D02*
X249284Y-326240D01*
X248243Y-325465D01*
X246993Y-325155D01*
X245743Y-325465D01*
X244701Y-326240D01*
X244076Y-327635D01*
X244284Y-329030D01*
X245118Y-330425D01*
G01X256993Y-315855D02*
X256784Y-316165D01*
X256368D01*
X256159Y-315855D01*
X256368Y-315545D01*
X256784D01*
X256993Y-315855D01*
G01X246159Y-306400D02*
X244910Y-305470D01*
X244284Y-304385D01*
X244076Y-303145D01*
X244493Y-301595D01*
X245534Y-300510D01*
X246784Y-300200D01*
X248035Y-300355D01*
X249076Y-300975D01*
X251159Y-304075D01*
X252618Y-305470D01*
X254701Y-306400D01*
X256576Y-306710D01*
Y-300200D01*
G01X251368Y-294000D02*
X249909Y-292915D01*
X249076Y-291985D01*
X248659Y-290745D01*
X249076Y-289660D01*
X249909Y-288885D01*
X251159Y-288265D01*
X252618Y-288110D01*
X253868Y-288265D01*
X255118Y-288885D01*
X256159Y-289815D01*
X256576Y-290900D01*
X256159Y-292140D01*
X254910Y-293225D01*
X253034Y-293845D01*
X250951Y-294000D01*
X248243Y-293690D01*
X246784Y-293225D01*
X245326Y-292450D01*
X244284Y-291365D01*
X244076Y-290280D01*
X244493Y-289195D01*
X245534Y-288420D01*
G01X251368Y-259400D02*
X249909Y-258315D01*
X249076Y-257385D01*
X248659Y-256145D01*
X249076Y-255060D01*
X249909Y-254285D01*
X251159Y-253665D01*
X252618Y-253510D01*
X253868Y-253665D01*
X255118Y-254285D01*
X256159Y-255215D01*
X256576Y-256300D01*
X256159Y-257540D01*
X254910Y-258625D01*
X253034Y-259245D01*
X250951Y-259400D01*
X248243Y-259090D01*
X246784Y-258625D01*
X245326Y-257850D01*
X244284Y-256765D01*
X244076Y-255680D01*
X244493Y-254595D01*
X245534Y-253820D01*
G01X254076Y-247465D02*
X255535Y-246535D01*
X256368Y-245295D01*
X256576Y-243900D01*
X256368Y-242660D01*
X255326Y-241420D01*
X254076Y-240645D01*
X252826Y-240490D01*
X251368Y-240800D01*
X250326Y-241885D01*
X249909Y-242970D01*
Y-244365D01*
G01Y-242970D02*
X249284Y-242040D01*
X248243Y-241265D01*
X246993Y-240955D01*
X245743Y-241265D01*
X244701Y-242040D01*
X244076Y-243435D01*
X244284Y-244830D01*
X245118Y-246225D01*
G01X256993Y-231655D02*
X256784Y-231965D01*
X256368D01*
X256159Y-231655D01*
X256368Y-231345D01*
X256784D01*
X256993Y-231655D01*
G01X254701Y-222665D02*
X255743Y-221735D01*
X256368Y-220650D01*
X256576Y-219255D01*
X256159Y-217860D01*
X255326Y-216775D01*
X253868Y-216000D01*
X252201Y-215845D01*
X250534Y-216155D01*
X249493Y-216930D01*
X248659Y-218015D01*
X248451Y-219100D01*
X248659Y-220185D01*
X249493Y-221580D01*
X244076Y-221115D01*
Y-216930D01*
G01X256576Y-206855D02*
X256368Y-205770D01*
X255743Y-204530D01*
X254701Y-203755D01*
X253243Y-203445D01*
X251785Y-203755D01*
X250534Y-204685D01*
X249909Y-206080D01*
Y-207630D01*
X249493Y-208560D01*
X248451Y-209335D01*
X246993Y-209645D01*
X245534Y-209180D01*
X244493Y-208095D01*
X244076Y-206855D01*
X244493Y-205615D01*
X245534Y-204530D01*
X246993Y-204065D01*
X248451Y-204375D01*
X249493Y-205150D01*
X249909Y-206080D01*
Y-207630D01*
X250534Y-209025D01*
X251785Y-209955D01*
X253243Y-210265D01*
X254701Y-209955D01*
X255743Y-209180D01*
X256368Y-207940D01*
X256576Y-206855D01*
G01X249154Y1644448D02*
G03I-2500J0D01*
G01X257028Y1648385D02*
G03I-2500J0D01*
G01X249154Y1658621D02*
G03I-2500J0D01*
G01X257028Y1662558D02*
G03I-2500J0D01*
G01X249154Y1672795D02*
G03I-2500J0D01*
G01X257028Y1676732D02*
G03I-2500J0D01*
G01X249154Y1686968D02*
G03I-2500J0D01*
G01X257028Y1690905D02*
G03I-2500J0D01*
G01X249154Y1715314D02*
G03I-2500J0D01*
G01Y1701141D02*
G03I-2500J0D01*
G01X257028Y1705078D02*
G03I-2500J0D01*
G01X249154Y1729488D02*
G03I-2500J0D01*
G01X257028Y1719251D02*
G03I-2500J0D01*
G01Y1733425D02*
G03I-2500J0D01*
G01X267172Y-368402D02*
X265923Y-367472D01*
X265297Y-366387D01*
X265089Y-365147D01*
X265506Y-363597D01*
X266547Y-362512D01*
X267797Y-362202D01*
X269048Y-362357D01*
X270089Y-362977D01*
X272172Y-366077D01*
X273631Y-367472D01*
X275714Y-368402D01*
X277589Y-368712D01*
Y-362202D01*
G01Y-353367D02*
X274881Y-353057D01*
X272589Y-352592D01*
X270506Y-351972D01*
X268214Y-351197D01*
X265089Y-349957D01*
Y-356157D01*
G01X277589Y-340967D02*
X274881Y-340657D01*
X272589Y-340192D01*
X270506Y-339572D01*
X268214Y-338797D01*
X265089Y-337557D01*
Y-343757D01*
G01Y-328257D02*
X265506Y-329497D01*
X266547Y-330427D01*
X267797Y-331047D01*
X269464Y-331512D01*
X271339Y-331667D01*
X273214Y-331512D01*
X274881Y-331047D01*
X276131Y-330427D01*
X277172Y-329497D01*
X277589Y-328257D01*
X277172Y-327017D01*
X276131Y-326087D01*
X274881Y-325467D01*
X273214Y-325002D01*
X271339Y-324847D01*
X269464Y-325002D01*
X267797Y-325467D01*
X266547Y-326087D01*
X265506Y-327017D01*
X265089Y-328257D01*
G01X278006Y-315857D02*
X277797Y-316167D01*
X277381D01*
X277172Y-315857D01*
X277381Y-315547D01*
X277797D01*
X278006Y-315857D01*
G01X276131Y-306092D02*
X277172Y-305007D01*
X277589Y-303767D01*
X277172Y-302527D01*
X275923Y-301442D01*
X274047Y-300667D01*
X272172Y-300357D01*
X269881D01*
X268006Y-300667D01*
X266339Y-301442D01*
X265506Y-302372D01*
X265089Y-303457D01*
X265506Y-304697D01*
X266339Y-305627D01*
X267589Y-306247D01*
X269256Y-306557D01*
X270714Y-306247D01*
X272172Y-305472D01*
X273006Y-304542D01*
X273214Y-303457D01*
X272798Y-302217D01*
X271756Y-301287D01*
X269881Y-300357D01*
G01X277589Y-291057D02*
X277381Y-289972D01*
X276756Y-288732D01*
X275714Y-287957D01*
X274256Y-287647D01*
X272798Y-287957D01*
X271547Y-288887D01*
X270922Y-290282D01*
Y-291832D01*
X270506Y-292762D01*
X269464Y-293537D01*
X268006Y-293847D01*
X266547Y-293382D01*
X265506Y-292297D01*
X265089Y-291057D01*
X265506Y-289817D01*
X266547Y-288732D01*
X268006Y-288267D01*
X269464Y-288577D01*
X270506Y-289352D01*
X270922Y-290282D01*
Y-291832D01*
X271547Y-293227D01*
X272798Y-294157D01*
X274256Y-294467D01*
X275714Y-294157D01*
X276756Y-293382D01*
X277381Y-292142D01*
X277589Y-291057D01*
G01Y-256767D02*
X274881Y-256457D01*
X272589Y-255992D01*
X270506Y-255372D01*
X268214Y-254597D01*
X265089Y-253357D01*
Y-259557D01*
G01Y-244057D02*
X265506Y-245297D01*
X266547Y-246227D01*
X267797Y-246847D01*
X269464Y-247312D01*
X271339Y-247467D01*
X273214Y-247312D01*
X274881Y-246847D01*
X276131Y-246227D01*
X277172Y-245297D01*
X277589Y-244057D01*
X277172Y-242817D01*
X276131Y-241887D01*
X274881Y-241267D01*
X273214Y-240802D01*
X271339Y-240647D01*
X269464Y-240802D01*
X267797Y-241267D01*
X266547Y-241887D01*
X265506Y-242817D01*
X265089Y-244057D01*
G01X278006Y-231657D02*
X277797Y-231967D01*
X277381D01*
X277172Y-231657D01*
X277381Y-231347D01*
X277797D01*
X278006Y-231657D01*
G01X275089Y-222667D02*
X276548Y-221737D01*
X277381Y-220497D01*
X277589Y-219102D01*
X277381Y-217862D01*
X276339Y-216622D01*
X275089Y-215847D01*
X273839Y-215692D01*
X272381Y-216002D01*
X271339Y-217087D01*
X270922Y-218172D01*
Y-219567D01*
G01Y-218172D02*
X270297Y-217242D01*
X269256Y-216467D01*
X268006Y-216157D01*
X266756Y-216467D01*
X265714Y-217242D01*
X265089Y-218637D01*
X265297Y-220032D01*
X266131Y-221427D01*
G01X277589Y-206857D02*
X277381Y-205772D01*
X276756Y-204532D01*
X275714Y-203757D01*
X274256Y-203447D01*
X272798Y-203757D01*
X271547Y-204687D01*
X270922Y-206082D01*
Y-207632D01*
X270506Y-208562D01*
X269464Y-209337D01*
X268006Y-209647D01*
X266547Y-209182D01*
X265506Y-208097D01*
X265089Y-206857D01*
X265506Y-205617D01*
X266547Y-204532D01*
X268006Y-204067D01*
X269464Y-204377D01*
X270506Y-205152D01*
X270922Y-206082D01*
Y-207632D01*
X271547Y-209027D01*
X272798Y-209957D01*
X274256Y-210267D01*
X275714Y-209957D01*
X276756Y-209182D01*
X277381Y-207942D01*
X277589Y-206857D01*
G01X264902Y1644448D02*
G03I-2500J0D01*
G01X272776Y1648385D02*
G03I-2500J0D01*
G01X264902Y1658621D02*
G03I-2500J0D01*
G01X272776Y1662558D02*
G03I-2500J0D01*
G01X264902Y1672795D02*
G03I-2500J0D01*
G01X272776Y1676732D02*
G03I-2500J0D01*
G01X264902Y1686968D02*
G03I-2500J0D01*
G01X272776Y1690905D02*
G03I-2500J0D01*
G01X264902Y1715314D02*
G03I-2500J0D01*
G01Y1701141D02*
G03I-2500J0D01*
G01X272776Y1705078D02*
G03I-2500J0D01*
G01X264902Y1729488D02*
G03I-2500J0D01*
G01X272776Y1719251D02*
G03I-2500J0D01*
G01Y1733425D02*
G03I-2500J0D01*
G01X293125Y-368867D02*
X294584Y-367937D01*
X295417Y-366697D01*
X295625Y-365302D01*
X295417Y-364062D01*
X294375Y-362822D01*
X293125Y-362047D01*
X291875Y-361892D01*
X290417Y-362202D01*
X289375Y-363287D01*
X288958Y-364372D01*
Y-365767D01*
G01Y-364372D02*
X288333Y-363442D01*
X287292Y-362667D01*
X286042Y-362357D01*
X284792Y-362667D01*
X283750Y-363442D01*
X283125Y-364837D01*
X283333Y-366232D01*
X284167Y-367627D01*
G01X283125Y-353057D02*
X283542Y-354297D01*
X284583Y-355227D01*
X285833Y-355847D01*
X287500Y-356312D01*
X289375Y-356467D01*
X291250Y-356312D01*
X292917Y-355847D01*
X294167Y-355227D01*
X295208Y-354297D01*
X295625Y-353057D01*
X295208Y-351817D01*
X294167Y-350887D01*
X292917Y-350267D01*
X291250Y-349802D01*
X289375Y-349647D01*
X287500Y-349802D01*
X285833Y-350267D01*
X284583Y-350887D01*
X283542Y-351817D01*
X283125Y-353057D01*
G01X290417Y-343602D02*
X288958Y-342517D01*
X288125Y-341587D01*
X287708Y-340347D01*
X288125Y-339262D01*
X288958Y-338487D01*
X290208Y-337867D01*
X291667Y-337712D01*
X292917Y-337867D01*
X294167Y-338487D01*
X295208Y-339417D01*
X295625Y-340502D01*
X295208Y-341742D01*
X293959Y-342827D01*
X292083Y-343447D01*
X290000Y-343602D01*
X287292Y-343292D01*
X285833Y-342827D01*
X284375Y-342052D01*
X283333Y-340967D01*
X283125Y-339882D01*
X283542Y-338797D01*
X284583Y-338022D01*
G01X295625Y-328567D02*
X292917Y-328257D01*
X290625Y-327792D01*
X288542Y-327172D01*
X286250Y-326397D01*
X283125Y-325157D01*
Y-331357D01*
G01X296042Y-315857D02*
X295833Y-316167D01*
X295417D01*
X295208Y-315857D01*
X295417Y-315547D01*
X295833D01*
X296042Y-315857D01*
G01X295625Y-303767D02*
X292917Y-303457D01*
X290625Y-302992D01*
X288542Y-302372D01*
X286250Y-301597D01*
X283125Y-300357D01*
Y-306557D01*
G01X285208Y-294002D02*
X283959Y-293072D01*
X283333Y-291987D01*
X283125Y-290747D01*
X283542Y-289197D01*
X284583Y-288112D01*
X285833Y-287802D01*
X287084Y-287957D01*
X288125Y-288577D01*
X290208Y-291677D01*
X291667Y-293072D01*
X293750Y-294002D01*
X295625Y-294312D01*
Y-287802D01*
G01Y-256767D02*
X292917Y-256457D01*
X290625Y-255992D01*
X288542Y-255372D01*
X286250Y-254597D01*
X283125Y-253357D01*
Y-259557D01*
G01X295625Y-244367D02*
X292917Y-244057D01*
X290625Y-243592D01*
X288542Y-242972D01*
X286250Y-242197D01*
X283125Y-240957D01*
Y-247157D01*
G01X296042Y-231657D02*
X295833Y-231967D01*
X295417D01*
X295208Y-231657D01*
X295417Y-231347D01*
X295833D01*
X296042Y-231657D01*
G01X294167Y-221892D02*
X295208Y-220807D01*
X295625Y-219567D01*
X295208Y-218327D01*
X293959Y-217242D01*
X292083Y-216467D01*
X290208Y-216157D01*
X287917D01*
X286042Y-216467D01*
X284375Y-217242D01*
X283542Y-218172D01*
X283125Y-219257D01*
X283542Y-220497D01*
X284375Y-221427D01*
X285625Y-222047D01*
X287292Y-222357D01*
X288750Y-222047D01*
X290208Y-221272D01*
X291042Y-220342D01*
X291250Y-219257D01*
X290834Y-218017D01*
X289792Y-217087D01*
X287917Y-216157D01*
G01X285208Y-209802D02*
X283959Y-208872D01*
X283333Y-207787D01*
X283125Y-206547D01*
X283542Y-204997D01*
X284583Y-203912D01*
X285833Y-203602D01*
X287084Y-203757D01*
X288125Y-204377D01*
X290208Y-207477D01*
X291667Y-208872D01*
X293750Y-209802D01*
X295625Y-210112D01*
Y-203602D01*
G01X280650Y1644448D02*
G03I-2500J0D01*
G01X288524Y1648385D02*
G03I-2500J0D01*
G01X280650Y1658621D02*
G03I-2500J0D01*
G01X288524Y1662558D02*
G03I-2500J0D01*
G01X280650Y1672795D02*
G03I-2500J0D01*
G01X288524Y1676732D02*
G03I-2500J0D01*
G01X280650Y1686968D02*
G03I-2500J0D01*
G01X288524Y1690905D02*
G03I-2500J0D01*
G01X280650Y1701141D02*
G03I-2500J0D01*
G01Y1715314D02*
G03I-2500J0D01*
G01X288524Y1705078D02*
G03I-2500J0D01*
G01X280650Y1729488D02*
G03I-2500J0D01*
G01X288524Y1719251D02*
G03I-2500J0D01*
G01Y1733425D02*
G03I-2500J0D01*
G01X310554Y-368866D02*
X312013Y-367936D01*
X312846Y-366696D01*
X313054Y-365301D01*
X312846Y-364061D01*
X311804Y-362821D01*
X310554Y-362046D01*
X309304Y-361891D01*
X307846Y-362201D01*
X306804Y-363286D01*
X306387Y-364371D01*
Y-365766D01*
G01Y-364371D02*
X305762Y-363441D01*
X304721Y-362666D01*
X303471Y-362356D01*
X302221Y-362666D01*
X301179Y-363441D01*
X300554Y-364836D01*
X300762Y-366231D01*
X301596Y-367626D01*
G01X302637Y-356001D02*
X301388Y-355071D01*
X300762Y-353986D01*
X300554Y-352746D01*
X300971Y-351196D01*
X302012Y-350111D01*
X303262Y-349801D01*
X304513Y-349956D01*
X305554Y-350576D01*
X307637Y-353676D01*
X309096Y-355071D01*
X311179Y-356001D01*
X313054Y-356311D01*
Y-349801D01*
G01X302637Y-343601D02*
X301388Y-342671D01*
X300762Y-341586D01*
X300554Y-340346D01*
X300971Y-338796D01*
X302012Y-337711D01*
X303262Y-337401D01*
X304513Y-337556D01*
X305554Y-338176D01*
X307637Y-341276D01*
X309096Y-342671D01*
X311179Y-343601D01*
X313054Y-343911D01*
Y-337401D01*
G01X311179Y-331666D02*
X312221Y-330736D01*
X312846Y-329651D01*
X313054Y-328256D01*
X312637Y-326861D01*
X311804Y-325776D01*
X310346Y-325001D01*
X308679Y-324846D01*
X307012Y-325156D01*
X305971Y-325931D01*
X305137Y-327016D01*
X304929Y-328101D01*
X305137Y-329186D01*
X305971Y-330581D01*
X300554Y-330116D01*
Y-325931D01*
G01X313471Y-315856D02*
X313262Y-316166D01*
X312846D01*
X312637Y-315856D01*
X312846Y-315546D01*
X313262D01*
X313471Y-315856D01*
G01X300554Y-303456D02*
X300971Y-304696D01*
X302012Y-305626D01*
X303262Y-306246D01*
X304929Y-306711D01*
X306804Y-306866D01*
X308679Y-306711D01*
X310346Y-306246D01*
X311596Y-305626D01*
X312637Y-304696D01*
X313054Y-303456D01*
X312637Y-302216D01*
X311596Y-301286D01*
X310346Y-300666D01*
X308679Y-300201D01*
X306804Y-300046D01*
X304929Y-300201D01*
X303262Y-300666D01*
X302012Y-301286D01*
X300971Y-302216D01*
X300554Y-303456D01*
G01Y-291056D02*
X300971Y-292296D01*
X302012Y-293226D01*
X303262Y-293846D01*
X304929Y-294311D01*
X306804Y-294466D01*
X308679Y-294311D01*
X310346Y-293846D01*
X311596Y-293226D01*
X312637Y-292296D01*
X313054Y-291056D01*
X312637Y-289816D01*
X311596Y-288886D01*
X310346Y-288266D01*
X308679Y-287801D01*
X306804Y-287646D01*
X304929Y-287801D01*
X303262Y-288266D01*
X302012Y-288886D01*
X300971Y-289816D01*
X300554Y-291056D01*
G01X313054Y-256456D02*
X312846Y-255371D01*
X312221Y-254131D01*
X311179Y-253356D01*
X309721Y-253046D01*
X308263Y-253356D01*
X307012Y-254286D01*
X306387Y-255681D01*
Y-257231D01*
X305971Y-258161D01*
X304929Y-258936D01*
X303471Y-259246D01*
X302012Y-258781D01*
X300971Y-257696D01*
X300554Y-256456D01*
X300971Y-255216D01*
X302012Y-254131D01*
X303471Y-253666D01*
X304929Y-253976D01*
X305971Y-254751D01*
X306387Y-255681D01*
Y-257231D01*
X307012Y-258626D01*
X308263Y-259556D01*
X309721Y-259866D01*
X311179Y-259556D01*
X312221Y-258781D01*
X312846Y-257541D01*
X313054Y-256456D01*
G01Y-244056D02*
X300554D01*
X303054Y-245916D01*
G01X313054D02*
Y-242196D01*
G01X313471Y-231656D02*
X313262Y-231966D01*
X312846D01*
X312637Y-231656D01*
X312846Y-231346D01*
X313262D01*
X313471Y-231656D01*
G01X311596Y-221891D02*
X312637Y-220806D01*
X313054Y-219566D01*
X312637Y-218326D01*
X311388Y-217241D01*
X309512Y-216466D01*
X307637Y-216156D01*
X305346D01*
X303471Y-216466D01*
X301804Y-217241D01*
X300971Y-218171D01*
X300554Y-219256D01*
X300971Y-220496D01*
X301804Y-221426D01*
X303054Y-222046D01*
X304721Y-222356D01*
X306179Y-222046D01*
X307637Y-221271D01*
X308471Y-220341D01*
X308679Y-219256D01*
X308263Y-218016D01*
X307221Y-217086D01*
X305346Y-216156D01*
G01X313054Y-206856D02*
X300554D01*
X303054Y-208716D01*
G01X313054D02*
Y-204996D01*
G01X304431Y1008240D02*
Y1015740D01*
X308725Y1008240D01*
Y1015740D01*
G01X312211Y1008240D02*
Y1015740D01*
X314451D01*
X315198Y1015365D01*
X315758Y1014490D01*
X315945Y1013490D01*
X315758Y1012490D01*
X315291Y1011740D01*
X314451Y1011365D01*
X312211D01*
G01X321578Y1015740D02*
Y1008240D01*
G01X319431Y1015740D02*
X323725D01*
G01X327118Y1008240D02*
Y1015740D01*
G01X331038D02*
Y1008240D01*
G01Y1011990D02*
X327118D01*
G01X308209Y1676732D02*
G03I-2500J0D01*
G01X300335Y1672795D02*
G03I-2500J0D01*
G01X308209Y1690905D02*
G03I-2500J0D01*
G01X300335Y1686968D02*
G03I-2500J0D01*
G01X308209Y1705078D02*
G03I-2500J0D01*
G01X300335Y1701141D02*
G03I-2500J0D01*
G01Y1715314D02*
G03I-2500J0D01*
G01X308209Y1719251D02*
G03I-2500J0D01*
G01X300335Y1729488D02*
G03I-2500J0D01*
G01X308209Y1733425D02*
G03I-2500J0D01*
G01X323957Y1676732D02*
G03I-2500J0D01*
G01X316083Y1672795D02*
G03I-2500J0D01*
G01X323957Y1690905D02*
G03I-2500J0D01*
G01X316083Y1686968D02*
G03I-2500J0D01*
G01X323957Y1705078D02*
G03I-2500J0D01*
G01X316083Y1701141D02*
G03I-2500J0D01*
G01Y1715314D02*
G03I-2500J0D01*
G01X323957Y1719251D02*
G03I-2500J0D01*
G01X316083Y1729488D02*
G03I-2500J0D01*
G01X323957Y1733425D02*
G03I-2500J0D01*
G01X326250Y-525312D02*
X326850Y-524512D01*
X327550Y-524112D01*
X328350Y-523979D01*
X329350Y-524246D01*
X330050Y-524912D01*
X330250Y-525712D01*
X330150Y-526513D01*
X329750Y-527179D01*
X327750Y-528512D01*
X326850Y-529446D01*
X326250Y-530779D01*
X326050Y-531979D01*
X330250D01*
G01X336150Y-523979D02*
X335350Y-524246D01*
X334750Y-524912D01*
X334350Y-525712D01*
X334050Y-526779D01*
X333950Y-527979D01*
X334050Y-529179D01*
X334350Y-530246D01*
X334750Y-531046D01*
X335350Y-531712D01*
X336150Y-531979D01*
X336950Y-531712D01*
X337550Y-531046D01*
X337950Y-530246D01*
X338250Y-529179D01*
X338350Y-527979D01*
X338250Y-526779D01*
X337950Y-525712D01*
X337550Y-524912D01*
X336950Y-524246D01*
X336150Y-523979D01*
G01X342250Y-525312D02*
X342850Y-524512D01*
X343550Y-524112D01*
X344350Y-523979D01*
X345350Y-524246D01*
X346050Y-524912D01*
X346250Y-525712D01*
X346150Y-526513D01*
X345750Y-527179D01*
X343750Y-528512D01*
X342850Y-529446D01*
X342250Y-530779D01*
X342050Y-531979D01*
X346250D01*
G01X349950Y-530379D02*
X350550Y-531312D01*
X351350Y-531846D01*
X352250Y-531979D01*
X353050Y-531846D01*
X353850Y-531179D01*
X354350Y-530379D01*
X354450Y-529579D01*
X354250Y-528646D01*
X353550Y-527979D01*
X352850Y-527712D01*
X351950D01*
G01X352850D02*
X353450Y-527312D01*
X353950Y-526646D01*
X354150Y-525846D01*
X353950Y-525046D01*
X353450Y-524379D01*
X352550Y-523979D01*
X351650Y-524112D01*
X350750Y-524646D01*
G01X358350Y-532246D02*
X361950Y-523979D01*
G01X368150D02*
X367350Y-524246D01*
X366750Y-524912D01*
X366350Y-525712D01*
X366050Y-526779D01*
X365950Y-527979D01*
X366050Y-529179D01*
X366350Y-530246D01*
X366750Y-531046D01*
X367350Y-531712D01*
X368150Y-531979D01*
X368950Y-531712D01*
X369550Y-531046D01*
X369950Y-530246D01*
X370250Y-529179D01*
X370350Y-527979D01*
X370250Y-526779D01*
X369950Y-525712D01*
X369550Y-524912D01*
X368950Y-524246D01*
X368150Y-523979D01*
G01X373950Y-530379D02*
X374550Y-531312D01*
X375350Y-531846D01*
X376250Y-531979D01*
X377050Y-531846D01*
X377850Y-531179D01*
X378350Y-530379D01*
X378450Y-529579D01*
X378250Y-528646D01*
X377550Y-527979D01*
X376850Y-527712D01*
X375950D01*
G01X376850D02*
X377450Y-527312D01*
X377950Y-526646D01*
X378150Y-525846D01*
X377950Y-525046D01*
X377450Y-524379D01*
X376550Y-523979D01*
X375650Y-524112D01*
X374750Y-524646D01*
G01X382350Y-532246D02*
X385950Y-523979D01*
G01X390250Y-525312D02*
X390850Y-524512D01*
X391550Y-524112D01*
X392350Y-523979D01*
X393350Y-524246D01*
X394050Y-524912D01*
X394250Y-525712D01*
X394150Y-526513D01*
X393750Y-527179D01*
X391750Y-528512D01*
X390850Y-529446D01*
X390250Y-530779D01*
X390050Y-531979D01*
X394250D01*
G01X401350D02*
Y-523979D01*
X397650Y-529712D01*
X402650D01*
G01X325950Y-506979D02*
Y-498979D01*
X327950D01*
X328750Y-499379D01*
X329350Y-499912D01*
X329850Y-500712D01*
X330250Y-501646D01*
X330350Y-502979D01*
X330250Y-504312D01*
X329850Y-505246D01*
X329350Y-506046D01*
X328750Y-506579D01*
X327950Y-506979D01*
X325950D01*
G01X333650D02*
X336150Y-498979D01*
X338650Y-506979D01*
G01X337750Y-504179D02*
X334550D01*
G01X344150Y-498979D02*
X343350Y-499246D01*
X342750Y-499912D01*
X342350Y-500712D01*
X342050Y-501779D01*
X341950Y-502979D01*
X342050Y-504179D01*
X342350Y-505246D01*
X342750Y-506046D01*
X343350Y-506712D01*
X344150Y-506979D01*
X344950Y-506712D01*
X345550Y-506046D01*
X345950Y-505246D01*
X346250Y-504179D01*
X346350Y-502979D01*
X346250Y-501779D01*
X345950Y-500712D01*
X345550Y-499912D01*
X344950Y-499246D01*
X344150Y-498979D01*
G01X350250Y-506979D02*
Y-498979D01*
X354050D01*
G01X352650Y-502846D02*
X350250D01*
G01X360150Y-498979D02*
X359350Y-499246D01*
X358750Y-499912D01*
X358350Y-500712D01*
X358050Y-501779D01*
X357950Y-502979D01*
X358050Y-504179D01*
X358350Y-505246D01*
X358750Y-506046D01*
X359350Y-506712D01*
X360150Y-506979D01*
X360950Y-506712D01*
X361550Y-506046D01*
X361950Y-505246D01*
X362250Y-504179D01*
X362350Y-502979D01*
X362250Y-501779D01*
X361950Y-500712D01*
X361550Y-499912D01*
X360950Y-499246D01*
X360150Y-498979D01*
G01X368150D02*
Y-506979D01*
G01X365850Y-498979D02*
X370450D01*
G01X373550Y-506979D02*
Y-498979D01*
X376150Y-505646D01*
X378750Y-498979D01*
Y-506979D01*
G01X384950Y-502712D02*
X385350Y-502312D01*
X385650Y-501646D01*
X385850Y-500712D01*
X385650Y-499912D01*
X385250Y-499379D01*
X384550Y-498979D01*
X381850D01*
Y-506979D01*
X385150D01*
X385850Y-506446D01*
X386250Y-505646D01*
X386450Y-504712D01*
X386250Y-503779D01*
X385650Y-502979D01*
X384950Y-502712D01*
X381850D01*
G01X390950Y-498979D02*
X393350D01*
G01X392150D02*
Y-506979D01*
G01X390950D02*
X393350D01*
G01X398150Y-505379D02*
X398650Y-506179D01*
X399250Y-506712D01*
X399950Y-506979D01*
X400750Y-506712D01*
X401350Y-506179D01*
X401950Y-505379D01*
X402150Y-504312D01*
Y-498979D01*
G01X408150D02*
X407350Y-499246D01*
X406750Y-499912D01*
X406350Y-500712D01*
X406050Y-501779D01*
X405950Y-502979D01*
X406050Y-504179D01*
X406350Y-505246D01*
X406750Y-506046D01*
X407350Y-506712D01*
X408150Y-506979D01*
X408950Y-506712D01*
X409550Y-506046D01*
X409950Y-505246D01*
X410250Y-504179D01*
X410350Y-502979D01*
X410250Y-501779D01*
X409950Y-500712D01*
X409550Y-499912D01*
X408950Y-499246D01*
X408150Y-498979D01*
G01X343024Y-369187D02*
X344483Y-368257D01*
X345316Y-367017D01*
X345524Y-365622D01*
X345316Y-364382D01*
X344274Y-363142D01*
X343024Y-362367D01*
X341774Y-362212D01*
X340316Y-362522D01*
X339274Y-363607D01*
X338857Y-364692D01*
Y-366087D01*
G01Y-364692D02*
X338232Y-363762D01*
X337191Y-362987D01*
X335941Y-362677D01*
X334691Y-362987D01*
X333649Y-363762D01*
X333024Y-365157D01*
X333232Y-366552D01*
X334066Y-367947D01*
G01X343649Y-356787D02*
X344691Y-355857D01*
X345316Y-354772D01*
X345524Y-353377D01*
X345107Y-351982D01*
X344274Y-350897D01*
X342816Y-350122D01*
X341149Y-349967D01*
X339482Y-350277D01*
X338441Y-351052D01*
X337607Y-352137D01*
X337399Y-353222D01*
X337607Y-354307D01*
X338441Y-355702D01*
X333024Y-355237D01*
Y-351052D01*
G01Y-340977D02*
X333441Y-342217D01*
X334482Y-343147D01*
X335732Y-343767D01*
X337399Y-344232D01*
X339274Y-344387D01*
X341149Y-344232D01*
X342816Y-343767D01*
X344066Y-343147D01*
X345107Y-342217D01*
X345524Y-340977D01*
X345107Y-339737D01*
X344066Y-338807D01*
X342816Y-338187D01*
X341149Y-337722D01*
X339274Y-337567D01*
X337399Y-337722D01*
X335732Y-338187D01*
X334482Y-338807D01*
X333441Y-339737D01*
X333024Y-340977D01*
G01Y-328577D02*
X333441Y-329817D01*
X334482Y-330747D01*
X335732Y-331367D01*
X337399Y-331832D01*
X339274Y-331987D01*
X341149Y-331832D01*
X342816Y-331367D01*
X344066Y-330747D01*
X345107Y-329817D01*
X345524Y-328577D01*
X345107Y-327337D01*
X344066Y-326407D01*
X342816Y-325787D01*
X341149Y-325322D01*
X339274Y-325167D01*
X337399Y-325322D01*
X335732Y-325787D01*
X334482Y-326407D01*
X333441Y-327337D01*
X333024Y-328577D01*
G01X345941Y-316177D02*
X345732Y-316487D01*
X345316D01*
X345107Y-316177D01*
X345316Y-315867D01*
X345732D01*
X345941Y-316177D01*
G01X344066Y-306412D02*
X345107Y-305327D01*
X345524Y-304087D01*
X345107Y-302847D01*
X343858Y-301762D01*
X341982Y-300987D01*
X340107Y-300677D01*
X337816D01*
X335941Y-300987D01*
X334274Y-301762D01*
X333441Y-302692D01*
X333024Y-303777D01*
X333441Y-305017D01*
X334274Y-305947D01*
X335524Y-306567D01*
X337191Y-306877D01*
X338649Y-306567D01*
X340107Y-305792D01*
X340941Y-304862D01*
X341149Y-303777D01*
X340733Y-302537D01*
X339691Y-301607D01*
X337816Y-300677D01*
G01X344066Y-294012D02*
X345107Y-292927D01*
X345524Y-291687D01*
X345107Y-290447D01*
X343858Y-289362D01*
X341982Y-288587D01*
X340107Y-288277D01*
X337816D01*
X335941Y-288587D01*
X334274Y-289362D01*
X333441Y-290292D01*
X333024Y-291377D01*
X333441Y-292617D01*
X334274Y-293547D01*
X335524Y-294167D01*
X337191Y-294477D01*
X338649Y-294167D01*
X340107Y-293392D01*
X340941Y-292462D01*
X341149Y-291377D01*
X340733Y-290137D01*
X339691Y-289207D01*
X337816Y-288277D01*
G01X345524Y-256777D02*
X345316Y-255692D01*
X344691Y-254452D01*
X343649Y-253677D01*
X342191Y-253367D01*
X340733Y-253677D01*
X339482Y-254607D01*
X338857Y-256002D01*
Y-257552D01*
X338441Y-258482D01*
X337399Y-259257D01*
X335941Y-259567D01*
X334482Y-259102D01*
X333441Y-258017D01*
X333024Y-256777D01*
X333441Y-255537D01*
X334482Y-254452D01*
X335941Y-253987D01*
X337399Y-254297D01*
X338441Y-255072D01*
X338857Y-256002D01*
Y-257552D01*
X339482Y-258947D01*
X340733Y-259877D01*
X342191Y-260187D01*
X343649Y-259877D01*
X344691Y-259102D01*
X345316Y-257862D01*
X345524Y-256777D01*
G01Y-244377D02*
X345316Y-243292D01*
X344691Y-242052D01*
X343649Y-241277D01*
X342191Y-240967D01*
X340733Y-241277D01*
X339482Y-242207D01*
X338857Y-243602D01*
Y-245152D01*
X338441Y-246082D01*
X337399Y-246857D01*
X335941Y-247167D01*
X334482Y-246702D01*
X333441Y-245617D01*
X333024Y-244377D01*
X333441Y-243137D01*
X334482Y-242052D01*
X335941Y-241587D01*
X337399Y-241897D01*
X338441Y-242672D01*
X338857Y-243602D01*
Y-245152D01*
X339482Y-246547D01*
X340733Y-247477D01*
X342191Y-247787D01*
X343649Y-247477D01*
X344691Y-246702D01*
X345316Y-245462D01*
X345524Y-244377D01*
G01X345941Y-231977D02*
X345732Y-232287D01*
X345316D01*
X345107Y-231977D01*
X345316Y-231667D01*
X345732D01*
X345941Y-231977D01*
G01X344066Y-222212D02*
X345107Y-221127D01*
X345524Y-219887D01*
X345107Y-218647D01*
X343858Y-217562D01*
X341982Y-216787D01*
X340107Y-216477D01*
X337816D01*
X335941Y-216787D01*
X334274Y-217562D01*
X333441Y-218492D01*
X333024Y-219577D01*
X333441Y-220817D01*
X334274Y-221747D01*
X335524Y-222367D01*
X337191Y-222677D01*
X338649Y-222367D01*
X340107Y-221592D01*
X340941Y-220662D01*
X341149Y-219577D01*
X340733Y-218337D01*
X339691Y-217407D01*
X337816Y-216477D01*
G01X343024Y-210587D02*
X344483Y-209657D01*
X345316Y-208417D01*
X345524Y-207022D01*
X345316Y-205782D01*
X344274Y-204542D01*
X343024Y-203767D01*
X341774Y-203612D01*
X340316Y-203922D01*
X339274Y-205007D01*
X338857Y-206092D01*
Y-207487D01*
G01Y-206092D02*
X338232Y-205162D01*
X337191Y-204387D01*
X335941Y-204077D01*
X334691Y-204387D01*
X333649Y-205162D01*
X333024Y-206557D01*
X333232Y-207952D01*
X334066Y-209347D01*
G01X339705Y1676732D02*
G03I-2500J0D01*
G01X331831Y1672795D02*
G03I-2500J0D01*
G01X339705Y1690905D02*
G03I-2500J0D01*
G01X331831Y1686968D02*
G03I-2500J0D01*
G01X339705Y1705078D02*
G03I-2500J0D01*
G01X331831Y1701141D02*
G03I-2500J0D01*
G01Y1715314D02*
G03I-2500J0D01*
G01X339705Y1719251D02*
G03I-2500J0D01*
G01X331831Y1729488D02*
G03I-2500J0D01*
G01X339705Y1733425D02*
G03I-2500J0D01*
G01X343750Y-481979D02*
Y-473979D01*
X347550D01*
G01X346150Y-477846D02*
X343750D01*
G01X353650Y-473979D02*
X352850Y-474246D01*
X352250Y-474912D01*
X351850Y-475712D01*
X351550Y-476779D01*
X351450Y-477979D01*
X351550Y-479179D01*
X351850Y-480246D01*
X352250Y-481046D01*
X352850Y-481712D01*
X353650Y-481979D01*
X354450Y-481712D01*
X355050Y-481046D01*
X355450Y-480246D01*
X355750Y-479179D01*
X355850Y-477979D01*
X355750Y-476779D01*
X355450Y-475712D01*
X355050Y-474912D01*
X354450Y-474246D01*
X353650Y-473979D01*
G01X361650D02*
Y-481979D01*
G01X359350Y-473979D02*
X363950D01*
G01X366650Y-484646D02*
X372650D01*
G01X375050Y-481979D02*
Y-473979D01*
X377650Y-480646D01*
X380250Y-473979D01*
Y-481979D01*
G01X386450Y-477712D02*
X386850Y-477312D01*
X387150Y-476646D01*
X387350Y-475712D01*
X387150Y-474912D01*
X386750Y-474379D01*
X386050Y-473979D01*
X383350D01*
Y-481979D01*
X386650D01*
X387350Y-481446D01*
X387750Y-480646D01*
X387950Y-479712D01*
X387750Y-478779D01*
X387150Y-477979D01*
X386450Y-477712D01*
X383350D01*
G01X390650Y-484646D02*
X396650D01*
G01X403650Y-481979D02*
X399650D01*
Y-473979D01*
X403650D01*
G01X402050Y-477846D02*
X399650D01*
G01X407050Y-481979D02*
Y-473979D01*
X409650Y-480646D01*
X412250Y-473979D01*
Y-481979D01*
G01X417650D02*
X418350Y-481846D01*
X419150Y-481446D01*
X419650Y-480779D01*
X419850Y-479846D01*
X419650Y-478913D01*
X419050Y-478112D01*
X418150Y-477712D01*
X417150D01*
X416550Y-477446D01*
X416050Y-476779D01*
X415850Y-475846D01*
X416150Y-474912D01*
X416850Y-474246D01*
X417650Y-473979D01*
X418450Y-474246D01*
X419150Y-474912D01*
X419450Y-475846D01*
X419250Y-476779D01*
X418750Y-477446D01*
X418150Y-477712D01*
X417150D01*
X416250Y-478112D01*
X415650Y-478913D01*
X415450Y-479846D01*
X415650Y-480779D01*
X416150Y-481446D01*
X416950Y-481846D01*
X417650Y-481979D01*
G01X423950Y-481046D02*
X424650Y-481712D01*
X425450Y-481979D01*
X426250Y-481712D01*
X426950Y-480913D01*
X427450Y-479712D01*
X427650Y-478512D01*
Y-477046D01*
X427450Y-475846D01*
X426950Y-474779D01*
X426350Y-474246D01*
X425650Y-473979D01*
X424850Y-474246D01*
X424250Y-474779D01*
X423850Y-475579D01*
X423650Y-476646D01*
X423850Y-477579D01*
X424350Y-478512D01*
X424950Y-479046D01*
X425650Y-479179D01*
X426450Y-478913D01*
X427050Y-478246D01*
X427650Y-477046D01*
G01X433650Y-473979D02*
X432850Y-474246D01*
X432250Y-474912D01*
X431850Y-475712D01*
X431550Y-476779D01*
X431450Y-477979D01*
X431550Y-479179D01*
X431850Y-480246D01*
X432250Y-481046D01*
X432850Y-481712D01*
X433650Y-481979D01*
X434450Y-481712D01*
X435050Y-481046D01*
X435450Y-480246D01*
X435750Y-479179D01*
X435850Y-477979D01*
X435750Y-476779D01*
X435450Y-475712D01*
X435050Y-474912D01*
X434450Y-474246D01*
X433650Y-473979D01*
G01X439450Y-481979D02*
Y-473979D01*
G01X443250D02*
X439450Y-478913D01*
G01X443850Y-481979D02*
X441150Y-476646D01*
G01X359813Y-369072D02*
X361272Y-368142D01*
X362105Y-366902D01*
X362313Y-365507D01*
X362105Y-364267D01*
X361063Y-363027D01*
X359813Y-362252D01*
X358563Y-362097D01*
X357105Y-362407D01*
X356063Y-363492D01*
X355646Y-364577D01*
Y-365972D01*
G01Y-364577D02*
X355021Y-363647D01*
X353980Y-362872D01*
X352730Y-362562D01*
X351480Y-362872D01*
X350438Y-363647D01*
X349813Y-365042D01*
X350021Y-366437D01*
X350855Y-367832D01*
G01X360438Y-356672D02*
X361480Y-355742D01*
X362105Y-354657D01*
X362313Y-353262D01*
X361896Y-351867D01*
X361063Y-350782D01*
X359605Y-350007D01*
X357938Y-349852D01*
X356271Y-350162D01*
X355230Y-350937D01*
X354396Y-352022D01*
X354188Y-353107D01*
X354396Y-354192D01*
X355230Y-355587D01*
X349813Y-355122D01*
Y-350937D01*
G01X357105Y-343807D02*
X355646Y-342722D01*
X354813Y-341792D01*
X354396Y-340552D01*
X354813Y-339467D01*
X355646Y-338692D01*
X356896Y-338072D01*
X358355Y-337917D01*
X359605Y-338072D01*
X360855Y-338692D01*
X361896Y-339622D01*
X362313Y-340707D01*
X361896Y-341947D01*
X360647Y-343032D01*
X358771Y-343652D01*
X356688Y-343807D01*
X353980Y-343497D01*
X352521Y-343032D01*
X351063Y-342257D01*
X350021Y-341172D01*
X349813Y-340087D01*
X350230Y-339002D01*
X351271Y-338227D01*
G01X349813Y-328462D02*
X350230Y-329702D01*
X351271Y-330632D01*
X352521Y-331252D01*
X354188Y-331717D01*
X356063Y-331872D01*
X357938Y-331717D01*
X359605Y-331252D01*
X360855Y-330632D01*
X361896Y-329702D01*
X362313Y-328462D01*
X361896Y-327222D01*
X360855Y-326292D01*
X359605Y-325672D01*
X357938Y-325207D01*
X356063Y-325052D01*
X354188Y-325207D01*
X352521Y-325672D01*
X351271Y-326292D01*
X350230Y-327222D01*
X349813Y-328462D01*
G01X362730Y-316062D02*
X362521Y-316372D01*
X362105D01*
X361896Y-316062D01*
X362105Y-315752D01*
X362521D01*
X362730Y-316062D01*
G01X357105Y-306607D02*
X355646Y-305522D01*
X354813Y-304592D01*
X354396Y-303352D01*
X354813Y-302267D01*
X355646Y-301492D01*
X356896Y-300872D01*
X358355Y-300717D01*
X359605Y-300872D01*
X360855Y-301492D01*
X361896Y-302422D01*
X362313Y-303507D01*
X361896Y-304747D01*
X360647Y-305832D01*
X358771Y-306452D01*
X356688Y-306607D01*
X353980Y-306297D01*
X352521Y-305832D01*
X351063Y-305057D01*
X350021Y-303972D01*
X349813Y-302887D01*
X350230Y-301802D01*
X351271Y-301027D01*
G01X359813Y-294672D02*
X361272Y-293742D01*
X362105Y-292502D01*
X362313Y-291107D01*
X362105Y-289867D01*
X361063Y-288627D01*
X359813Y-287852D01*
X358563Y-287697D01*
X357105Y-288007D01*
X356063Y-289092D01*
X355646Y-290177D01*
Y-291572D01*
G01Y-290177D02*
X355021Y-289247D01*
X353980Y-288472D01*
X352730Y-288162D01*
X351480Y-288472D01*
X350438Y-289247D01*
X349813Y-290642D01*
X350021Y-292037D01*
X350855Y-293432D01*
G01X360855Y-259297D02*
X361896Y-258212D01*
X362313Y-256972D01*
X361896Y-255732D01*
X360647Y-254647D01*
X358771Y-253872D01*
X356896Y-253562D01*
X354605D01*
X352730Y-253872D01*
X351063Y-254647D01*
X350230Y-255577D01*
X349813Y-256662D01*
X350230Y-257902D01*
X351063Y-258832D01*
X352313Y-259452D01*
X353980Y-259762D01*
X355438Y-259452D01*
X356896Y-258677D01*
X357730Y-257747D01*
X357938Y-256662D01*
X357522Y-255422D01*
X356480Y-254492D01*
X354605Y-253562D01*
G01X349813Y-244262D02*
X350230Y-245502D01*
X351271Y-246432D01*
X352521Y-247052D01*
X354188Y-247517D01*
X356063Y-247672D01*
X357938Y-247517D01*
X359605Y-247052D01*
X360855Y-246432D01*
X361896Y-245502D01*
X362313Y-244262D01*
X361896Y-243022D01*
X360855Y-242092D01*
X359605Y-241472D01*
X357938Y-241007D01*
X356063Y-240852D01*
X354188Y-241007D01*
X352521Y-241472D01*
X351271Y-242092D01*
X350230Y-243022D01*
X349813Y-244262D01*
G01X362730Y-231862D02*
X362521Y-232172D01*
X362105D01*
X361896Y-231862D01*
X362105Y-231552D01*
X362521D01*
X362730Y-231862D01*
G01X362313Y-217602D02*
X349813D01*
X358771Y-223337D01*
Y-215587D01*
G01X362313Y-205202D02*
X349813D01*
X358771Y-210937D01*
Y-203187D01*
G01X355028Y824653D02*
Y832153D01*
X359322Y824653D01*
Y832153D01*
G01X362808Y824653D02*
Y832153D01*
X365048D01*
X365795Y831778D01*
X366355Y830903D01*
X366542Y829903D01*
X366355Y828903D01*
X365888Y828153D01*
X365048Y827778D01*
X362808D01*
G01X372175Y832153D02*
Y824653D01*
G01X370028Y832153D02*
X374322D01*
G01X377715Y824653D02*
Y832153D01*
G01X381635D02*
Y824653D01*
G01Y828403D02*
X377715D01*
G01X355453Y1676732D02*
G03I-2500J0D01*
G01X347579Y1672795D02*
G03I-2500J0D01*
G01X355453Y1690905D02*
G03I-2500J0D01*
G01X347579Y1686968D02*
G03I-2500J0D01*
G01X355453Y1705078D02*
G03I-2500J0D01*
G01X347579Y1701141D02*
G03I-2500J0D01*
G01Y1715314D02*
G03I-2500J0D01*
G01X355453Y1719251D02*
G03I-2500J0D01*
G01X347579Y1729488D02*
G03I-2500J0D01*
G01X355453Y1733425D02*
G03I-2500J0D01*
G01X376000Y-368720D02*
X377459Y-367790D01*
X378292Y-366550D01*
X378500Y-365155D01*
X378292Y-363915D01*
X377250Y-362675D01*
X376000Y-361900D01*
X374750Y-361745D01*
X373292Y-362055D01*
X372250Y-363140D01*
X371833Y-364225D01*
Y-365620D01*
G01Y-364225D02*
X371208Y-363295D01*
X370167Y-362520D01*
X368917Y-362210D01*
X367667Y-362520D01*
X366625Y-363295D01*
X366000Y-364690D01*
X366208Y-366085D01*
X367042Y-367480D01*
G01X373292Y-355855D02*
X371833Y-354770D01*
X371000Y-353840D01*
X370583Y-352600D01*
X371000Y-351515D01*
X371833Y-350740D01*
X373083Y-350120D01*
X374542Y-349965D01*
X375792Y-350120D01*
X377042Y-350740D01*
X378083Y-351670D01*
X378500Y-352755D01*
X378083Y-353995D01*
X376834Y-355080D01*
X374958Y-355700D01*
X372875Y-355855D01*
X370167Y-355545D01*
X368708Y-355080D01*
X367250Y-354305D01*
X366208Y-353220D01*
X366000Y-352135D01*
X366417Y-351050D01*
X367458Y-350275D01*
G01X378500Y-340510D02*
X378292Y-339425D01*
X377667Y-338185D01*
X376625Y-337410D01*
X375167Y-337100D01*
X373709Y-337410D01*
X372458Y-338340D01*
X371833Y-339735D01*
Y-341285D01*
X371417Y-342215D01*
X370375Y-342990D01*
X368917Y-343300D01*
X367458Y-342835D01*
X366417Y-341750D01*
X366000Y-340510D01*
X366417Y-339270D01*
X367458Y-338185D01*
X368917Y-337720D01*
X370375Y-338030D01*
X371417Y-338805D01*
X371833Y-339735D01*
Y-341285D01*
X372458Y-342680D01*
X373709Y-343610D01*
X375167Y-343920D01*
X376625Y-343610D01*
X377667Y-342835D01*
X378292Y-341595D01*
X378500Y-340510D01*
G01Y-326250D02*
X366000D01*
X374958Y-331985D01*
Y-324235D01*
G01X378917Y-315710D02*
X378708Y-316020D01*
X378292D01*
X378083Y-315710D01*
X378292Y-315400D01*
X378708D01*
X378917Y-315710D01*
G01X376000Y-306720D02*
X377459Y-305790D01*
X378292Y-304550D01*
X378500Y-303155D01*
X378292Y-301915D01*
X377250Y-300675D01*
X376000Y-299900D01*
X374750Y-299745D01*
X373292Y-300055D01*
X372250Y-301140D01*
X371833Y-302225D01*
Y-303620D01*
G01Y-302225D02*
X371208Y-301295D01*
X370167Y-300520D01*
X368917Y-300210D01*
X367667Y-300520D01*
X366625Y-301295D01*
X366000Y-302690D01*
X366208Y-304085D01*
X367042Y-305480D01*
G01X378500Y-291220D02*
X375792Y-290910D01*
X373500Y-290445D01*
X371417Y-289825D01*
X369125Y-289050D01*
X366000Y-287810D01*
Y-294010D01*
G01X377042Y-258945D02*
X378083Y-257860D01*
X378500Y-256620D01*
X378083Y-255380D01*
X376834Y-254295D01*
X374958Y-253520D01*
X373083Y-253210D01*
X370792D01*
X368917Y-253520D01*
X367250Y-254295D01*
X366417Y-255225D01*
X366000Y-256310D01*
X366417Y-257550D01*
X367250Y-258480D01*
X368500Y-259100D01*
X370167Y-259410D01*
X371625Y-259100D01*
X373083Y-258325D01*
X373917Y-257395D01*
X374125Y-256310D01*
X373709Y-255070D01*
X372667Y-254140D01*
X370792Y-253210D01*
G01X376000Y-247320D02*
X377459Y-246390D01*
X378292Y-245150D01*
X378500Y-243755D01*
X378292Y-242515D01*
X377250Y-241275D01*
X376000Y-240500D01*
X374750Y-240345D01*
X373292Y-240655D01*
X372250Y-241740D01*
X371833Y-242825D01*
Y-244220D01*
G01Y-242825D02*
X371208Y-241895D01*
X370167Y-241120D01*
X368917Y-240810D01*
X367667Y-241120D01*
X366625Y-241895D01*
X366000Y-243290D01*
X366208Y-244685D01*
X367042Y-246080D01*
G01X378917Y-231510D02*
X378708Y-231820D01*
X378292D01*
X378083Y-231510D01*
X378292Y-231200D01*
X378708D01*
X378917Y-231510D01*
G01X376625Y-222520D02*
X377667Y-221590D01*
X378292Y-220505D01*
X378500Y-219110D01*
X378083Y-217715D01*
X377250Y-216630D01*
X375792Y-215855D01*
X374125Y-215700D01*
X372458Y-216010D01*
X371417Y-216785D01*
X370583Y-217870D01*
X370375Y-218955D01*
X370583Y-220040D01*
X371417Y-221435D01*
X366000Y-220970D01*
Y-216785D01*
G01X378500Y-206710D02*
X378292Y-205625D01*
X377667Y-204385D01*
X376625Y-203610D01*
X375167Y-203300D01*
X373709Y-203610D01*
X372458Y-204540D01*
X371833Y-205935D01*
Y-207485D01*
X371417Y-208415D01*
X370375Y-209190D01*
X368917Y-209500D01*
X367458Y-209035D01*
X366417Y-207950D01*
X366000Y-206710D01*
X366417Y-205470D01*
X367458Y-204385D01*
X368917Y-203920D01*
X370375Y-204230D01*
X371417Y-205005D01*
X371833Y-205935D01*
Y-207485D01*
X372458Y-208880D01*
X373709Y-209810D01*
X375167Y-210120D01*
X376625Y-209810D01*
X377667Y-209035D01*
X378292Y-207795D01*
X378500Y-206710D01*
G01X360681Y1186321D02*
Y1193821D01*
X364975Y1186321D01*
Y1193821D01*
G01X368461Y1186321D02*
Y1193821D01*
X370701D01*
X371448Y1193446D01*
X372008Y1192571D01*
X372195Y1191571D01*
X372008Y1190571D01*
X371541Y1189821D01*
X370701Y1189446D01*
X368461D01*
G01X377828Y1193821D02*
Y1186321D01*
G01X375681Y1193821D02*
X379975D01*
G01X383368Y1186321D02*
Y1193821D01*
G01X387288D02*
Y1186321D01*
G01Y1190071D02*
X383368D01*
G01X391265Y-356553D02*
X392724Y-355623D01*
X393557Y-354383D01*
X393765Y-352988D01*
X393557Y-351748D01*
X392515Y-350508D01*
X391265Y-349733D01*
X390015Y-349578D01*
X388557Y-349888D01*
X387515Y-350973D01*
X387098Y-352058D01*
Y-353453D01*
G01Y-352058D02*
X386473Y-351128D01*
X385432Y-350353D01*
X384182Y-350043D01*
X382932Y-350353D01*
X381890Y-351128D01*
X381265Y-352523D01*
X381473Y-353918D01*
X382307Y-355313D01*
G01X393765Y-341053D02*
X391057Y-340743D01*
X388765Y-340278D01*
X386682Y-339658D01*
X384390Y-338883D01*
X381265Y-337643D01*
Y-343843D01*
G01X391265Y-331753D02*
X392724Y-330823D01*
X393557Y-329583D01*
X393765Y-328188D01*
X393557Y-326948D01*
X392515Y-325708D01*
X391265Y-324933D01*
X390015Y-324778D01*
X388557Y-325088D01*
X387515Y-326173D01*
X387098Y-327258D01*
Y-328653D01*
G01Y-327258D02*
X386473Y-326328D01*
X385432Y-325553D01*
X384182Y-325243D01*
X382932Y-325553D01*
X381890Y-326328D01*
X381265Y-327723D01*
X381473Y-329118D01*
X382307Y-330513D01*
G01X388557Y-318888D02*
X387098Y-317803D01*
X386265Y-316873D01*
X385848Y-315633D01*
X386265Y-314548D01*
X387098Y-313773D01*
X388348Y-313153D01*
X389807Y-312998D01*
X391057Y-313153D01*
X392307Y-313773D01*
X393348Y-314703D01*
X393765Y-315788D01*
X393348Y-317028D01*
X392099Y-318113D01*
X390223Y-318733D01*
X388140Y-318888D01*
X385432Y-318578D01*
X383973Y-318113D01*
X382515Y-317338D01*
X381473Y-316253D01*
X381265Y-315168D01*
X381682Y-314083D01*
X382723Y-313308D01*
G01X394182Y-303543D02*
X393973Y-303853D01*
X393557D01*
X393348Y-303543D01*
X393557Y-303233D01*
X393973D01*
X394182Y-303543D01*
G01X383348Y-294088D02*
X382099Y-293158D01*
X381473Y-292073D01*
X381265Y-290833D01*
X381682Y-289283D01*
X382723Y-288198D01*
X383973Y-287888D01*
X385224Y-288043D01*
X386265Y-288663D01*
X388348Y-291763D01*
X389807Y-293158D01*
X391890Y-294088D01*
X393765Y-294398D01*
Y-287888D01*
G01X383348Y-281688D02*
X382099Y-280758D01*
X381473Y-279673D01*
X381265Y-278433D01*
X381682Y-276883D01*
X382723Y-275798D01*
X383973Y-275488D01*
X385224Y-275643D01*
X386265Y-276263D01*
X388348Y-279363D01*
X389807Y-280758D01*
X391890Y-281688D01*
X393765Y-281998D01*
Y-275488D01*
G01X392307Y-246778D02*
X393348Y-245693D01*
X393765Y-244453D01*
X393348Y-243213D01*
X392099Y-242128D01*
X390223Y-241353D01*
X388348Y-241043D01*
X386057D01*
X384182Y-241353D01*
X382515Y-242128D01*
X381682Y-243058D01*
X381265Y-244143D01*
X381682Y-245383D01*
X382515Y-246313D01*
X383765Y-246933D01*
X385432Y-247243D01*
X386890Y-246933D01*
X388348Y-246158D01*
X389182Y-245228D01*
X389390Y-244143D01*
X388974Y-242903D01*
X387932Y-241973D01*
X386057Y-241043D01*
G01X393765Y-229883D02*
X381265D01*
X390223Y-235618D01*
Y-227868D01*
G01X394182Y-219343D02*
X393973Y-219653D01*
X393557D01*
X393348Y-219343D01*
X393557Y-219033D01*
X393973D01*
X394182Y-219343D01*
G01X392307Y-209578D02*
X393348Y-208493D01*
X393765Y-207253D01*
X393348Y-206013D01*
X392099Y-204928D01*
X390223Y-204153D01*
X388348Y-203843D01*
X386057D01*
X384182Y-204153D01*
X382515Y-204928D01*
X381682Y-205858D01*
X381265Y-206943D01*
X381682Y-208183D01*
X382515Y-209113D01*
X383765Y-209733D01*
X385432Y-210043D01*
X386890Y-209733D01*
X388348Y-208958D01*
X389182Y-208028D01*
X389390Y-206943D01*
X388974Y-205703D01*
X387932Y-204773D01*
X386057Y-203843D01*
G01X376943Y160350D02*
Y167850D01*
X381237Y160350D01*
Y167850D01*
G01X384723Y160350D02*
Y167850D01*
X386963D01*
X387710Y167475D01*
X388270Y166600D01*
X388457Y165600D01*
X388270Y164600D01*
X387803Y163850D01*
X386963Y163475D01*
X384723D01*
G01X394090Y167850D02*
Y160350D01*
G01X391943Y167850D02*
X396237D01*
G01X399630Y160350D02*
Y167850D01*
G01X403550D02*
Y160350D01*
G01Y164100D02*
X399630D01*
G01X391468Y2020163D02*
X383968D01*
X390218Y2022590D01*
X383968Y2025017D01*
X391468D01*
G01Y2027757D02*
X383968Y2030090D01*
X391468Y2032423D01*
G01X388843Y2031583D02*
Y2028597D01*
G01X391468Y2035723D02*
X383968D01*
Y2038057D01*
X384343Y2038803D01*
X384843Y2039270D01*
X385843Y2039457D01*
X386843Y2039270D01*
X387468Y2038710D01*
X387843Y2038057D01*
Y2035723D01*
G01Y2038057D02*
X391468Y2039457D01*
G01Y2043037D02*
X383968D01*
G01Y2046583D02*
X388593Y2043037D01*
G01X391468Y2047143D02*
X386468Y2044623D01*
G01X391718Y2052590D02*
X391593Y2052403D01*
X391343D01*
X391218Y2052590D01*
X391343Y2052777D01*
X391593D01*
X391718Y2052590D01*
G01X388343D02*
X388218Y2052403D01*
X387968D01*
X387843Y2052590D01*
X387968Y2052777D01*
X388218D01*
X388343Y2052590D01*
G01X383968Y2060090D02*
X391468D01*
G01X383968Y2057943D02*
Y2062237D01*
G01Y2066470D02*
Y2068710D01*
G01Y2067590D02*
X391468D01*
G01Y2066470D02*
Y2068710D01*
G01Y2072943D02*
X383968D01*
X391468Y2077237D01*
X383968D01*
G01Y2088223D02*
X391468D01*
Y2091957D01*
G01Y2099457D02*
Y2095723D01*
X383968D01*
Y2099457D01*
G01X387593Y2097963D02*
Y2095723D01*
G01X391468Y2102757D02*
X383968Y2105090D01*
X391468Y2107423D01*
G01X388843Y2106583D02*
Y2103597D01*
G01X391468Y2110537D02*
X383968D01*
Y2112403D01*
X384343Y2113150D01*
X384843Y2113710D01*
X385593Y2114177D01*
X386468Y2114550D01*
X387718Y2114643D01*
X388968Y2114550D01*
X389843Y2114177D01*
X390593Y2113710D01*
X391093Y2113150D01*
X391468Y2112403D01*
Y2110537D01*
G01X391718Y2120090D02*
X391593Y2119903D01*
X391343D01*
X391218Y2120090D01*
X391343Y2120277D01*
X391593D01*
X391718Y2120090D01*
G01X388343D02*
X388218Y2119903D01*
X387968D01*
X387843Y2120090D01*
X387968Y2120277D01*
X388218D01*
X388343Y2120090D01*
G01X391468Y2125723D02*
X383968D01*
Y2128057D01*
X384343Y2128803D01*
X384843Y2129270D01*
X385843Y2129457D01*
X386843Y2129270D01*
X387468Y2128710D01*
X387843Y2128057D01*
Y2125723D01*
G01Y2128057D02*
X391468Y2129457D01*
G01Y2136957D02*
Y2133223D01*
X383968D01*
Y2136957D01*
G01X387593Y2135463D02*
Y2133223D01*
G01X384593Y2144643D02*
X384218Y2144083D01*
X383968Y2143430D01*
Y2142683D01*
X384343Y2141843D01*
X384968Y2141190D01*
X385718Y2140723D01*
X386968Y2140350D01*
X388093Y2140257D01*
X389218Y2140443D01*
X389968Y2140723D01*
X390718Y2141283D01*
X391218Y2141937D01*
X391468Y2142590D01*
Y2143243D01*
X391218Y2143897D01*
X390843Y2144457D01*
X390343Y2144923D01*
G01X391468Y2150090D02*
X391343Y2149343D01*
X390843Y2148690D01*
X390093Y2148130D01*
X389218Y2147757D01*
X388218Y2147570D01*
X387218D01*
X386218Y2147757D01*
X385343Y2148130D01*
X384593Y2148690D01*
X384093Y2149343D01*
X383968Y2150090D01*
X384093Y2150837D01*
X384593Y2151490D01*
X385343Y2152050D01*
X386218Y2152423D01*
X387218Y2152610D01*
X388218D01*
X389218Y2152423D01*
X390093Y2152050D01*
X390843Y2151490D01*
X391343Y2150837D01*
X391468Y2150090D01*
G01Y2155163D02*
X383968D01*
X390218Y2157590D01*
X383968Y2160017D01*
X391468D01*
G01Y2162663D02*
X383968D01*
X390218Y2165090D01*
X383968Y2167517D01*
X391468D01*
G01Y2174457D02*
Y2170723D01*
X383968D01*
Y2174457D01*
G01X387593Y2172963D02*
Y2170723D01*
G01X391468Y2177943D02*
X383968D01*
X391468Y2182237D01*
X383968D01*
G01X391468Y2185537D02*
X383968D01*
Y2187403D01*
X384343Y2188150D01*
X384843Y2188710D01*
X385593Y2189177D01*
X386468Y2189550D01*
X387718Y2189643D01*
X388968Y2189550D01*
X389843Y2189177D01*
X390593Y2188710D01*
X391093Y2188150D01*
X391468Y2187403D01*
Y2185537D01*
G01Y2196957D02*
Y2193223D01*
X383968D01*
Y2196957D01*
G01X387593Y2195463D02*
Y2193223D01*
G01X391468Y2200537D02*
X383968D01*
Y2202403D01*
X384343Y2203150D01*
X384843Y2203710D01*
X385593Y2204177D01*
X386468Y2204550D01*
X387718Y2204643D01*
X388968Y2204550D01*
X389843Y2204177D01*
X390593Y2203710D01*
X391093Y2203150D01*
X391468Y2202403D01*
Y2200537D01*
G01Y2215537D02*
X383968D01*
Y2217403D01*
X384343Y2218150D01*
X384843Y2218710D01*
X385593Y2219177D01*
X386468Y2219550D01*
X387718Y2219643D01*
X388968Y2219550D01*
X389843Y2219177D01*
X390593Y2218710D01*
X391093Y2218150D01*
X391468Y2217403D01*
Y2215537D01*
G01Y2223223D02*
X383968D01*
Y2225557D01*
X384343Y2226303D01*
X384843Y2226770D01*
X385843Y2226957D01*
X386843Y2226770D01*
X387468Y2226210D01*
X387843Y2225557D01*
Y2223223D01*
G01Y2225557D02*
X391468Y2226957D01*
G01X383968Y2231470D02*
Y2233710D01*
G01Y2232590D02*
X391468D01*
G01Y2231470D02*
Y2233710D01*
G01X383968Y2238223D02*
X391468D01*
Y2241957D01*
G01X383968Y2245723D02*
X391468D01*
Y2249457D01*
G01X390468Y2260630D02*
X391093Y2261377D01*
X391468Y2262217D01*
Y2262963D01*
X391093Y2263710D01*
X390468Y2264270D01*
X389593Y2264550D01*
X388718Y2264363D01*
X387968Y2263897D01*
X387468Y2263057D01*
X387218Y2261937D01*
X386718Y2261283D01*
X385843Y2261003D01*
X384968Y2261190D01*
X384343Y2261657D01*
X383968Y2262310D01*
Y2262963D01*
X384218Y2263617D01*
X384843Y2264177D01*
G01X383968Y2268970D02*
Y2271210D01*
G01Y2270090D02*
X391468D01*
G01Y2268970D02*
Y2271210D01*
G01X383968Y2275817D02*
Y2279363D01*
X391468Y2275817D01*
Y2279363D01*
G01Y2286957D02*
Y2283223D01*
X383968D01*
Y2286957D01*
G01X387593Y2285463D02*
Y2283223D01*
G01X391468Y2298317D02*
X383968D01*
Y2301863D01*
G01X387593Y2300557D02*
Y2298317D01*
G01X391468Y2307590D02*
X391343Y2306843D01*
X390843Y2306190D01*
X390093Y2305630D01*
X389218Y2305257D01*
X388218Y2305070D01*
X387218D01*
X386218Y2305257D01*
X385343Y2305630D01*
X384593Y2306190D01*
X384093Y2306843D01*
X383968Y2307590D01*
X384093Y2308337D01*
X384593Y2308990D01*
X385343Y2309550D01*
X386218Y2309923D01*
X387218Y2310110D01*
X388218D01*
X389218Y2309923D01*
X390093Y2309550D01*
X390843Y2308990D01*
X391343Y2308337D01*
X391468Y2307590D01*
G01Y2313223D02*
X383968D01*
Y2315557D01*
X384343Y2316303D01*
X384843Y2316770D01*
X385843Y2316957D01*
X386843Y2316770D01*
X387468Y2316210D01*
X387843Y2315557D01*
Y2313223D01*
G01Y2315557D02*
X391468Y2316957D01*
G01X383968Y2330090D02*
X384218Y2329343D01*
X384843Y2328783D01*
X385593Y2328410D01*
X386593Y2328130D01*
X387718Y2328037D01*
X388843Y2328130D01*
X389843Y2328410D01*
X390593Y2328783D01*
X391218Y2329343D01*
X391468Y2330090D01*
X391218Y2330837D01*
X390593Y2331397D01*
X389843Y2331770D01*
X388843Y2332050D01*
X387718Y2332143D01*
X386593Y2332050D01*
X385593Y2331770D01*
X384843Y2331397D01*
X384218Y2330837D01*
X383968Y2330090D01*
G01X391718Y2337590D02*
X391593Y2337403D01*
X391343D01*
X391218Y2337590D01*
X391343Y2337777D01*
X391593D01*
X391718Y2337590D01*
G01X390343Y2343037D02*
X390968Y2343597D01*
X391343Y2344250D01*
X391468Y2345090D01*
X391218Y2345930D01*
X390718Y2346583D01*
X389843Y2347050D01*
X388843Y2347143D01*
X387843Y2346957D01*
X387218Y2346490D01*
X386718Y2345837D01*
X386593Y2345183D01*
X386718Y2344530D01*
X387218Y2343690D01*
X383968Y2343970D01*
Y2346490D01*
G01X391468Y2350163D02*
X383968D01*
X390218Y2352590D01*
X383968Y2355017D01*
X391468D01*
G01Y2357663D02*
X383968D01*
X390218Y2360090D01*
X383968Y2362517D01*
X391468D01*
G01Y2373317D02*
X383968D01*
Y2376863D01*
G01X387593Y2375557D02*
Y2373317D01*
G01X383968Y2381470D02*
Y2383710D01*
G01Y2382590D02*
X391468D01*
G01Y2381470D02*
Y2383710D01*
G01Y2387943D02*
X383968D01*
X391468Y2392237D01*
X383968D01*
G01Y2396470D02*
Y2398710D01*
G01Y2397590D02*
X391468D01*
G01Y2396470D02*
Y2398710D01*
G01X390468Y2403130D02*
X391093Y2403877D01*
X391468Y2404717D01*
Y2405463D01*
X391093Y2406210D01*
X390468Y2406770D01*
X389593Y2407050D01*
X388718Y2406863D01*
X387968Y2406397D01*
X387468Y2405557D01*
X387218Y2404437D01*
X386718Y2403783D01*
X385843Y2403503D01*
X384968Y2403690D01*
X384343Y2404157D01*
X383968Y2404810D01*
Y2405463D01*
X384218Y2406117D01*
X384843Y2406677D01*
G01X391468Y2410630D02*
X383968D01*
G01Y2414550D02*
X391468D01*
G01X387718D02*
Y2410630D01*
G01X391468Y2421957D02*
Y2418223D01*
X383968D01*
Y2421957D01*
G01X387593Y2420463D02*
Y2418223D01*
G01X391468Y2425537D02*
X383968D01*
Y2427403D01*
X384343Y2428150D01*
X384843Y2428710D01*
X385593Y2429177D01*
X386468Y2429550D01*
X387718Y2429643D01*
X388968Y2429550D01*
X389843Y2429177D01*
X390593Y2428710D01*
X391093Y2428150D01*
X391468Y2427403D01*
Y2425537D01*
G01Y2440723D02*
X383968D01*
Y2442963D01*
X384343Y2443710D01*
X385218Y2444270D01*
X386218Y2444457D01*
X387218Y2444270D01*
X387968Y2443803D01*
X388343Y2442963D01*
Y2440723D01*
G01X383968Y2450090D02*
X391468D01*
G01X383968Y2447943D02*
Y2452237D01*
G01X391468Y2455630D02*
X383968D01*
G01Y2459550D02*
X391468D01*
G01X387718D02*
Y2455630D01*
G01X383968Y2471470D02*
Y2473710D01*
G01Y2472590D02*
X391468D01*
G01Y2471470D02*
Y2473710D01*
G01X390468Y2478130D02*
X391093Y2478877D01*
X391468Y2479717D01*
Y2480463D01*
X391093Y2481210D01*
X390468Y2481770D01*
X389593Y2482050D01*
X388718Y2481863D01*
X387968Y2481397D01*
X387468Y2480557D01*
X387218Y2479437D01*
X386718Y2478783D01*
X385843Y2478503D01*
X384968Y2478690D01*
X384343Y2479157D01*
X383968Y2479810D01*
Y2480463D01*
X384218Y2481117D01*
X384843Y2481677D01*
G01X383968Y2495090D02*
X384218Y2494343D01*
X384843Y2493783D01*
X385593Y2493410D01*
X386593Y2493130D01*
X387718Y2493037D01*
X388843Y2493130D01*
X389843Y2493410D01*
X390593Y2493783D01*
X391218Y2494343D01*
X391468Y2495090D01*
X391218Y2495837D01*
X390593Y2496397D01*
X389843Y2496770D01*
X388843Y2497050D01*
X387718Y2497143D01*
X386593Y2497050D01*
X385593Y2496770D01*
X384843Y2496397D01*
X384218Y2495837D01*
X383968Y2495090D01*
G01X391718Y2502590D02*
X391593Y2502403D01*
X391343D01*
X391218Y2502590D01*
X391343Y2502777D01*
X391593D01*
X391718Y2502590D01*
G01X388343Y2508317D02*
X387468Y2508970D01*
X386968Y2509530D01*
X386718Y2510277D01*
X386968Y2510930D01*
X387468Y2511397D01*
X388218Y2511770D01*
X389093Y2511863D01*
X389843Y2511770D01*
X390593Y2511397D01*
X391218Y2510837D01*
X391468Y2510183D01*
X391218Y2509437D01*
X390468Y2508783D01*
X389343Y2508410D01*
X388093Y2508317D01*
X386468Y2508503D01*
X385593Y2508783D01*
X384718Y2509250D01*
X384093Y2509903D01*
X383968Y2510557D01*
X384218Y2511210D01*
X384843Y2511677D01*
G01X391468Y2515163D02*
X383968D01*
X390218Y2517590D01*
X383968Y2520017D01*
X391468D01*
G01Y2522663D02*
X383968D01*
X390218Y2525090D01*
X383968Y2527517D01*
X391468D01*
G01Y2537663D02*
X383968D01*
X390218Y2540090D01*
X383968Y2542517D01*
X391468D01*
G01Y2549457D02*
Y2545723D01*
X383968D01*
Y2549457D01*
G01X387593Y2547963D02*
Y2545723D01*
G01X383968Y2555090D02*
X391468D01*
G01X383968Y2552943D02*
Y2557237D01*
G01X391468Y2560723D02*
X383968D01*
Y2563057D01*
X384343Y2563803D01*
X384843Y2564270D01*
X385843Y2564457D01*
X386843Y2564270D01*
X387468Y2563710D01*
X387843Y2563057D01*
Y2560723D01*
G01Y2563057D02*
X391468Y2564457D01*
G01X383968Y2568970D02*
Y2571210D01*
G01Y2570090D02*
X391468D01*
G01Y2568970D02*
Y2571210D01*
G01X384593Y2579643D02*
X384218Y2579083D01*
X383968Y2578430D01*
Y2577683D01*
X384343Y2576843D01*
X384968Y2576190D01*
X385718Y2575723D01*
X386968Y2575350D01*
X388093Y2575257D01*
X389218Y2575443D01*
X389968Y2575723D01*
X390718Y2576283D01*
X391218Y2576937D01*
X391468Y2577590D01*
Y2578243D01*
X391218Y2578897D01*
X390843Y2579457D01*
X390343Y2579923D01*
G01X391468Y2590537D02*
X383968D01*
Y2592403D01*
X384343Y2593150D01*
X384843Y2593710D01*
X385593Y2594177D01*
X386468Y2594550D01*
X387718Y2594643D01*
X388968Y2594550D01*
X389843Y2594177D01*
X390593Y2593710D01*
X391093Y2593150D01*
X391468Y2592403D01*
Y2590537D01*
G01Y2598223D02*
X383968D01*
Y2600557D01*
X384343Y2601303D01*
X384843Y2601770D01*
X385843Y2601957D01*
X386843Y2601770D01*
X387468Y2601210D01*
X387843Y2600557D01*
Y2598223D01*
G01Y2600557D02*
X391468Y2601957D01*
G01X383968Y2606470D02*
Y2608710D01*
G01Y2607590D02*
X391468D01*
G01Y2606470D02*
Y2608710D01*
G01X383968Y2613223D02*
X391468D01*
Y2616957D01*
G01X383968Y2620723D02*
X391468D01*
Y2624457D01*
G01X393968Y2629623D02*
X392718Y2628690D01*
X391468Y2628223D01*
X386468D01*
X385218Y2628690D01*
X383968Y2629623D01*
G01Y2637590D02*
X384218Y2636843D01*
X384843Y2636283D01*
X385593Y2635910D01*
X386593Y2635630D01*
X387718Y2635537D01*
X388843Y2635630D01*
X389843Y2635910D01*
X390593Y2636283D01*
X391218Y2636843D01*
X391468Y2637590D01*
X391218Y2638337D01*
X390593Y2638897D01*
X389843Y2639270D01*
X388843Y2639550D01*
X387718Y2639643D01*
X386593Y2639550D01*
X385593Y2639270D01*
X384843Y2638897D01*
X384218Y2638337D01*
X383968Y2637590D01*
G01X391718Y2645090D02*
X391593Y2644903D01*
X391343D01*
X391218Y2645090D01*
X391343Y2645277D01*
X391593D01*
X391718Y2645090D01*
G01X383968Y2652590D02*
X384218Y2651843D01*
X384843Y2651283D01*
X385593Y2650910D01*
X386593Y2650630D01*
X387718Y2650537D01*
X388843Y2650630D01*
X389843Y2650910D01*
X390593Y2651283D01*
X391218Y2651843D01*
X391468Y2652590D01*
X391218Y2653337D01*
X390593Y2653897D01*
X389843Y2654270D01*
X388843Y2654550D01*
X387718Y2654643D01*
X386593Y2654550D01*
X385593Y2654270D01*
X384843Y2653897D01*
X384218Y2653337D01*
X383968Y2652590D01*
G01X385218Y2658317D02*
X384468Y2658877D01*
X384093Y2659530D01*
X383968Y2660277D01*
X384218Y2661210D01*
X384843Y2661863D01*
X385593Y2662050D01*
X386343Y2661957D01*
X386968Y2661583D01*
X388218Y2659717D01*
X389093Y2658877D01*
X390343Y2658317D01*
X391468Y2658130D01*
Y2662050D01*
G01X389968Y2665537D02*
X390843Y2666097D01*
X391343Y2666843D01*
X391468Y2667683D01*
X391343Y2668430D01*
X390718Y2669177D01*
X389968Y2669643D01*
X389218Y2669737D01*
X388343Y2669550D01*
X387718Y2668897D01*
X387468Y2668243D01*
Y2667403D01*
G01Y2668243D02*
X387093Y2668803D01*
X386468Y2669270D01*
X385718Y2669457D01*
X384968Y2669270D01*
X384343Y2668803D01*
X383968Y2667963D01*
X384093Y2667123D01*
X384593Y2666283D01*
G01X388343Y2673317D02*
X387468Y2673970D01*
X386968Y2674530D01*
X386718Y2675277D01*
X386968Y2675930D01*
X387468Y2676397D01*
X388218Y2676770D01*
X389093Y2676863D01*
X389843Y2676770D01*
X390593Y2676397D01*
X391218Y2675837D01*
X391468Y2675183D01*
X391218Y2674437D01*
X390468Y2673783D01*
X389343Y2673410D01*
X388093Y2673317D01*
X386468Y2673503D01*
X385593Y2673783D01*
X384718Y2674250D01*
X384093Y2674903D01*
X383968Y2675557D01*
X384218Y2676210D01*
X384843Y2676677D01*
G01X385593Y2681750D02*
X383968Y2682217D01*
G01Y2683430D02*
X385593Y2682963D01*
G01X393968Y2690557D02*
X392718Y2691490D01*
X391468Y2691957D01*
X386468D01*
X385218Y2691490D01*
X383968Y2690557D01*
G01X391718Y2697590D02*
X391593Y2697403D01*
X391343D01*
X391218Y2697590D01*
X391343Y2697777D01*
X391593D01*
X391718Y2697590D01*
G01X410525Y-369172D02*
X411984Y-368242D01*
X412817Y-367002D01*
X413025Y-365607D01*
X412817Y-364367D01*
X411775Y-363127D01*
X410525Y-362352D01*
X409275Y-362197D01*
X407817Y-362507D01*
X406775Y-363592D01*
X406358Y-364677D01*
Y-366072D01*
G01Y-364677D02*
X405733Y-363747D01*
X404692Y-362972D01*
X403442Y-362662D01*
X402192Y-362972D01*
X401150Y-363747D01*
X400525Y-365142D01*
X400733Y-366537D01*
X401567Y-367932D01*
G01X411567Y-355997D02*
X412608Y-354912D01*
X413025Y-353672D01*
X412608Y-352432D01*
X411359Y-351347D01*
X409483Y-350572D01*
X407608Y-350262D01*
X405317D01*
X403442Y-350572D01*
X401775Y-351347D01*
X400942Y-352277D01*
X400525Y-353362D01*
X400942Y-354602D01*
X401775Y-355532D01*
X403025Y-356152D01*
X404692Y-356462D01*
X406150Y-356152D01*
X407608Y-355377D01*
X408442Y-354447D01*
X408650Y-353362D01*
X408234Y-352122D01*
X407192Y-351192D01*
X405317Y-350262D01*
G01X411150Y-344372D02*
X412192Y-343442D01*
X412817Y-342357D01*
X413025Y-340962D01*
X412608Y-339567D01*
X411775Y-338482D01*
X410317Y-337707D01*
X408650Y-337552D01*
X406983Y-337862D01*
X405942Y-338637D01*
X405108Y-339722D01*
X404900Y-340807D01*
X405108Y-341892D01*
X405942Y-343287D01*
X400525Y-342822D01*
Y-338637D01*
G01X407817Y-331507D02*
X406358Y-330422D01*
X405525Y-329492D01*
X405108Y-328252D01*
X405525Y-327167D01*
X406358Y-326392D01*
X407608Y-325772D01*
X409067Y-325617D01*
X410317Y-325772D01*
X411567Y-326392D01*
X412608Y-327322D01*
X413025Y-328407D01*
X412608Y-329647D01*
X411359Y-330732D01*
X409483Y-331352D01*
X407400Y-331507D01*
X404692Y-331197D01*
X403233Y-330732D01*
X401775Y-329957D01*
X400733Y-328872D01*
X400525Y-327787D01*
X400942Y-326702D01*
X401983Y-325927D01*
G01X413442Y-316162D02*
X413233Y-316472D01*
X412817D01*
X412608Y-316162D01*
X412817Y-315852D01*
X413233D01*
X413442Y-316162D01*
G01X413025Y-304072D02*
X410317Y-303762D01*
X408025Y-303297D01*
X405942Y-302677D01*
X403650Y-301902D01*
X400525Y-300662D01*
Y-306862D01*
G01Y-291362D02*
X400942Y-292602D01*
X401983Y-293532D01*
X403233Y-294152D01*
X404900Y-294617D01*
X406775Y-294772D01*
X408650Y-294617D01*
X410317Y-294152D01*
X411567Y-293532D01*
X412608Y-292602D01*
X413025Y-291362D01*
X412608Y-290122D01*
X411567Y-289192D01*
X410317Y-288572D01*
X408650Y-288107D01*
X406775Y-287952D01*
X404900Y-288107D01*
X403233Y-288572D01*
X401983Y-289192D01*
X400942Y-290122D01*
X400525Y-291362D01*
G01X413025Y-256762D02*
X400525D01*
X403025Y-258622D01*
G01X413025D02*
Y-254902D01*
G01X400525Y-244362D02*
X400942Y-245602D01*
X401983Y-246532D01*
X403233Y-247152D01*
X404900Y-247617D01*
X406775Y-247772D01*
X408650Y-247617D01*
X410317Y-247152D01*
X411567Y-246532D01*
X412608Y-245602D01*
X413025Y-244362D01*
X412608Y-243122D01*
X411567Y-242192D01*
X410317Y-241572D01*
X408650Y-241107D01*
X406775Y-240952D01*
X404900Y-241107D01*
X403233Y-241572D01*
X401983Y-242192D01*
X400942Y-243122D01*
X400525Y-244362D01*
G01Y-231962D02*
X400942Y-233202D01*
X401983Y-234132D01*
X403233Y-234752D01*
X404900Y-235217D01*
X406775Y-235372D01*
X408650Y-235217D01*
X410317Y-234752D01*
X411567Y-234132D01*
X412608Y-233202D01*
X413025Y-231962D01*
X412608Y-230722D01*
X411567Y-229792D01*
X410317Y-229172D01*
X408650Y-228707D01*
X406775Y-228552D01*
X404900Y-228707D01*
X403233Y-229172D01*
X401983Y-229792D01*
X400942Y-230722D01*
X400525Y-231962D01*
G01X413442Y-219562D02*
X413233Y-219872D01*
X412817D01*
X412608Y-219562D01*
X412817Y-219252D01*
X413233D01*
X413442Y-219562D01*
G01X411150Y-210572D02*
X412192Y-209642D01*
X412817Y-208557D01*
X413025Y-207162D01*
X412608Y-205767D01*
X411775Y-204682D01*
X410317Y-203907D01*
X408650Y-203752D01*
X406983Y-204062D01*
X405942Y-204837D01*
X405108Y-205922D01*
X404900Y-207007D01*
X405108Y-208092D01*
X405942Y-209487D01*
X400525Y-209022D01*
Y-204837D01*
G01X398873Y2062371D02*
X398498Y2061811D01*
X398248Y2061158D01*
Y2060411D01*
X398623Y2059571D01*
X399248Y2058918D01*
X399998Y2058451D01*
X401248Y2058078D01*
X402373Y2057985D01*
X403498Y2058171D01*
X404248Y2058451D01*
X404998Y2059011D01*
X405498Y2059665D01*
X405748Y2060318D01*
Y2060971D01*
X405498Y2061625D01*
X405123Y2062185D01*
X404623Y2062651D01*
G01X405748Y2067818D02*
X405623Y2067071D01*
X405123Y2066418D01*
X404373Y2065858D01*
X403498Y2065485D01*
X402498Y2065298D01*
X401498D01*
X400498Y2065485D01*
X399623Y2065858D01*
X398873Y2066418D01*
X398373Y2067071D01*
X398248Y2067818D01*
X398373Y2068565D01*
X398873Y2069218D01*
X399623Y2069778D01*
X400498Y2070151D01*
X401498Y2070338D01*
X402498D01*
X403498Y2070151D01*
X404373Y2069778D01*
X405123Y2069218D01*
X405623Y2068565D01*
X405748Y2067818D01*
G01Y2073451D02*
X398248D01*
Y2075691D01*
X398623Y2076438D01*
X399498Y2076998D01*
X400498Y2077185D01*
X401498Y2076998D01*
X402248Y2076531D01*
X402623Y2075691D01*
Y2073451D01*
G01X405748Y2080951D02*
X398248D01*
Y2083191D01*
X398623Y2083938D01*
X399498Y2084498D01*
X400498Y2084685D01*
X401498Y2084498D01*
X402248Y2084031D01*
X402623Y2083191D01*
Y2080951D01*
G01X405748Y2092185D02*
Y2088451D01*
X398248D01*
Y2092185D01*
G01X401873Y2090691D02*
Y2088451D01*
G01X405748Y2095951D02*
X398248D01*
Y2098285D01*
X398623Y2099031D01*
X399123Y2099498D01*
X400123Y2099685D01*
X401123Y2099498D01*
X401748Y2098938D01*
X402123Y2098285D01*
Y2095951D01*
G01Y2098285D02*
X405748Y2099685D01*
G01Y2112818D02*
X405623Y2112071D01*
X405123Y2111418D01*
X404373Y2110858D01*
X403498Y2110485D01*
X402498Y2110298D01*
X401498D01*
X400498Y2110485D01*
X399623Y2110858D01*
X398873Y2111418D01*
X398373Y2112071D01*
X398248Y2112818D01*
X398373Y2113565D01*
X398873Y2114218D01*
X399623Y2114778D01*
X400498Y2115151D01*
X401498Y2115338D01*
X402498D01*
X403498Y2115151D01*
X404373Y2114778D01*
X405123Y2114218D01*
X405623Y2113565D01*
X405748Y2112818D01*
G01X404748Y2118358D02*
X405373Y2119105D01*
X405748Y2119945D01*
Y2120691D01*
X405373Y2121438D01*
X404748Y2121998D01*
X403873Y2122278D01*
X402998Y2122091D01*
X402248Y2121625D01*
X401748Y2120785D01*
X401498Y2119665D01*
X400998Y2119011D01*
X400123Y2118731D01*
X399248Y2118918D01*
X398623Y2119385D01*
X398248Y2120038D01*
Y2120691D01*
X398498Y2121345D01*
X399123Y2121905D01*
G01X405748Y2125951D02*
X398248D01*
Y2128191D01*
X398623Y2128938D01*
X399498Y2129498D01*
X400498Y2129685D01*
X401498Y2129498D01*
X402248Y2129031D01*
X402623Y2128191D01*
Y2125951D01*
G01X405998Y2133638D02*
X398248Y2136998D01*
G01Y2142818D02*
X405748D01*
G01X398248Y2140671D02*
Y2144965D01*
G01Y2149198D02*
Y2151438D01*
G01Y2150318D02*
X405748D01*
G01Y2149198D02*
Y2151438D01*
G01Y2155671D02*
X398248D01*
X405748Y2159965D01*
X398248D01*
G01X408248Y2164851D02*
X406998Y2163918D01*
X405748Y2163451D01*
X400748D01*
X399498Y2163918D01*
X398248Y2164851D01*
G01Y2171698D02*
Y2173938D01*
G01Y2172818D02*
X405748D01*
G01Y2171698D02*
Y2173938D01*
G01Y2177891D02*
X398248D01*
X404498Y2180318D01*
X398248Y2182745D01*
X405748D01*
G01Y2185391D02*
X398248D01*
X404498Y2187818D01*
X398248Y2190245D01*
X405748D01*
G01Y2197185D02*
Y2193451D01*
X398248D01*
Y2197185D01*
G01X401873Y2195691D02*
Y2193451D01*
G01X405748Y2200951D02*
X398248D01*
Y2203285D01*
X398623Y2204031D01*
X399123Y2204498D01*
X400123Y2204685D01*
X401123Y2204498D01*
X401748Y2203938D01*
X402123Y2203285D01*
Y2200951D01*
G01Y2203285D02*
X405748Y2204685D01*
G01X404748Y2208358D02*
X405373Y2209105D01*
X405748Y2209945D01*
Y2210691D01*
X405373Y2211438D01*
X404748Y2211998D01*
X403873Y2212278D01*
X402998Y2212091D01*
X402248Y2211625D01*
X401748Y2210785D01*
X401498Y2209665D01*
X400998Y2209011D01*
X400123Y2208731D01*
X399248Y2208918D01*
X398623Y2209385D01*
X398248Y2210038D01*
Y2210691D01*
X398498Y2211345D01*
X399123Y2211905D01*
G01X398248Y2216698D02*
Y2218938D01*
G01Y2217818D02*
X405748D01*
G01Y2216698D02*
Y2218938D01*
G01Y2225318D02*
X405623Y2224571D01*
X405123Y2223918D01*
X404373Y2223358D01*
X403498Y2222985D01*
X402498Y2222798D01*
X401498D01*
X400498Y2222985D01*
X399623Y2223358D01*
X398873Y2223918D01*
X398373Y2224571D01*
X398248Y2225318D01*
X398373Y2226065D01*
X398873Y2226718D01*
X399623Y2227278D01*
X400498Y2227651D01*
X401498Y2227838D01*
X402498D01*
X403498Y2227651D01*
X404373Y2227278D01*
X405123Y2226718D01*
X405623Y2226065D01*
X405748Y2225318D01*
G01Y2230671D02*
X398248D01*
X405748Y2234965D01*
X398248D01*
G01X408248Y2240785D02*
X406998Y2241718D01*
X405748Y2242185D01*
X400748D01*
X399498Y2241718D01*
X398248Y2240785D01*
G01X405998Y2247818D02*
X405873Y2247631D01*
X405623D01*
X405498Y2247818D01*
X405623Y2248005D01*
X405873D01*
X405998Y2247818D01*
G01X402623D02*
X402498Y2247631D01*
X402248D01*
X402123Y2247818D01*
X402248Y2248005D01*
X402498D01*
X402623Y2247818D01*
G01X405748Y2253451D02*
X398248D01*
Y2255785D01*
X398623Y2256531D01*
X399123Y2256998D01*
X400123Y2257185D01*
X401123Y2256998D01*
X401748Y2256438D01*
X402123Y2255785D01*
Y2253451D01*
G01Y2255785D02*
X405748Y2257185D01*
G01Y2264685D02*
Y2260951D01*
X398248D01*
Y2264685D01*
G01X401873Y2263191D02*
Y2260951D01*
G01X398873Y2272371D02*
X398498Y2271811D01*
X398248Y2271158D01*
Y2270411D01*
X398623Y2269571D01*
X399248Y2268918D01*
X399998Y2268451D01*
X401248Y2268078D01*
X402373Y2267985D01*
X403498Y2268171D01*
X404248Y2268451D01*
X404998Y2269011D01*
X405498Y2269665D01*
X405748Y2270318D01*
Y2270971D01*
X405498Y2271625D01*
X405123Y2272185D01*
X404623Y2272651D01*
G01X405748Y2277818D02*
X405623Y2277071D01*
X405123Y2276418D01*
X404373Y2275858D01*
X403498Y2275485D01*
X402498Y2275298D01*
X401498D01*
X400498Y2275485D01*
X399623Y2275858D01*
X398873Y2276418D01*
X398373Y2277071D01*
X398248Y2277818D01*
X398373Y2278565D01*
X398873Y2279218D01*
X399623Y2279778D01*
X400498Y2280151D01*
X401498Y2280338D01*
X402498D01*
X403498Y2280151D01*
X404373Y2279778D01*
X405123Y2279218D01*
X405623Y2278565D01*
X405748Y2277818D01*
G01Y2282891D02*
X398248D01*
X404498Y2285318D01*
X398248Y2287745D01*
X405748D01*
G01Y2290391D02*
X398248D01*
X404498Y2292818D01*
X398248Y2295245D01*
X405748D01*
G01Y2302185D02*
Y2298451D01*
X398248D01*
Y2302185D01*
G01X401873Y2300691D02*
Y2298451D01*
G01X405748Y2305671D02*
X398248D01*
X405748Y2309965D01*
X398248D01*
G01X405748Y2313265D02*
X398248D01*
Y2315131D01*
X398623Y2315878D01*
X399123Y2316438D01*
X399873Y2316905D01*
X400748Y2317278D01*
X401998Y2317371D01*
X403248Y2317278D01*
X404123Y2316905D01*
X404873Y2316438D01*
X405373Y2315878D01*
X405748Y2315131D01*
Y2313265D01*
G01Y2324685D02*
Y2320951D01*
X398248D01*
Y2324685D01*
G01X401873Y2323191D02*
Y2320951D01*
G01X405748Y2328265D02*
X398248D01*
Y2330131D01*
X398623Y2330878D01*
X399123Y2331438D01*
X399873Y2331905D01*
X400748Y2332278D01*
X401998Y2332371D01*
X403248Y2332278D01*
X404123Y2331905D01*
X404873Y2331438D01*
X405373Y2330878D01*
X405748Y2330131D01*
Y2328265D01*
G01Y2343265D02*
X398248D01*
Y2345131D01*
X398623Y2345878D01*
X399123Y2346438D01*
X399873Y2346905D01*
X400748Y2347278D01*
X401998Y2347371D01*
X403248Y2347278D01*
X404123Y2346905D01*
X404873Y2346438D01*
X405373Y2345878D01*
X405748Y2345131D01*
Y2343265D01*
G01Y2350951D02*
X398248D01*
Y2353285D01*
X398623Y2354031D01*
X399123Y2354498D01*
X400123Y2354685D01*
X401123Y2354498D01*
X401748Y2353938D01*
X402123Y2353285D01*
Y2350951D01*
G01Y2353285D02*
X405748Y2354685D01*
G01X398248Y2359198D02*
Y2361438D01*
G01Y2360318D02*
X405748D01*
G01Y2359198D02*
Y2361438D01*
G01X398248Y2365951D02*
X405748D01*
Y2369685D01*
G01X398248Y2373451D02*
X405748D01*
Y2377185D01*
G01X404748Y2388358D02*
X405373Y2389105D01*
X405748Y2389945D01*
Y2390691D01*
X405373Y2391438D01*
X404748Y2391998D01*
X403873Y2392278D01*
X402998Y2392091D01*
X402248Y2391625D01*
X401748Y2390785D01*
X401498Y2389665D01*
X400998Y2389011D01*
X400123Y2388731D01*
X399248Y2388918D01*
X398623Y2389385D01*
X398248Y2390038D01*
Y2390691D01*
X398498Y2391345D01*
X399123Y2391905D01*
G01X398248Y2396698D02*
Y2398938D01*
G01Y2397818D02*
X405748D01*
G01Y2396698D02*
Y2398938D01*
G01X398248Y2403545D02*
Y2407091D01*
X405748Y2403545D01*
Y2407091D01*
G01Y2414685D02*
Y2410951D01*
X398248D01*
Y2414685D01*
G01X401873Y2413191D02*
Y2410951D01*
G01X405748Y2426045D02*
X398248D01*
Y2429591D01*
G01X401873Y2428285D02*
Y2426045D01*
G01X405748Y2435318D02*
X405623Y2434571D01*
X405123Y2433918D01*
X404373Y2433358D01*
X403498Y2432985D01*
X402498Y2432798D01*
X401498D01*
X400498Y2432985D01*
X399623Y2433358D01*
X398873Y2433918D01*
X398373Y2434571D01*
X398248Y2435318D01*
X398373Y2436065D01*
X398873Y2436718D01*
X399623Y2437278D01*
X400498Y2437651D01*
X401498Y2437838D01*
X402498D01*
X403498Y2437651D01*
X404373Y2437278D01*
X405123Y2436718D01*
X405623Y2436065D01*
X405748Y2435318D01*
G01Y2440951D02*
X398248D01*
Y2443285D01*
X398623Y2444031D01*
X399123Y2444498D01*
X400123Y2444685D01*
X401123Y2444498D01*
X401748Y2443938D01*
X402123Y2443285D01*
Y2440951D01*
G01Y2443285D02*
X405748Y2444685D01*
G01X398248Y2457818D02*
X398498Y2457071D01*
X399123Y2456511D01*
X399873Y2456138D01*
X400873Y2455858D01*
X401998Y2455765D01*
X403123Y2455858D01*
X404123Y2456138D01*
X404873Y2456511D01*
X405498Y2457071D01*
X405748Y2457818D01*
X405498Y2458565D01*
X404873Y2459125D01*
X404123Y2459498D01*
X403123Y2459778D01*
X401998Y2459871D01*
X400873Y2459778D01*
X399873Y2459498D01*
X399123Y2459125D01*
X398498Y2458565D01*
X398248Y2457818D01*
G01X405998Y2465318D02*
X405873Y2465131D01*
X405623D01*
X405498Y2465318D01*
X405623Y2465505D01*
X405873D01*
X405998Y2465318D01*
G01X404623Y2470765D02*
X405248Y2471325D01*
X405623Y2471978D01*
X405748Y2472818D01*
X405498Y2473658D01*
X404998Y2474311D01*
X404123Y2474778D01*
X403123Y2474871D01*
X402123Y2474685D01*
X401498Y2474218D01*
X400998Y2473565D01*
X400873Y2472911D01*
X400998Y2472258D01*
X401498Y2471418D01*
X398248Y2471698D01*
Y2474218D01*
G01X405748Y2477891D02*
X398248D01*
X404498Y2480318D01*
X398248Y2482745D01*
X405748D01*
G01Y2485391D02*
X398248D01*
X404498Y2487818D01*
X398248Y2490245D01*
X405748D01*
G01Y2501045D02*
X398248D01*
Y2504591D01*
G01X401873Y2503285D02*
Y2501045D01*
G01X398248Y2509198D02*
Y2511438D01*
G01Y2510318D02*
X405748D01*
G01Y2509198D02*
Y2511438D01*
G01Y2515671D02*
X398248D01*
X405748Y2519965D01*
X398248D01*
G01Y2524198D02*
Y2526438D01*
G01Y2525318D02*
X405748D01*
G01Y2524198D02*
Y2526438D01*
G01X404748Y2530858D02*
X405373Y2531605D01*
X405748Y2532445D01*
Y2533191D01*
X405373Y2533938D01*
X404748Y2534498D01*
X403873Y2534778D01*
X402998Y2534591D01*
X402248Y2534125D01*
X401748Y2533285D01*
X401498Y2532165D01*
X400998Y2531511D01*
X400123Y2531231D01*
X399248Y2531418D01*
X398623Y2531885D01*
X398248Y2532538D01*
Y2533191D01*
X398498Y2533845D01*
X399123Y2534405D01*
G01X405748Y2538358D02*
X398248D01*
G01Y2542278D02*
X405748D01*
G01X401998D02*
Y2538358D01*
G01X405748Y2549685D02*
Y2545951D01*
X398248D01*
Y2549685D01*
G01X401873Y2548191D02*
Y2545951D01*
G01X405748Y2553265D02*
X398248D01*
Y2555131D01*
X398623Y2555878D01*
X399123Y2556438D01*
X399873Y2556905D01*
X400748Y2557278D01*
X401998Y2557371D01*
X403248Y2557278D01*
X404123Y2556905D01*
X404873Y2556438D01*
X405373Y2555878D01*
X405748Y2555131D01*
Y2553265D01*
G01Y2568451D02*
X398248D01*
Y2570691D01*
X398623Y2571438D01*
X399498Y2571998D01*
X400498Y2572185D01*
X401498Y2571998D01*
X402248Y2571531D01*
X402623Y2570691D01*
Y2568451D01*
G01X398248Y2577818D02*
X405748D01*
G01X398248Y2575671D02*
Y2579965D01*
G01X405748Y2583358D02*
X398248D01*
G01Y2587278D02*
X405748D01*
G01X401998D02*
Y2583358D01*
G01X398248Y2599198D02*
Y2601438D01*
G01Y2600318D02*
X405748D01*
G01Y2599198D02*
Y2601438D01*
G01X404748Y2605858D02*
X405373Y2606605D01*
X405748Y2607445D01*
Y2608191D01*
X405373Y2608938D01*
X404748Y2609498D01*
X403873Y2609778D01*
X402998Y2609591D01*
X402248Y2609125D01*
X401748Y2608285D01*
X401498Y2607165D01*
X400998Y2606511D01*
X400123Y2606231D01*
X399248Y2606418D01*
X398623Y2606885D01*
X398248Y2607538D01*
Y2608191D01*
X398498Y2608845D01*
X399123Y2609405D01*
G01X398248Y2622818D02*
X398498Y2622071D01*
X399123Y2621511D01*
X399873Y2621138D01*
X400873Y2620858D01*
X401998Y2620765D01*
X403123Y2620858D01*
X404123Y2621138D01*
X404873Y2621511D01*
X405498Y2622071D01*
X405748Y2622818D01*
X405498Y2623565D01*
X404873Y2624125D01*
X404123Y2624498D01*
X403123Y2624778D01*
X401998Y2624871D01*
X400873Y2624778D01*
X399873Y2624498D01*
X399123Y2624125D01*
X398498Y2623565D01*
X398248Y2622818D01*
G01X405998Y2630318D02*
X405873Y2630131D01*
X405623D01*
X405498Y2630318D01*
X405623Y2630505D01*
X405873D01*
X405998Y2630318D01*
G01X402623Y2636045D02*
X401748Y2636698D01*
X401248Y2637258D01*
X400998Y2638005D01*
X401248Y2638658D01*
X401748Y2639125D01*
X402498Y2639498D01*
X403373Y2639591D01*
X404123Y2639498D01*
X404873Y2639125D01*
X405498Y2638565D01*
X405748Y2637911D01*
X405498Y2637165D01*
X404748Y2636511D01*
X403623Y2636138D01*
X402373Y2636045D01*
X400748Y2636231D01*
X399873Y2636511D01*
X398998Y2636978D01*
X398373Y2637631D01*
X398248Y2638285D01*
X398498Y2638938D01*
X399123Y2639405D01*
G01X405748Y2642891D02*
X398248D01*
X404498Y2645318D01*
X398248Y2647745D01*
X405748D01*
G01Y2650391D02*
X398248D01*
X404498Y2652818D01*
X398248Y2655245D01*
X405748D01*
G01Y2665391D02*
X398248D01*
X404498Y2667818D01*
X398248Y2670245D01*
X405748D01*
G01Y2677185D02*
Y2673451D01*
X398248D01*
Y2677185D01*
G01X401873Y2675691D02*
Y2673451D01*
G01X398248Y2682818D02*
X405748D01*
G01X398248Y2680671D02*
Y2684965D01*
G01X405748Y2688451D02*
X398248D01*
Y2690785D01*
X398623Y2691531D01*
X399123Y2691998D01*
X400123Y2692185D01*
X401123Y2691998D01*
X401748Y2691438D01*
X402123Y2690785D01*
Y2688451D01*
G01Y2690785D02*
X405748Y2692185D01*
G01X398248Y2696698D02*
Y2698938D01*
G01Y2697818D02*
X405748D01*
G01Y2696698D02*
Y2698938D01*
G01X398873Y2707371D02*
X398498Y2706811D01*
X398248Y2706158D01*
Y2705411D01*
X398623Y2704571D01*
X399248Y2703918D01*
X399998Y2703451D01*
X401248Y2703078D01*
X402373Y2702985D01*
X403498Y2703171D01*
X404248Y2703451D01*
X404998Y2704011D01*
X405498Y2704665D01*
X405748Y2705318D01*
Y2705971D01*
X405498Y2706625D01*
X405123Y2707185D01*
X404623Y2707651D01*
G01X405748Y2718265D02*
X398248D01*
Y2720131D01*
X398623Y2720878D01*
X399123Y2721438D01*
X399873Y2721905D01*
X400748Y2722278D01*
X401998Y2722371D01*
X403248Y2722278D01*
X404123Y2721905D01*
X404873Y2721438D01*
X405373Y2720878D01*
X405748Y2720131D01*
Y2718265D01*
G01Y2725951D02*
X398248D01*
Y2728285D01*
X398623Y2729031D01*
X399123Y2729498D01*
X400123Y2729685D01*
X401123Y2729498D01*
X401748Y2728938D01*
X402123Y2728285D01*
Y2725951D01*
G01Y2728285D02*
X405748Y2729685D01*
G01X398248Y2734198D02*
Y2736438D01*
G01Y2735318D02*
X405748D01*
G01Y2734198D02*
Y2736438D01*
G01X398248Y2740951D02*
X405748D01*
Y2744685D01*
G01X398248Y2748451D02*
X405748D01*
Y2752185D01*
G01X408248Y2757351D02*
X406998Y2756418D01*
X405748Y2755951D01*
X400748D01*
X399498Y2756418D01*
X398248Y2757351D01*
G01Y2765318D02*
X398498Y2764571D01*
X399123Y2764011D01*
X399873Y2763638D01*
X400873Y2763358D01*
X401998Y2763265D01*
X403123Y2763358D01*
X404123Y2763638D01*
X404873Y2764011D01*
X405498Y2764571D01*
X405748Y2765318D01*
X405498Y2766065D01*
X404873Y2766625D01*
X404123Y2766998D01*
X403123Y2767278D01*
X401998Y2767371D01*
X400873Y2767278D01*
X399873Y2766998D01*
X399123Y2766625D01*
X398498Y2766065D01*
X398248Y2765318D01*
G01X405998Y2772818D02*
X405873Y2772631D01*
X405623D01*
X405498Y2772818D01*
X405623Y2773005D01*
X405873D01*
X405998Y2772818D01*
G01X398248Y2780318D02*
X398498Y2779571D01*
X399123Y2779011D01*
X399873Y2778638D01*
X400873Y2778358D01*
X401998Y2778265D01*
X403123Y2778358D01*
X404123Y2778638D01*
X404873Y2779011D01*
X405498Y2779571D01*
X405748Y2780318D01*
X405498Y2781065D01*
X404873Y2781625D01*
X404123Y2781998D01*
X403123Y2782278D01*
X401998Y2782371D01*
X400873Y2782278D01*
X399873Y2781998D01*
X399123Y2781625D01*
X398498Y2781065D01*
X398248Y2780318D01*
G01X399498Y2786045D02*
X398748Y2786605D01*
X398373Y2787258D01*
X398248Y2788005D01*
X398498Y2788938D01*
X399123Y2789591D01*
X399873Y2789778D01*
X400623Y2789685D01*
X401248Y2789311D01*
X402498Y2787445D01*
X403373Y2786605D01*
X404623Y2786045D01*
X405748Y2785858D01*
Y2789778D01*
G01X404248Y2793265D02*
X405123Y2793825D01*
X405623Y2794571D01*
X405748Y2795411D01*
X405623Y2796158D01*
X404998Y2796905D01*
X404248Y2797371D01*
X403498Y2797465D01*
X402623Y2797278D01*
X401998Y2796625D01*
X401748Y2795971D01*
Y2795131D01*
G01Y2795971D02*
X401373Y2796531D01*
X400748Y2796998D01*
X399998Y2797185D01*
X399248Y2796998D01*
X398623Y2796531D01*
X398248Y2795691D01*
X398373Y2794851D01*
X398873Y2794011D01*
G01X402623Y2801045D02*
X401748Y2801698D01*
X401248Y2802258D01*
X400998Y2803005D01*
X401248Y2803658D01*
X401748Y2804125D01*
X402498Y2804498D01*
X403373Y2804591D01*
X404123Y2804498D01*
X404873Y2804125D01*
X405498Y2803565D01*
X405748Y2802911D01*
X405498Y2802165D01*
X404748Y2801511D01*
X403623Y2801138D01*
X402373Y2801045D01*
X400748Y2801231D01*
X399873Y2801511D01*
X398998Y2801978D01*
X398373Y2802631D01*
X398248Y2803285D01*
X398498Y2803938D01*
X399123Y2804405D01*
G01X399873Y2809478D02*
X398248Y2809945D01*
G01Y2811158D02*
X399873Y2810691D01*
G01X408248Y2818285D02*
X406998Y2819218D01*
X405748Y2819685D01*
X400748D01*
X399498Y2819218D01*
X398248Y2818285D01*
G01X405998Y2825318D02*
X405873Y2825131D01*
X405623D01*
X405498Y2825318D01*
X405623Y2825505D01*
X405873D01*
X405998Y2825318D01*
G01X414650Y-534979D02*
Y-526979D01*
X413450Y-528579D01*
G01Y-534979D02*
X415850D01*
G01X420750Y-531646D02*
X421450Y-530712D01*
X422050Y-530179D01*
X422850Y-529912D01*
X423550Y-530179D01*
X424050Y-530712D01*
X424450Y-531512D01*
X424550Y-532446D01*
X424450Y-533246D01*
X424050Y-534046D01*
X423450Y-534712D01*
X422750Y-534979D01*
X421950Y-534712D01*
X421250Y-533913D01*
X420850Y-532712D01*
X420750Y-531379D01*
X420950Y-529646D01*
X421250Y-528712D01*
X421750Y-527779D01*
X422450Y-527112D01*
X423150Y-526979D01*
X423850Y-527246D01*
X424350Y-527912D01*
G01X430650Y-535246D02*
X430450Y-535112D01*
Y-534846D01*
X430650Y-534712D01*
X430850Y-534846D01*
Y-535112D01*
X430650Y-535246D01*
G01X436750Y-531646D02*
X437450Y-530712D01*
X438050Y-530179D01*
X438850Y-529912D01*
X439550Y-530179D01*
X440050Y-530712D01*
X440450Y-531512D01*
X440550Y-532446D01*
X440450Y-533246D01*
X440050Y-534046D01*
X439450Y-534712D01*
X438750Y-534979D01*
X437950Y-534712D01*
X437250Y-533913D01*
X436850Y-532712D01*
X436750Y-531379D01*
X436950Y-529646D01*
X437250Y-528712D01*
X437750Y-527779D01*
X438450Y-527112D01*
X439150Y-526979D01*
X439850Y-527246D01*
X440350Y-527912D01*
G01X426830Y-381540D02*
X428289Y-380610D01*
X429122Y-379370D01*
X429330Y-377975D01*
X429122Y-376735D01*
X428080Y-375495D01*
X426830Y-374720D01*
X425580Y-374565D01*
X424122Y-374875D01*
X423080Y-375960D01*
X422663Y-377045D01*
Y-378440D01*
G01Y-377045D02*
X422038Y-376115D01*
X420997Y-375340D01*
X419747Y-375030D01*
X418497Y-375340D01*
X417455Y-376115D01*
X416830Y-377510D01*
X417038Y-378905D01*
X417872Y-380300D01*
G01X427872Y-368365D02*
X428913Y-367280D01*
X429330Y-366040D01*
X428913Y-364800D01*
X427664Y-363715D01*
X425788Y-362940D01*
X423913Y-362630D01*
X421622D01*
X419747Y-362940D01*
X418080Y-363715D01*
X417247Y-364645D01*
X416830Y-365730D01*
X417247Y-366970D01*
X418080Y-367900D01*
X419330Y-368520D01*
X420997Y-368830D01*
X422455Y-368520D01*
X423913Y-367745D01*
X424747Y-366815D01*
X424955Y-365730D01*
X424539Y-364490D01*
X423497Y-363560D01*
X421622Y-362630D01*
G01X427455Y-356740D02*
X428497Y-355810D01*
X429122Y-354725D01*
X429330Y-353330D01*
X428913Y-351935D01*
X428080Y-350850D01*
X426622Y-350075D01*
X424955Y-349920D01*
X423288Y-350230D01*
X422247Y-351005D01*
X421413Y-352090D01*
X421205Y-353175D01*
X421413Y-354260D01*
X422247Y-355655D01*
X416830Y-355190D01*
Y-351005D01*
G01X418913Y-343875D02*
X417664Y-342945D01*
X417038Y-341860D01*
X416830Y-340620D01*
X417247Y-339070D01*
X418288Y-337985D01*
X419538Y-337675D01*
X420789Y-337830D01*
X421830Y-338450D01*
X423913Y-341550D01*
X425372Y-342945D01*
X427455Y-343875D01*
X429330Y-344185D01*
Y-337675D01*
G01X429747Y-328530D02*
X429538Y-328840D01*
X429122D01*
X428913Y-328530D01*
X429122Y-328220D01*
X429538D01*
X429747Y-328530D01*
G01X416830Y-316130D02*
X417247Y-317370D01*
X418288Y-318300D01*
X419538Y-318920D01*
X421205Y-319385D01*
X423080Y-319540D01*
X424955Y-319385D01*
X426622Y-318920D01*
X427872Y-318300D01*
X428913Y-317370D01*
X429330Y-316130D01*
X428913Y-314890D01*
X427872Y-313960D01*
X426622Y-313340D01*
X424955Y-312875D01*
X423080Y-312720D01*
X421205Y-312875D01*
X419538Y-313340D01*
X418288Y-313960D01*
X417247Y-314890D01*
X416830Y-316130D01*
G01X429330Y-303730D02*
X429122Y-302645D01*
X428497Y-301405D01*
X427455Y-300630D01*
X425997Y-300320D01*
X424539Y-300630D01*
X423288Y-301560D01*
X422663Y-302955D01*
Y-304505D01*
X422247Y-305435D01*
X421205Y-306210D01*
X419747Y-306520D01*
X418288Y-306055D01*
X417247Y-304970D01*
X416830Y-303730D01*
X417247Y-302490D01*
X418288Y-301405D01*
X419747Y-300940D01*
X421205Y-301250D01*
X422247Y-302025D01*
X422663Y-302955D01*
Y-304505D01*
X423288Y-305900D01*
X424539Y-306830D01*
X425997Y-307140D01*
X427455Y-306830D01*
X428497Y-306055D01*
X429122Y-304815D01*
X429330Y-303730D01*
G01Y-269130D02*
X416830D01*
X419330Y-270990D01*
G01X429330D02*
Y-267270D01*
G01X416830Y-256730D02*
X417247Y-257970D01*
X418288Y-258900D01*
X419538Y-259520D01*
X421205Y-259985D01*
X423080Y-260140D01*
X424955Y-259985D01*
X426622Y-259520D01*
X427872Y-258900D01*
X428913Y-257970D01*
X429330Y-256730D01*
X428913Y-255490D01*
X427872Y-254560D01*
X426622Y-253940D01*
X424955Y-253475D01*
X423080Y-253320D01*
X421205Y-253475D01*
X419538Y-253940D01*
X418288Y-254560D01*
X417247Y-255490D01*
X416830Y-256730D01*
G01Y-244330D02*
X417247Y-245570D01*
X418288Y-246500D01*
X419538Y-247120D01*
X421205Y-247585D01*
X423080Y-247740D01*
X424955Y-247585D01*
X426622Y-247120D01*
X427872Y-246500D01*
X428913Y-245570D01*
X429330Y-244330D01*
X428913Y-243090D01*
X427872Y-242160D01*
X426622Y-241540D01*
X424955Y-241075D01*
X423080Y-240920D01*
X421205Y-241075D01*
X419538Y-241540D01*
X418288Y-242160D01*
X417247Y-243090D01*
X416830Y-244330D01*
G01X429747Y-231930D02*
X429538Y-232240D01*
X429122D01*
X428913Y-231930D01*
X429122Y-231620D01*
X429538D01*
X429747Y-231930D01*
G01X426830Y-222940D02*
X428289Y-222010D01*
X429122Y-220770D01*
X429330Y-219375D01*
X429122Y-218135D01*
X428080Y-216895D01*
X426830Y-216120D01*
X425580Y-215965D01*
X424122Y-216275D01*
X423080Y-217360D01*
X422663Y-218445D01*
Y-219840D01*
G01Y-218445D02*
X422038Y-217515D01*
X420997Y-216740D01*
X419747Y-216430D01*
X418497Y-216740D01*
X417455Y-217515D01*
X416830Y-218910D01*
X417038Y-220305D01*
X417872Y-221700D01*
G01X429330Y-207130D02*
X429122Y-206045D01*
X428497Y-204805D01*
X427455Y-204030D01*
X425997Y-203720D01*
X424539Y-204030D01*
X423288Y-204960D01*
X422663Y-206355D01*
Y-207905D01*
X422247Y-208835D01*
X421205Y-209610D01*
X419747Y-209920D01*
X418288Y-209455D01*
X417247Y-208370D01*
X416830Y-207130D01*
X417247Y-205890D01*
X418288Y-204805D01*
X419747Y-204340D01*
X421205Y-204650D01*
X422247Y-205425D01*
X422663Y-206355D01*
Y-207905D01*
X423288Y-209300D01*
X424539Y-210230D01*
X425997Y-210540D01*
X427455Y-210230D01*
X428497Y-209455D01*
X429122Y-208215D01*
X429330Y-207130D01*
G01X417648Y2058358D02*
X418273Y2059105D01*
X418648Y2059945D01*
Y2060691D01*
X418273Y2061438D01*
X417648Y2061998D01*
X416773Y2062278D01*
X415898Y2062091D01*
X415148Y2061625D01*
X414648Y2060785D01*
X414398Y2059665D01*
X413898Y2059011D01*
X413023Y2058731D01*
X412148Y2058918D01*
X411523Y2059385D01*
X411148Y2060038D01*
Y2060691D01*
X411398Y2061345D01*
X412023Y2061905D01*
G01X411148Y2066698D02*
Y2068938D01*
G01Y2067818D02*
X418648D01*
G01Y2066698D02*
Y2068938D01*
G01X411148Y2073451D02*
X418648D01*
Y2077185D01*
G01X411148Y2080485D02*
X418648Y2082818D01*
X411148Y2085151D01*
G01X418648Y2092185D02*
Y2088451D01*
X411148D01*
Y2092185D01*
G01X414773Y2090691D02*
Y2088451D01*
G01X418648Y2095951D02*
X411148D01*
Y2098285D01*
X411523Y2099031D01*
X412023Y2099498D01*
X413023Y2099685D01*
X414023Y2099498D01*
X414648Y2098938D01*
X415023Y2098285D01*
Y2095951D01*
G01Y2098285D02*
X418648Y2099685D01*
G01X421148Y2104851D02*
X419898Y2103918D01*
X418648Y2103451D01*
X413648D01*
X412398Y2103918D01*
X411148Y2104851D01*
G01Y2111698D02*
Y2113938D01*
G01Y2112818D02*
X418648D01*
G01Y2111698D02*
Y2113938D01*
G01Y2117891D02*
X411148D01*
X417398Y2120318D01*
X411148Y2122745D01*
X418648D01*
G01Y2125391D02*
X411148D01*
X417398Y2127818D01*
X411148Y2130245D01*
X418648D01*
G01Y2137185D02*
Y2133451D01*
X411148D01*
Y2137185D01*
G01X414773Y2135691D02*
Y2133451D01*
G01X418648Y2140951D02*
X411148D01*
Y2143285D01*
X411523Y2144031D01*
X412023Y2144498D01*
X413023Y2144685D01*
X414023Y2144498D01*
X414648Y2143938D01*
X415023Y2143285D01*
Y2140951D01*
G01Y2143285D02*
X418648Y2144685D01*
G01X417648Y2148358D02*
X418273Y2149105D01*
X418648Y2149945D01*
Y2150691D01*
X418273Y2151438D01*
X417648Y2151998D01*
X416773Y2152278D01*
X415898Y2152091D01*
X415148Y2151625D01*
X414648Y2150785D01*
X414398Y2149665D01*
X413898Y2149011D01*
X413023Y2148731D01*
X412148Y2148918D01*
X411523Y2149385D01*
X411148Y2150038D01*
Y2150691D01*
X411398Y2151345D01*
X412023Y2151905D01*
G01X411148Y2156698D02*
Y2158938D01*
G01Y2157818D02*
X418648D01*
G01Y2156698D02*
Y2158938D01*
G01Y2165318D02*
X418523Y2164571D01*
X418023Y2163918D01*
X417273Y2163358D01*
X416398Y2162985D01*
X415398Y2162798D01*
X414398D01*
X413398Y2162985D01*
X412523Y2163358D01*
X411773Y2163918D01*
X411273Y2164571D01*
X411148Y2165318D01*
X411273Y2166065D01*
X411773Y2166718D01*
X412523Y2167278D01*
X413398Y2167651D01*
X414398Y2167838D01*
X415398D01*
X416398Y2167651D01*
X417273Y2167278D01*
X418023Y2166718D01*
X418523Y2166065D01*
X418648Y2165318D01*
G01Y2170671D02*
X411148D01*
X418648Y2174965D01*
X411148D01*
G01X421148Y2180785D02*
X419898Y2181718D01*
X418648Y2182185D01*
X413648D01*
X412398Y2181718D01*
X411148Y2180785D01*
G01X418898Y2187818D02*
X418773Y2187631D01*
X418523D01*
X418398Y2187818D01*
X418523Y2188005D01*
X418773D01*
X418898Y2187818D01*
G01X415523D02*
X415398Y2187631D01*
X415148D01*
X415023Y2187818D01*
X415148Y2188005D01*
X415398D01*
X415523Y2187818D01*
G01X418648Y2193451D02*
X411148D01*
Y2195785D01*
X411523Y2196531D01*
X412023Y2196998D01*
X413023Y2197185D01*
X414023Y2196998D01*
X414648Y2196438D01*
X415023Y2195785D01*
Y2193451D01*
G01Y2195785D02*
X418648Y2197185D01*
G01Y2204685D02*
Y2200951D01*
X411148D01*
Y2204685D01*
G01X414773Y2203191D02*
Y2200951D01*
G01X411773Y2212371D02*
X411398Y2211811D01*
X411148Y2211158D01*
Y2210411D01*
X411523Y2209571D01*
X412148Y2208918D01*
X412898Y2208451D01*
X414148Y2208078D01*
X415273Y2207985D01*
X416398Y2208171D01*
X417148Y2208451D01*
X417898Y2209011D01*
X418398Y2209665D01*
X418648Y2210318D01*
Y2210971D01*
X418398Y2211625D01*
X418023Y2212185D01*
X417523Y2212651D01*
G01X418648Y2217818D02*
X418523Y2217071D01*
X418023Y2216418D01*
X417273Y2215858D01*
X416398Y2215485D01*
X415398Y2215298D01*
X414398D01*
X413398Y2215485D01*
X412523Y2215858D01*
X411773Y2216418D01*
X411273Y2217071D01*
X411148Y2217818D01*
X411273Y2218565D01*
X411773Y2219218D01*
X412523Y2219778D01*
X413398Y2220151D01*
X414398Y2220338D01*
X415398D01*
X416398Y2220151D01*
X417273Y2219778D01*
X418023Y2219218D01*
X418523Y2218565D01*
X418648Y2217818D01*
G01Y2222891D02*
X411148D01*
X417398Y2225318D01*
X411148Y2227745D01*
X418648D01*
G01Y2230391D02*
X411148D01*
X417398Y2232818D01*
X411148Y2235245D01*
X418648D01*
G01Y2242185D02*
Y2238451D01*
X411148D01*
Y2242185D01*
G01X414773Y2240691D02*
Y2238451D01*
G01X418648Y2245671D02*
X411148D01*
X418648Y2249965D01*
X411148D01*
G01X418648Y2253265D02*
X411148D01*
Y2255131D01*
X411523Y2255878D01*
X412023Y2256438D01*
X412773Y2256905D01*
X413648Y2257278D01*
X414898Y2257371D01*
X416148Y2257278D01*
X417023Y2256905D01*
X417773Y2256438D01*
X418273Y2255878D01*
X418648Y2255131D01*
Y2253265D01*
G01Y2264685D02*
Y2260951D01*
X411148D01*
Y2264685D01*
G01X414773Y2263191D02*
Y2260951D01*
G01X418648Y2268265D02*
X411148D01*
Y2270131D01*
X411523Y2270878D01*
X412023Y2271438D01*
X412773Y2271905D01*
X413648Y2272278D01*
X414898Y2272371D01*
X416148Y2272278D01*
X417023Y2271905D01*
X417773Y2271438D01*
X418273Y2270878D01*
X418648Y2270131D01*
Y2268265D01*
G01Y2283265D02*
X411148D01*
Y2285131D01*
X411523Y2285878D01*
X412023Y2286438D01*
X412773Y2286905D01*
X413648Y2287278D01*
X414898Y2287371D01*
X416148Y2287278D01*
X417023Y2286905D01*
X417773Y2286438D01*
X418273Y2285878D01*
X418648Y2285131D01*
Y2283265D01*
G01Y2290951D02*
X411148D01*
Y2293285D01*
X411523Y2294031D01*
X412023Y2294498D01*
X413023Y2294685D01*
X414023Y2294498D01*
X414648Y2293938D01*
X415023Y2293285D01*
Y2290951D01*
G01Y2293285D02*
X418648Y2294685D01*
G01X411148Y2299198D02*
Y2301438D01*
G01Y2300318D02*
X418648D01*
G01Y2299198D02*
Y2301438D01*
G01X411148Y2305951D02*
X418648D01*
Y2309685D01*
G01X411148Y2313451D02*
X418648D01*
Y2317185D01*
G01X417648Y2328358D02*
X418273Y2329105D01*
X418648Y2329945D01*
Y2330691D01*
X418273Y2331438D01*
X417648Y2331998D01*
X416773Y2332278D01*
X415898Y2332091D01*
X415148Y2331625D01*
X414648Y2330785D01*
X414398Y2329665D01*
X413898Y2329011D01*
X413023Y2328731D01*
X412148Y2328918D01*
X411523Y2329385D01*
X411148Y2330038D01*
Y2330691D01*
X411398Y2331345D01*
X412023Y2331905D01*
G01X411148Y2336698D02*
Y2338938D01*
G01Y2337818D02*
X418648D01*
G01Y2336698D02*
Y2338938D01*
G01X411148Y2343545D02*
Y2347091D01*
X418648Y2343545D01*
Y2347091D01*
G01Y2354685D02*
Y2350951D01*
X411148D01*
Y2354685D01*
G01X414773Y2353191D02*
Y2350951D01*
G01X418648Y2366045D02*
X411148D01*
Y2369591D01*
G01X414773Y2368285D02*
Y2366045D01*
G01X418648Y2375318D02*
X418523Y2374571D01*
X418023Y2373918D01*
X417273Y2373358D01*
X416398Y2372985D01*
X415398Y2372798D01*
X414398D01*
X413398Y2372985D01*
X412523Y2373358D01*
X411773Y2373918D01*
X411273Y2374571D01*
X411148Y2375318D01*
X411273Y2376065D01*
X411773Y2376718D01*
X412523Y2377278D01*
X413398Y2377651D01*
X414398Y2377838D01*
X415398D01*
X416398Y2377651D01*
X417273Y2377278D01*
X418023Y2376718D01*
X418523Y2376065D01*
X418648Y2375318D01*
G01Y2380951D02*
X411148D01*
Y2383285D01*
X411523Y2384031D01*
X412023Y2384498D01*
X413023Y2384685D01*
X414023Y2384498D01*
X414648Y2383938D01*
X415023Y2383285D01*
Y2380951D01*
G01Y2383285D02*
X418648Y2384685D01*
G01X411148Y2397818D02*
X411398Y2397071D01*
X412023Y2396511D01*
X412773Y2396138D01*
X413773Y2395858D01*
X414898Y2395765D01*
X416023Y2395858D01*
X417023Y2396138D01*
X417773Y2396511D01*
X418398Y2397071D01*
X418648Y2397818D01*
X418398Y2398565D01*
X417773Y2399125D01*
X417023Y2399498D01*
X416023Y2399778D01*
X414898Y2399871D01*
X413773Y2399778D01*
X412773Y2399498D01*
X412023Y2399125D01*
X411398Y2398565D01*
X411148Y2397818D01*
G01X418898Y2405318D02*
X418773Y2405131D01*
X418523D01*
X418398Y2405318D01*
X418523Y2405505D01*
X418773D01*
X418898Y2405318D01*
G01X417523Y2410765D02*
X418148Y2411325D01*
X418523Y2411978D01*
X418648Y2412818D01*
X418398Y2413658D01*
X417898Y2414311D01*
X417023Y2414778D01*
X416023Y2414871D01*
X415023Y2414685D01*
X414398Y2414218D01*
X413898Y2413565D01*
X413773Y2412911D01*
X413898Y2412258D01*
X414398Y2411418D01*
X411148Y2411698D01*
Y2414218D01*
G01X418648Y2417891D02*
X411148D01*
X417398Y2420318D01*
X411148Y2422745D01*
X418648D01*
G01Y2425391D02*
X411148D01*
X417398Y2427818D01*
X411148Y2430245D01*
X418648D01*
G01Y2441045D02*
X411148D01*
Y2444591D01*
G01X414773Y2443285D02*
Y2441045D01*
G01X411148Y2449198D02*
Y2451438D01*
G01Y2450318D02*
X418648D01*
G01Y2449198D02*
Y2451438D01*
G01Y2455671D02*
X411148D01*
X418648Y2459965D01*
X411148D01*
G01Y2464198D02*
Y2466438D01*
G01Y2465318D02*
X418648D01*
G01Y2464198D02*
Y2466438D01*
G01X417648Y2470858D02*
X418273Y2471605D01*
X418648Y2472445D01*
Y2473191D01*
X418273Y2473938D01*
X417648Y2474498D01*
X416773Y2474778D01*
X415898Y2474591D01*
X415148Y2474125D01*
X414648Y2473285D01*
X414398Y2472165D01*
X413898Y2471511D01*
X413023Y2471231D01*
X412148Y2471418D01*
X411523Y2471885D01*
X411148Y2472538D01*
Y2473191D01*
X411398Y2473845D01*
X412023Y2474405D01*
G01X418648Y2478358D02*
X411148D01*
G01Y2482278D02*
X418648D01*
G01X414898D02*
Y2478358D01*
G01X418648Y2489685D02*
Y2485951D01*
X411148D01*
Y2489685D01*
G01X414773Y2488191D02*
Y2485951D01*
G01X418648Y2493265D02*
X411148D01*
Y2495131D01*
X411523Y2495878D01*
X412023Y2496438D01*
X412773Y2496905D01*
X413648Y2497278D01*
X414898Y2497371D01*
X416148Y2497278D01*
X417023Y2496905D01*
X417773Y2496438D01*
X418273Y2495878D01*
X418648Y2495131D01*
Y2493265D01*
G01Y2508451D02*
X411148D01*
Y2510691D01*
X411523Y2511438D01*
X412398Y2511998D01*
X413398Y2512185D01*
X414398Y2511998D01*
X415148Y2511531D01*
X415523Y2510691D01*
Y2508451D01*
G01X411148Y2517818D02*
X418648D01*
G01X411148Y2515671D02*
Y2519965D01*
G01X418648Y2523358D02*
X411148D01*
G01Y2527278D02*
X418648D01*
G01X414898D02*
Y2523358D01*
G01X411148Y2539198D02*
Y2541438D01*
G01Y2540318D02*
X418648D01*
G01Y2539198D02*
Y2541438D01*
G01X417648Y2545858D02*
X418273Y2546605D01*
X418648Y2547445D01*
Y2548191D01*
X418273Y2548938D01*
X417648Y2549498D01*
X416773Y2549778D01*
X415898Y2549591D01*
X415148Y2549125D01*
X414648Y2548285D01*
X414398Y2547165D01*
X413898Y2546511D01*
X413023Y2546231D01*
X412148Y2546418D01*
X411523Y2546885D01*
X411148Y2547538D01*
Y2548191D01*
X411398Y2548845D01*
X412023Y2549405D01*
G01X411148Y2562818D02*
X411398Y2562071D01*
X412023Y2561511D01*
X412773Y2561138D01*
X413773Y2560858D01*
X414898Y2560765D01*
X416023Y2560858D01*
X417023Y2561138D01*
X417773Y2561511D01*
X418398Y2562071D01*
X418648Y2562818D01*
X418398Y2563565D01*
X417773Y2564125D01*
X417023Y2564498D01*
X416023Y2564778D01*
X414898Y2564871D01*
X413773Y2564778D01*
X412773Y2564498D01*
X412023Y2564125D01*
X411398Y2563565D01*
X411148Y2562818D01*
G01X418898Y2570318D02*
X418773Y2570131D01*
X418523D01*
X418398Y2570318D01*
X418523Y2570505D01*
X418773D01*
X418898Y2570318D01*
G01X415523Y2576045D02*
X414648Y2576698D01*
X414148Y2577258D01*
X413898Y2578005D01*
X414148Y2578658D01*
X414648Y2579125D01*
X415398Y2579498D01*
X416273Y2579591D01*
X417023Y2579498D01*
X417773Y2579125D01*
X418398Y2578565D01*
X418648Y2577911D01*
X418398Y2577165D01*
X417648Y2576511D01*
X416523Y2576138D01*
X415273Y2576045D01*
X413648Y2576231D01*
X412773Y2576511D01*
X411898Y2576978D01*
X411273Y2577631D01*
X411148Y2578285D01*
X411398Y2578938D01*
X412023Y2579405D01*
G01X418648Y2582891D02*
X411148D01*
X417398Y2585318D01*
X411148Y2587745D01*
X418648D01*
G01Y2590391D02*
X411148D01*
X417398Y2592818D01*
X411148Y2595245D01*
X418648D01*
G01Y2605391D02*
X411148D01*
X417398Y2607818D01*
X411148Y2610245D01*
X418648D01*
G01Y2617185D02*
Y2613451D01*
X411148D01*
Y2617185D01*
G01X414773Y2615691D02*
Y2613451D01*
G01X411148Y2622818D02*
X418648D01*
G01X411148Y2620671D02*
Y2624965D01*
G01X418648Y2628451D02*
X411148D01*
Y2630785D01*
X411523Y2631531D01*
X412023Y2631998D01*
X413023Y2632185D01*
X414023Y2631998D01*
X414648Y2631438D01*
X415023Y2630785D01*
Y2628451D01*
G01Y2630785D02*
X418648Y2632185D01*
G01X411148Y2636698D02*
Y2638938D01*
G01Y2637818D02*
X418648D01*
G01Y2636698D02*
Y2638938D01*
G01X411773Y2647371D02*
X411398Y2646811D01*
X411148Y2646158D01*
Y2645411D01*
X411523Y2644571D01*
X412148Y2643918D01*
X412898Y2643451D01*
X414148Y2643078D01*
X415273Y2642985D01*
X416398Y2643171D01*
X417148Y2643451D01*
X417898Y2644011D01*
X418398Y2644665D01*
X418648Y2645318D01*
Y2645971D01*
X418398Y2646625D01*
X418023Y2647185D01*
X417523Y2647651D01*
G01X418648Y2658265D02*
X411148D01*
Y2660131D01*
X411523Y2660878D01*
X412023Y2661438D01*
X412773Y2661905D01*
X413648Y2662278D01*
X414898Y2662371D01*
X416148Y2662278D01*
X417023Y2661905D01*
X417773Y2661438D01*
X418273Y2660878D01*
X418648Y2660131D01*
Y2658265D01*
G01Y2665951D02*
X411148D01*
Y2668285D01*
X411523Y2669031D01*
X412023Y2669498D01*
X413023Y2669685D01*
X414023Y2669498D01*
X414648Y2668938D01*
X415023Y2668285D01*
Y2665951D01*
G01Y2668285D02*
X418648Y2669685D01*
G01X411148Y2674198D02*
Y2676438D01*
G01Y2675318D02*
X418648D01*
G01Y2674198D02*
Y2676438D01*
G01X411148Y2680951D02*
X418648D01*
Y2684685D01*
G01X411148Y2688451D02*
X418648D01*
Y2692185D01*
G01X421148Y2697351D02*
X419898Y2696418D01*
X418648Y2695951D01*
X413648D01*
X412398Y2696418D01*
X411148Y2697351D01*
G01Y2705318D02*
X411398Y2704571D01*
X412023Y2704011D01*
X412773Y2703638D01*
X413773Y2703358D01*
X414898Y2703265D01*
X416023Y2703358D01*
X417023Y2703638D01*
X417773Y2704011D01*
X418398Y2704571D01*
X418648Y2705318D01*
X418398Y2706065D01*
X417773Y2706625D01*
X417023Y2706998D01*
X416023Y2707278D01*
X414898Y2707371D01*
X413773Y2707278D01*
X412773Y2706998D01*
X412023Y2706625D01*
X411398Y2706065D01*
X411148Y2705318D01*
G01X418898Y2712818D02*
X418773Y2712631D01*
X418523D01*
X418398Y2712818D01*
X418523Y2713005D01*
X418773D01*
X418898Y2712818D01*
G01X411148Y2720318D02*
X411398Y2719571D01*
X412023Y2719011D01*
X412773Y2718638D01*
X413773Y2718358D01*
X414898Y2718265D01*
X416023Y2718358D01*
X417023Y2718638D01*
X417773Y2719011D01*
X418398Y2719571D01*
X418648Y2720318D01*
X418398Y2721065D01*
X417773Y2721625D01*
X417023Y2721998D01*
X416023Y2722278D01*
X414898Y2722371D01*
X413773Y2722278D01*
X412773Y2721998D01*
X412023Y2721625D01*
X411398Y2721065D01*
X411148Y2720318D01*
G01X412398Y2726045D02*
X411648Y2726605D01*
X411273Y2727258D01*
X411148Y2728005D01*
X411398Y2728938D01*
X412023Y2729591D01*
X412773Y2729778D01*
X413523Y2729685D01*
X414148Y2729311D01*
X415398Y2727445D01*
X416273Y2726605D01*
X417523Y2726045D01*
X418648Y2725858D01*
Y2729778D01*
G01X417148Y2733265D02*
X418023Y2733825D01*
X418523Y2734571D01*
X418648Y2735411D01*
X418523Y2736158D01*
X417898Y2736905D01*
X417148Y2737371D01*
X416398Y2737465D01*
X415523Y2737278D01*
X414898Y2736625D01*
X414648Y2735971D01*
Y2735131D01*
G01Y2735971D02*
X414273Y2736531D01*
X413648Y2736998D01*
X412898Y2737185D01*
X412148Y2736998D01*
X411523Y2736531D01*
X411148Y2735691D01*
X411273Y2734851D01*
X411773Y2734011D01*
G01X415523Y2741045D02*
X414648Y2741698D01*
X414148Y2742258D01*
X413898Y2743005D01*
X414148Y2743658D01*
X414648Y2744125D01*
X415398Y2744498D01*
X416273Y2744591D01*
X417023Y2744498D01*
X417773Y2744125D01*
X418398Y2743565D01*
X418648Y2742911D01*
X418398Y2742165D01*
X417648Y2741511D01*
X416523Y2741138D01*
X415273Y2741045D01*
X413648Y2741231D01*
X412773Y2741511D01*
X411898Y2741978D01*
X411273Y2742631D01*
X411148Y2743285D01*
X411398Y2743938D01*
X412023Y2744405D01*
G01X412773Y2749478D02*
X411148Y2749945D01*
G01Y2751158D02*
X412773Y2750691D01*
G01X421148Y2758285D02*
X419898Y2759218D01*
X418648Y2759685D01*
X413648D01*
X412398Y2759218D01*
X411148Y2758285D01*
G01X418898Y2765318D02*
X418773Y2765131D01*
X418523D01*
X418398Y2765318D01*
X418523Y2765505D01*
X418773D01*
X418898Y2765318D01*
G01X447293Y-376063D02*
X434793D01*
X443751Y-381798D01*
Y-374048D01*
G01X447293Y-363663D02*
X434793D01*
X443751Y-369398D01*
Y-361648D01*
G01X447293Y-353123D02*
X434793D01*
X437293Y-354983D01*
G01X447293D02*
Y-351263D01*
G01X434793Y-340723D02*
X435210Y-341963D01*
X436251Y-342893D01*
X437501Y-343513D01*
X439168Y-343978D01*
X441043Y-344133D01*
X442918Y-343978D01*
X444585Y-343513D01*
X445835Y-342893D01*
X446876Y-341963D01*
X447293Y-340723D01*
X446876Y-339483D01*
X445835Y-338553D01*
X444585Y-337933D01*
X442918Y-337468D01*
X441043Y-337313D01*
X439168Y-337468D01*
X437501Y-337933D01*
X436251Y-338553D01*
X435210Y-339483D01*
X434793Y-340723D01*
G01X447710Y-328323D02*
X447501Y-328633D01*
X447085D01*
X446876Y-328323D01*
X447085Y-328013D01*
X447501D01*
X447710Y-328323D01*
G01X447293Y-314063D02*
X434793D01*
X443751Y-319798D01*
Y-312048D01*
G01X444793Y-306933D02*
X446252Y-306003D01*
X447085Y-304763D01*
X447293Y-303368D01*
X447085Y-302128D01*
X446043Y-300888D01*
X444793Y-300113D01*
X443543Y-299958D01*
X442085Y-300268D01*
X441043Y-301353D01*
X440626Y-302438D01*
Y-303833D01*
G01Y-302438D02*
X440001Y-301508D01*
X438960Y-300733D01*
X437710Y-300423D01*
X436460Y-300733D01*
X435418Y-301508D01*
X434793Y-302903D01*
X435001Y-304298D01*
X435835Y-305693D01*
G01X447293Y-268923D02*
X434793D01*
X437293Y-270783D01*
G01X447293D02*
Y-267063D01*
G01Y-256523D02*
X434793D01*
X437293Y-258383D01*
G01X447293D02*
Y-254663D01*
G01X436876Y-247068D02*
X435627Y-246138D01*
X435001Y-245053D01*
X434793Y-243813D01*
X435210Y-242263D01*
X436251Y-241178D01*
X437501Y-240868D01*
X438752Y-241023D01*
X439793Y-241643D01*
X441876Y-244743D01*
X443335Y-246138D01*
X445418Y-247068D01*
X447293Y-247378D01*
Y-240868D01*
G01X447710Y-231723D02*
X447501Y-232033D01*
X447085D01*
X446876Y-231723D01*
X447085Y-231413D01*
X447501D01*
X447710Y-231723D01*
G01X434793Y-219323D02*
X435210Y-220563D01*
X436251Y-221493D01*
X437501Y-222113D01*
X439168Y-222578D01*
X441043Y-222733D01*
X442918Y-222578D01*
X444585Y-222113D01*
X445835Y-221493D01*
X446876Y-220563D01*
X447293Y-219323D01*
X446876Y-218083D01*
X445835Y-217153D01*
X444585Y-216533D01*
X442918Y-216068D01*
X441043Y-215913D01*
X439168Y-216068D01*
X437501Y-216533D01*
X436251Y-217153D01*
X435210Y-218083D01*
X434793Y-219323D01*
G01X436876Y-209868D02*
X435627Y-208938D01*
X435001Y-207853D01*
X434793Y-206613D01*
X435210Y-205063D01*
X436251Y-203978D01*
X437501Y-203668D01*
X438752Y-203823D01*
X439793Y-204443D01*
X441876Y-207543D01*
X443335Y-208938D01*
X445418Y-209868D01*
X447293Y-210178D01*
Y-203668D01*
G01X435898Y2021234D02*
X428398D01*
X435898Y2025528D01*
X428398D01*
G01X435898Y2030881D02*
X435773Y2030134D01*
X435273Y2029481D01*
X434523Y2028921D01*
X433648Y2028548D01*
X432648Y2028361D01*
X431648D01*
X430648Y2028548D01*
X429773Y2028921D01*
X429023Y2029481D01*
X428523Y2030134D01*
X428398Y2030881D01*
X428523Y2031628D01*
X429023Y2032281D01*
X429773Y2032841D01*
X430648Y2033214D01*
X431648Y2033401D01*
X432648D01*
X433648Y2033214D01*
X434523Y2032841D01*
X435273Y2032281D01*
X435773Y2031628D01*
X435898Y2030881D01*
G01Y2036234D02*
X428398D01*
X435898Y2040528D01*
X428398D01*
G01X433398Y2044668D02*
Y2047094D01*
G01X435898Y2050954D02*
X428398D01*
X434648Y2053381D01*
X428398Y2055808D01*
X435898D01*
G01Y2058548D02*
X428398Y2060881D01*
X435898Y2063214D01*
G01X433273Y2062374D02*
Y2059388D01*
G01X435898Y2066514D02*
X428398D01*
Y2068848D01*
X428773Y2069594D01*
X429273Y2070061D01*
X430273Y2070248D01*
X431273Y2070061D01*
X431898Y2069501D01*
X432273Y2068848D01*
Y2066514D01*
G01Y2068848D02*
X435898Y2070248D01*
G01Y2073828D02*
X428398D01*
G01Y2077374D02*
X433023Y2073828D01*
G01X435898Y2077934D02*
X430898Y2075414D01*
G01X436148Y2083381D02*
X436023Y2083194D01*
X435773D01*
X435648Y2083381D01*
X435773Y2083568D01*
X436023D01*
X436148Y2083381D01*
G01X432773D02*
X432648Y2083194D01*
X432398D01*
X432273Y2083381D01*
X432398Y2083568D01*
X432648D01*
X432773Y2083381D01*
G01X428398Y2090881D02*
X435898D01*
G01X428398Y2088734D02*
Y2093028D01*
G01Y2097261D02*
Y2099501D01*
G01Y2098381D02*
X435898D01*
G01Y2097261D02*
Y2099501D01*
G01Y2103734D02*
X428398D01*
X435898Y2108028D01*
X428398D01*
G01Y2119014D02*
X435898D01*
Y2122748D01*
G01Y2130248D02*
Y2126514D01*
X428398D01*
Y2130248D01*
G01X432023Y2128754D02*
Y2126514D01*
G01X435898Y2133548D02*
X428398Y2135881D01*
X435898Y2138214D01*
G01X433273Y2137374D02*
Y2134388D01*
G01X435898Y2141328D02*
X428398D01*
Y2143194D01*
X428773Y2143941D01*
X429273Y2144501D01*
X430023Y2144968D01*
X430898Y2145341D01*
X432148Y2145434D01*
X433398Y2145341D01*
X434273Y2144968D01*
X435023Y2144501D01*
X435523Y2143941D01*
X435898Y2143194D01*
Y2141328D01*
G01X436148Y2150881D02*
X436023Y2150694D01*
X435773D01*
X435648Y2150881D01*
X435773Y2151068D01*
X436023D01*
X436148Y2150881D01*
G01X432773D02*
X432648Y2150694D01*
X432398D01*
X432273Y2150881D01*
X432398Y2151068D01*
X432648D01*
X432773Y2150881D01*
G01X435898Y2156514D02*
X428398D01*
Y2158848D01*
X428773Y2159594D01*
X429273Y2160061D01*
X430273Y2160248D01*
X431273Y2160061D01*
X431898Y2159501D01*
X432273Y2158848D01*
Y2156514D01*
G01Y2158848D02*
X435898Y2160248D01*
G01Y2167748D02*
Y2164014D01*
X428398D01*
Y2167748D01*
G01X432023Y2166254D02*
Y2164014D01*
G01X429023Y2175434D02*
X428648Y2174874D01*
X428398Y2174221D01*
Y2173474D01*
X428773Y2172634D01*
X429398Y2171981D01*
X430148Y2171514D01*
X431398Y2171141D01*
X432523Y2171048D01*
X433648Y2171234D01*
X434398Y2171514D01*
X435148Y2172074D01*
X435648Y2172728D01*
X435898Y2173381D01*
Y2174034D01*
X435648Y2174688D01*
X435273Y2175248D01*
X434773Y2175714D01*
G01X435898Y2180881D02*
X435773Y2180134D01*
X435273Y2179481D01*
X434523Y2178921D01*
X433648Y2178548D01*
X432648Y2178361D01*
X431648D01*
X430648Y2178548D01*
X429773Y2178921D01*
X429023Y2179481D01*
X428523Y2180134D01*
X428398Y2180881D01*
X428523Y2181628D01*
X429023Y2182281D01*
X429773Y2182841D01*
X430648Y2183214D01*
X431648Y2183401D01*
X432648D01*
X433648Y2183214D01*
X434523Y2182841D01*
X435273Y2182281D01*
X435773Y2181628D01*
X435898Y2180881D01*
G01Y2185954D02*
X428398D01*
X434648Y2188381D01*
X428398Y2190808D01*
X435898D01*
G01Y2193454D02*
X428398D01*
X434648Y2195881D01*
X428398Y2198308D01*
X435898D01*
G01Y2205248D02*
Y2201514D01*
X428398D01*
Y2205248D01*
G01X432023Y2203754D02*
Y2201514D01*
G01X435898Y2208734D02*
X428398D01*
X435898Y2213028D01*
X428398D01*
G01X435898Y2216328D02*
X428398D01*
Y2218194D01*
X428773Y2218941D01*
X429273Y2219501D01*
X430023Y2219968D01*
X430898Y2220341D01*
X432148Y2220434D01*
X433398Y2220341D01*
X434273Y2219968D01*
X435023Y2219501D01*
X435523Y2218941D01*
X435898Y2218194D01*
Y2216328D01*
G01Y2227748D02*
Y2224014D01*
X428398D01*
Y2227748D01*
G01X432023Y2226254D02*
Y2224014D01*
G01X435898Y2231328D02*
X428398D01*
Y2233194D01*
X428773Y2233941D01*
X429273Y2234501D01*
X430023Y2234968D01*
X430898Y2235341D01*
X432148Y2235434D01*
X433398Y2235341D01*
X434273Y2234968D01*
X435023Y2234501D01*
X435523Y2233941D01*
X435898Y2233194D01*
Y2231328D01*
G01Y2246328D02*
X428398D01*
Y2248194D01*
X428773Y2248941D01*
X429273Y2249501D01*
X430023Y2249968D01*
X430898Y2250341D01*
X432148Y2250434D01*
X433398Y2250341D01*
X434273Y2249968D01*
X435023Y2249501D01*
X435523Y2248941D01*
X435898Y2248194D01*
Y2246328D01*
G01Y2254014D02*
X428398D01*
Y2256348D01*
X428773Y2257094D01*
X429273Y2257561D01*
X430273Y2257748D01*
X431273Y2257561D01*
X431898Y2257001D01*
X432273Y2256348D01*
Y2254014D01*
G01Y2256348D02*
X435898Y2257748D01*
G01X428398Y2262261D02*
Y2264501D01*
G01Y2263381D02*
X435898D01*
G01Y2262261D02*
Y2264501D01*
G01X428398Y2269014D02*
X435898D01*
Y2272748D01*
G01X428398Y2276514D02*
X435898D01*
Y2280248D01*
G01X434898Y2291421D02*
X435523Y2292168D01*
X435898Y2293008D01*
Y2293754D01*
X435523Y2294501D01*
X434898Y2295061D01*
X434023Y2295341D01*
X433148Y2295154D01*
X432398Y2294688D01*
X431898Y2293848D01*
X431648Y2292728D01*
X431148Y2292074D01*
X430273Y2291794D01*
X429398Y2291981D01*
X428773Y2292448D01*
X428398Y2293101D01*
Y2293754D01*
X428648Y2294408D01*
X429273Y2294968D01*
G01X428398Y2299761D02*
Y2302001D01*
G01Y2300881D02*
X435898D01*
G01Y2299761D02*
Y2302001D01*
G01X428398Y2306608D02*
Y2310154D01*
X435898Y2306608D01*
Y2310154D01*
G01Y2317748D02*
Y2314014D01*
X428398D01*
Y2317748D01*
G01X432023Y2316254D02*
Y2314014D01*
G01X435898Y2329108D02*
X428398D01*
Y2332654D01*
G01X432023Y2331348D02*
Y2329108D01*
G01X435898Y2338381D02*
X435773Y2337634D01*
X435273Y2336981D01*
X434523Y2336421D01*
X433648Y2336048D01*
X432648Y2335861D01*
X431648D01*
X430648Y2336048D01*
X429773Y2336421D01*
X429023Y2336981D01*
X428523Y2337634D01*
X428398Y2338381D01*
X428523Y2339128D01*
X429023Y2339781D01*
X429773Y2340341D01*
X430648Y2340714D01*
X431648Y2340901D01*
X432648D01*
X433648Y2340714D01*
X434523Y2340341D01*
X435273Y2339781D01*
X435773Y2339128D01*
X435898Y2338381D01*
G01Y2344014D02*
X428398D01*
Y2346348D01*
X428773Y2347094D01*
X429273Y2347561D01*
X430273Y2347748D01*
X431273Y2347561D01*
X431898Y2347001D01*
X432273Y2346348D01*
Y2344014D01*
G01Y2346348D02*
X435898Y2347748D01*
G01X428398Y2360881D02*
X428648Y2360134D01*
X429273Y2359574D01*
X430023Y2359201D01*
X431023Y2358921D01*
X432148Y2358828D01*
X433273Y2358921D01*
X434273Y2359201D01*
X435023Y2359574D01*
X435648Y2360134D01*
X435898Y2360881D01*
X435648Y2361628D01*
X435023Y2362188D01*
X434273Y2362561D01*
X433273Y2362841D01*
X432148Y2362934D01*
X431023Y2362841D01*
X430023Y2362561D01*
X429273Y2362188D01*
X428648Y2361628D01*
X428398Y2360881D01*
G01X436148Y2368381D02*
X436023Y2368194D01*
X435773D01*
X435648Y2368381D01*
X435773Y2368568D01*
X436023D01*
X436148Y2368381D01*
G01X434398Y2373828D02*
X435273Y2374388D01*
X435773Y2375134D01*
X435898Y2375974D01*
X435773Y2376721D01*
X435148Y2377468D01*
X434398Y2377934D01*
X433648Y2378028D01*
X432773Y2377841D01*
X432148Y2377188D01*
X431898Y2376534D01*
Y2375694D01*
G01Y2376534D02*
X431523Y2377094D01*
X430898Y2377561D01*
X430148Y2377748D01*
X429398Y2377561D01*
X428773Y2377094D01*
X428398Y2376254D01*
X428523Y2375414D01*
X429023Y2374574D01*
G01X432773Y2381608D02*
X431898Y2382261D01*
X431398Y2382821D01*
X431148Y2383568D01*
X431398Y2384221D01*
X431898Y2384688D01*
X432648Y2385061D01*
X433523Y2385154D01*
X434273Y2385061D01*
X435023Y2384688D01*
X435648Y2384128D01*
X435898Y2383474D01*
X435648Y2382728D01*
X434898Y2382074D01*
X433773Y2381701D01*
X432523Y2381608D01*
X430898Y2381794D01*
X430023Y2382074D01*
X429148Y2382541D01*
X428523Y2383194D01*
X428398Y2383848D01*
X428648Y2384501D01*
X429273Y2384968D01*
G01X435898Y2388454D02*
X428398D01*
X434648Y2390881D01*
X428398Y2393308D01*
X435898D01*
G01Y2395954D02*
X428398D01*
X434648Y2398381D01*
X428398Y2400808D01*
X435898D01*
G01Y2411608D02*
X428398D01*
Y2415154D01*
G01X432023Y2413848D02*
Y2411608D01*
G01X428398Y2419761D02*
Y2422001D01*
G01Y2420881D02*
X435898D01*
G01Y2419761D02*
Y2422001D01*
G01Y2426234D02*
X428398D01*
X435898Y2430528D01*
X428398D01*
G01Y2434761D02*
Y2437001D01*
G01Y2435881D02*
X435898D01*
G01Y2434761D02*
Y2437001D01*
G01X434898Y2441421D02*
X435523Y2442168D01*
X435898Y2443008D01*
Y2443754D01*
X435523Y2444501D01*
X434898Y2445061D01*
X434023Y2445341D01*
X433148Y2445154D01*
X432398Y2444688D01*
X431898Y2443848D01*
X431648Y2442728D01*
X431148Y2442074D01*
X430273Y2441794D01*
X429398Y2441981D01*
X428773Y2442448D01*
X428398Y2443101D01*
Y2443754D01*
X428648Y2444408D01*
X429273Y2444968D01*
G01X435898Y2448921D02*
X428398D01*
G01Y2452841D02*
X435898D01*
G01X432148D02*
Y2448921D01*
G01X435898Y2460248D02*
Y2456514D01*
X428398D01*
Y2460248D01*
G01X432023Y2458754D02*
Y2456514D01*
G01X435898Y2463828D02*
X428398D01*
Y2465694D01*
X428773Y2466441D01*
X429273Y2467001D01*
X430023Y2467468D01*
X430898Y2467841D01*
X432148Y2467934D01*
X433398Y2467841D01*
X434273Y2467468D01*
X435023Y2467001D01*
X435523Y2466441D01*
X435898Y2465694D01*
Y2463828D01*
G01Y2479014D02*
X428398D01*
Y2481254D01*
X428773Y2482001D01*
X429648Y2482561D01*
X430648Y2482748D01*
X431648Y2482561D01*
X432398Y2482094D01*
X432773Y2481254D01*
Y2479014D01*
G01X428398Y2488381D02*
X435898D01*
G01X428398Y2486234D02*
Y2490528D01*
G01X435898Y2493921D02*
X428398D01*
G01Y2497841D02*
X435898D01*
G01X432148D02*
Y2493921D01*
G01X428398Y2509761D02*
Y2512001D01*
G01Y2510881D02*
X435898D01*
G01Y2509761D02*
Y2512001D01*
G01X434898Y2516421D02*
X435523Y2517168D01*
X435898Y2518008D01*
Y2518754D01*
X435523Y2519501D01*
X434898Y2520061D01*
X434023Y2520341D01*
X433148Y2520154D01*
X432398Y2519688D01*
X431898Y2518848D01*
X431648Y2517728D01*
X431148Y2517074D01*
X430273Y2516794D01*
X429398Y2516981D01*
X428773Y2517448D01*
X428398Y2518101D01*
Y2518754D01*
X428648Y2519408D01*
X429273Y2519968D01*
G01X428398Y2533381D02*
X428648Y2532634D01*
X429273Y2532074D01*
X430023Y2531701D01*
X431023Y2531421D01*
X432148Y2531328D01*
X433273Y2531421D01*
X434273Y2531701D01*
X435023Y2532074D01*
X435648Y2532634D01*
X435898Y2533381D01*
X435648Y2534128D01*
X435023Y2534688D01*
X434273Y2535061D01*
X433273Y2535341D01*
X432148Y2535434D01*
X431023Y2535341D01*
X430023Y2535061D01*
X429273Y2534688D01*
X428648Y2534128D01*
X428398Y2533381D01*
G01X436148Y2540881D02*
X436023Y2540694D01*
X435773D01*
X435648Y2540881D01*
X435773Y2541068D01*
X436023D01*
X436148Y2540881D01*
G01X435898Y2549501D02*
X428398D01*
X433773Y2546048D01*
Y2550714D01*
G01X434773Y2553828D02*
X435398Y2554388D01*
X435773Y2555041D01*
X435898Y2555881D01*
X435648Y2556721D01*
X435148Y2557374D01*
X434273Y2557841D01*
X433273Y2557934D01*
X432273Y2557748D01*
X431648Y2557281D01*
X431148Y2556628D01*
X431023Y2555974D01*
X431148Y2555321D01*
X431648Y2554481D01*
X428398Y2554761D01*
Y2557281D01*
G01X435898Y2560954D02*
X428398D01*
X434648Y2563381D01*
X428398Y2565808D01*
X435898D01*
G01Y2568454D02*
X428398D01*
X434648Y2570881D01*
X428398Y2573308D01*
X435898D01*
G01Y2583454D02*
X428398D01*
X434648Y2585881D01*
X428398Y2588308D01*
X435898D01*
G01Y2595248D02*
Y2591514D01*
X428398D01*
Y2595248D01*
G01X432023Y2593754D02*
Y2591514D01*
G01X428398Y2600881D02*
X435898D01*
G01X428398Y2598734D02*
Y2603028D01*
G01X435898Y2606514D02*
X428398D01*
Y2608848D01*
X428773Y2609594D01*
X429273Y2610061D01*
X430273Y2610248D01*
X431273Y2610061D01*
X431898Y2609501D01*
X432273Y2608848D01*
Y2606514D01*
G01Y2608848D02*
X435898Y2610248D01*
G01X428398Y2614761D02*
Y2617001D01*
G01Y2615881D02*
X435898D01*
G01Y2614761D02*
Y2617001D01*
G01X429023Y2625434D02*
X428648Y2624874D01*
X428398Y2624221D01*
Y2623474D01*
X428773Y2622634D01*
X429398Y2621981D01*
X430148Y2621514D01*
X431398Y2621141D01*
X432523Y2621048D01*
X433648Y2621234D01*
X434398Y2621514D01*
X435148Y2622074D01*
X435648Y2622728D01*
X435898Y2623381D01*
Y2624034D01*
X435648Y2624688D01*
X435273Y2625248D01*
X434773Y2625714D01*
G01X435898Y2636328D02*
X428398D01*
Y2638194D01*
X428773Y2638941D01*
X429273Y2639501D01*
X430023Y2639968D01*
X430898Y2640341D01*
X432148Y2640434D01*
X433398Y2640341D01*
X434273Y2639968D01*
X435023Y2639501D01*
X435523Y2638941D01*
X435898Y2638194D01*
Y2636328D01*
G01Y2644014D02*
X428398D01*
Y2646348D01*
X428773Y2647094D01*
X429273Y2647561D01*
X430273Y2647748D01*
X431273Y2647561D01*
X431898Y2647001D01*
X432273Y2646348D01*
Y2644014D01*
G01Y2646348D02*
X435898Y2647748D01*
G01X428398Y2652261D02*
Y2654501D01*
G01Y2653381D02*
X435898D01*
G01Y2652261D02*
Y2654501D01*
G01X428398Y2659014D02*
X435898D01*
Y2662748D01*
G01X428398Y2666514D02*
X435898D01*
Y2670248D01*
G01X438398Y2675414D02*
X437148Y2674481D01*
X435898Y2674014D01*
X430898D01*
X429648Y2674481D01*
X428398Y2675414D01*
G01Y2683381D02*
X428648Y2682634D01*
X429273Y2682074D01*
X430023Y2681701D01*
X431023Y2681421D01*
X432148Y2681328D01*
X433273Y2681421D01*
X434273Y2681701D01*
X435023Y2682074D01*
X435648Y2682634D01*
X435898Y2683381D01*
X435648Y2684128D01*
X435023Y2684688D01*
X434273Y2685061D01*
X433273Y2685341D01*
X432148Y2685434D01*
X431023Y2685341D01*
X430023Y2685061D01*
X429273Y2684688D01*
X428648Y2684128D01*
X428398Y2683381D01*
G01X436148Y2690881D02*
X436023Y2690694D01*
X435773D01*
X435648Y2690881D01*
X435773Y2691068D01*
X436023D01*
X436148Y2690881D01*
G01X428398Y2698381D02*
X428648Y2697634D01*
X429273Y2697074D01*
X430023Y2696701D01*
X431023Y2696421D01*
X432148Y2696328D01*
X433273Y2696421D01*
X434273Y2696701D01*
X435023Y2697074D01*
X435648Y2697634D01*
X435898Y2698381D01*
X435648Y2699128D01*
X435023Y2699688D01*
X434273Y2700061D01*
X433273Y2700341D01*
X432148Y2700434D01*
X431023Y2700341D01*
X430023Y2700061D01*
X429273Y2699688D01*
X428648Y2699128D01*
X428398Y2698381D01*
G01X435898Y2705881D02*
X428398D01*
X429898Y2704761D01*
G01X435898D02*
Y2707001D01*
G01Y2713194D02*
X434273Y2713381D01*
X432898Y2713661D01*
X431648Y2714034D01*
X430273Y2714501D01*
X428398Y2715248D01*
Y2711514D01*
G01X435898Y2720694D02*
X434273Y2720881D01*
X432898Y2721161D01*
X431648Y2721534D01*
X430273Y2722001D01*
X428398Y2722748D01*
Y2719014D01*
G01X430023Y2727541D02*
X428398Y2728008D01*
G01Y2729221D02*
X430023Y2728754D01*
G01X438398Y2736348D02*
X437148Y2737281D01*
X435898Y2737748D01*
X430898D01*
X429648Y2737281D01*
X428398Y2736348D01*
G01X436148Y2743381D02*
X436023Y2743194D01*
X435773D01*
X435648Y2743381D01*
X435773Y2743568D01*
X436023D01*
X436148Y2743381D01*
G01X442823Y2055184D02*
X442448Y2054624D01*
X442198Y2053971D01*
Y2053224D01*
X442573Y2052384D01*
X443198Y2051731D01*
X443948Y2051264D01*
X445198Y2050891D01*
X446323Y2050798D01*
X447448Y2050984D01*
X448198Y2051264D01*
X448948Y2051824D01*
X449448Y2052478D01*
X449698Y2053131D01*
Y2053784D01*
X449448Y2054438D01*
X449073Y2054998D01*
X448573Y2055464D01*
G01X449698Y2060631D02*
X449573Y2059884D01*
X449073Y2059231D01*
X448323Y2058671D01*
X447448Y2058298D01*
X446448Y2058111D01*
X445448D01*
X444448Y2058298D01*
X443573Y2058671D01*
X442823Y2059231D01*
X442323Y2059884D01*
X442198Y2060631D01*
X442323Y2061378D01*
X442823Y2062031D01*
X443573Y2062591D01*
X444448Y2062964D01*
X445448Y2063151D01*
X446448D01*
X447448Y2062964D01*
X448323Y2062591D01*
X449073Y2062031D01*
X449573Y2061378D01*
X449698Y2060631D01*
G01Y2066264D02*
X442198D01*
Y2068504D01*
X442573Y2069251D01*
X443448Y2069811D01*
X444448Y2069998D01*
X445448Y2069811D01*
X446198Y2069344D01*
X446573Y2068504D01*
Y2066264D01*
G01X449698Y2073764D02*
X442198D01*
Y2076004D01*
X442573Y2076751D01*
X443448Y2077311D01*
X444448Y2077498D01*
X445448Y2077311D01*
X446198Y2076844D01*
X446573Y2076004D01*
Y2073764D01*
G01X449698Y2084998D02*
Y2081264D01*
X442198D01*
Y2084998D01*
G01X445823Y2083504D02*
Y2081264D01*
G01X449698Y2088764D02*
X442198D01*
Y2091098D01*
X442573Y2091844D01*
X443073Y2092311D01*
X444073Y2092498D01*
X445073Y2092311D01*
X445698Y2091751D01*
X446073Y2091098D01*
Y2088764D01*
G01Y2091098D02*
X449698Y2092498D01*
G01Y2105631D02*
X449573Y2104884D01*
X449073Y2104231D01*
X448323Y2103671D01*
X447448Y2103298D01*
X446448Y2103111D01*
X445448D01*
X444448Y2103298D01*
X443573Y2103671D01*
X442823Y2104231D01*
X442323Y2104884D01*
X442198Y2105631D01*
X442323Y2106378D01*
X442823Y2107031D01*
X443573Y2107591D01*
X444448Y2107964D01*
X445448Y2108151D01*
X446448D01*
X447448Y2107964D01*
X448323Y2107591D01*
X449073Y2107031D01*
X449573Y2106378D01*
X449698Y2105631D01*
G01X448698Y2111171D02*
X449323Y2111918D01*
X449698Y2112758D01*
Y2113504D01*
X449323Y2114251D01*
X448698Y2114811D01*
X447823Y2115091D01*
X446948Y2114904D01*
X446198Y2114438D01*
X445698Y2113598D01*
X445448Y2112478D01*
X444948Y2111824D01*
X444073Y2111544D01*
X443198Y2111731D01*
X442573Y2112198D01*
X442198Y2112851D01*
Y2113504D01*
X442448Y2114158D01*
X443073Y2114718D01*
G01X449698Y2118764D02*
X442198D01*
Y2121004D01*
X442573Y2121751D01*
X443448Y2122311D01*
X444448Y2122498D01*
X445448Y2122311D01*
X446198Y2121844D01*
X446573Y2121004D01*
Y2118764D01*
G01X449948Y2126451D02*
X442198Y2129811D01*
G01Y2135631D02*
X449698D01*
G01X442198Y2133484D02*
Y2137778D01*
G01Y2142011D02*
Y2144251D01*
G01Y2143131D02*
X449698D01*
G01Y2142011D02*
Y2144251D01*
G01Y2148484D02*
X442198D01*
X449698Y2152778D01*
X442198D01*
G01X452198Y2157664D02*
X450948Y2156731D01*
X449698Y2156264D01*
X444698D01*
X443448Y2156731D01*
X442198Y2157664D01*
G01Y2164511D02*
Y2166751D01*
G01Y2165631D02*
X449698D01*
G01Y2164511D02*
Y2166751D01*
G01Y2170704D02*
X442198D01*
X448448Y2173131D01*
X442198Y2175558D01*
X449698D01*
G01Y2178204D02*
X442198D01*
X448448Y2180631D01*
X442198Y2183058D01*
X449698D01*
G01Y2189998D02*
Y2186264D01*
X442198D01*
Y2189998D01*
G01X445823Y2188504D02*
Y2186264D01*
G01X449698Y2193764D02*
X442198D01*
Y2196098D01*
X442573Y2196844D01*
X443073Y2197311D01*
X444073Y2197498D01*
X445073Y2197311D01*
X445698Y2196751D01*
X446073Y2196098D01*
Y2193764D01*
G01Y2196098D02*
X449698Y2197498D01*
G01X448698Y2201171D02*
X449323Y2201918D01*
X449698Y2202758D01*
Y2203504D01*
X449323Y2204251D01*
X448698Y2204811D01*
X447823Y2205091D01*
X446948Y2204904D01*
X446198Y2204438D01*
X445698Y2203598D01*
X445448Y2202478D01*
X444948Y2201824D01*
X444073Y2201544D01*
X443198Y2201731D01*
X442573Y2202198D01*
X442198Y2202851D01*
Y2203504D01*
X442448Y2204158D01*
X443073Y2204718D01*
G01X442198Y2209511D02*
Y2211751D01*
G01Y2210631D02*
X449698D01*
G01Y2209511D02*
Y2211751D01*
G01Y2218131D02*
X449573Y2217384D01*
X449073Y2216731D01*
X448323Y2216171D01*
X447448Y2215798D01*
X446448Y2215611D01*
X445448D01*
X444448Y2215798D01*
X443573Y2216171D01*
X442823Y2216731D01*
X442323Y2217384D01*
X442198Y2218131D01*
X442323Y2218878D01*
X442823Y2219531D01*
X443573Y2220091D01*
X444448Y2220464D01*
X445448Y2220651D01*
X446448D01*
X447448Y2220464D01*
X448323Y2220091D01*
X449073Y2219531D01*
X449573Y2218878D01*
X449698Y2218131D01*
G01Y2223484D02*
X442198D01*
X449698Y2227778D01*
X442198D01*
G01X452198Y2233598D02*
X450948Y2234531D01*
X449698Y2234998D01*
X444698D01*
X443448Y2234531D01*
X442198Y2233598D01*
G01X449948Y2240631D02*
X449823Y2240444D01*
X449573D01*
X449448Y2240631D01*
X449573Y2240818D01*
X449823D01*
X449948Y2240631D01*
G01X446573D02*
X446448Y2240444D01*
X446198D01*
X446073Y2240631D01*
X446198Y2240818D01*
X446448D01*
X446573Y2240631D01*
G01X449698Y2246264D02*
X442198D01*
Y2248598D01*
X442573Y2249344D01*
X443073Y2249811D01*
X444073Y2249998D01*
X445073Y2249811D01*
X445698Y2249251D01*
X446073Y2248598D01*
Y2246264D01*
G01Y2248598D02*
X449698Y2249998D01*
G01Y2257498D02*
Y2253764D01*
X442198D01*
Y2257498D01*
G01X445823Y2256004D02*
Y2253764D01*
G01X442823Y2265184D02*
X442448Y2264624D01*
X442198Y2263971D01*
Y2263224D01*
X442573Y2262384D01*
X443198Y2261731D01*
X443948Y2261264D01*
X445198Y2260891D01*
X446323Y2260798D01*
X447448Y2260984D01*
X448198Y2261264D01*
X448948Y2261824D01*
X449448Y2262478D01*
X449698Y2263131D01*
Y2263784D01*
X449448Y2264438D01*
X449073Y2264998D01*
X448573Y2265464D01*
G01X449698Y2270631D02*
X449573Y2269884D01*
X449073Y2269231D01*
X448323Y2268671D01*
X447448Y2268298D01*
X446448Y2268111D01*
X445448D01*
X444448Y2268298D01*
X443573Y2268671D01*
X442823Y2269231D01*
X442323Y2269884D01*
X442198Y2270631D01*
X442323Y2271378D01*
X442823Y2272031D01*
X443573Y2272591D01*
X444448Y2272964D01*
X445448Y2273151D01*
X446448D01*
X447448Y2272964D01*
X448323Y2272591D01*
X449073Y2272031D01*
X449573Y2271378D01*
X449698Y2270631D01*
G01Y2275704D02*
X442198D01*
X448448Y2278131D01*
X442198Y2280558D01*
X449698D01*
G01Y2283204D02*
X442198D01*
X448448Y2285631D01*
X442198Y2288058D01*
X449698D01*
G01Y2294998D02*
Y2291264D01*
X442198D01*
Y2294998D01*
G01X445823Y2293504D02*
Y2291264D01*
G01X449698Y2298484D02*
X442198D01*
X449698Y2302778D01*
X442198D01*
G01X449698Y2306078D02*
X442198D01*
Y2307944D01*
X442573Y2308691D01*
X443073Y2309251D01*
X443823Y2309718D01*
X444698Y2310091D01*
X445948Y2310184D01*
X447198Y2310091D01*
X448073Y2309718D01*
X448823Y2309251D01*
X449323Y2308691D01*
X449698Y2307944D01*
Y2306078D01*
G01Y2317498D02*
Y2313764D01*
X442198D01*
Y2317498D01*
G01X445823Y2316004D02*
Y2313764D01*
G01X449698Y2321078D02*
X442198D01*
Y2322944D01*
X442573Y2323691D01*
X443073Y2324251D01*
X443823Y2324718D01*
X444698Y2325091D01*
X445948Y2325184D01*
X447198Y2325091D01*
X448073Y2324718D01*
X448823Y2324251D01*
X449323Y2323691D01*
X449698Y2322944D01*
Y2321078D01*
G01Y2336078D02*
X442198D01*
Y2337944D01*
X442573Y2338691D01*
X443073Y2339251D01*
X443823Y2339718D01*
X444698Y2340091D01*
X445948Y2340184D01*
X447198Y2340091D01*
X448073Y2339718D01*
X448823Y2339251D01*
X449323Y2338691D01*
X449698Y2337944D01*
Y2336078D01*
G01Y2343764D02*
X442198D01*
Y2346098D01*
X442573Y2346844D01*
X443073Y2347311D01*
X444073Y2347498D01*
X445073Y2347311D01*
X445698Y2346751D01*
X446073Y2346098D01*
Y2343764D01*
G01Y2346098D02*
X449698Y2347498D01*
G01X442198Y2352011D02*
Y2354251D01*
G01Y2353131D02*
X449698D01*
G01Y2352011D02*
Y2354251D01*
G01X442198Y2358764D02*
X449698D01*
Y2362498D01*
G01X442198Y2366264D02*
X449698D01*
Y2369998D01*
G01X448698Y2381171D02*
X449323Y2381918D01*
X449698Y2382758D01*
Y2383504D01*
X449323Y2384251D01*
X448698Y2384811D01*
X447823Y2385091D01*
X446948Y2384904D01*
X446198Y2384438D01*
X445698Y2383598D01*
X445448Y2382478D01*
X444948Y2381824D01*
X444073Y2381544D01*
X443198Y2381731D01*
X442573Y2382198D01*
X442198Y2382851D01*
Y2383504D01*
X442448Y2384158D01*
X443073Y2384718D01*
G01X442198Y2389511D02*
Y2391751D01*
G01Y2390631D02*
X449698D01*
G01Y2389511D02*
Y2391751D01*
G01X442198Y2396358D02*
Y2399904D01*
X449698Y2396358D01*
Y2399904D01*
G01Y2407498D02*
Y2403764D01*
X442198D01*
Y2407498D01*
G01X445823Y2406004D02*
Y2403764D01*
G01X449698Y2418858D02*
X442198D01*
Y2422404D01*
G01X445823Y2421098D02*
Y2418858D01*
G01X449698Y2428131D02*
X449573Y2427384D01*
X449073Y2426731D01*
X448323Y2426171D01*
X447448Y2425798D01*
X446448Y2425611D01*
X445448D01*
X444448Y2425798D01*
X443573Y2426171D01*
X442823Y2426731D01*
X442323Y2427384D01*
X442198Y2428131D01*
X442323Y2428878D01*
X442823Y2429531D01*
X443573Y2430091D01*
X444448Y2430464D01*
X445448Y2430651D01*
X446448D01*
X447448Y2430464D01*
X448323Y2430091D01*
X449073Y2429531D01*
X449573Y2428878D01*
X449698Y2428131D01*
G01Y2433764D02*
X442198D01*
Y2436098D01*
X442573Y2436844D01*
X443073Y2437311D01*
X444073Y2437498D01*
X445073Y2437311D01*
X445698Y2436751D01*
X446073Y2436098D01*
Y2433764D01*
G01Y2436098D02*
X449698Y2437498D01*
G01X442198Y2450631D02*
X442448Y2449884D01*
X443073Y2449324D01*
X443823Y2448951D01*
X444823Y2448671D01*
X445948Y2448578D01*
X447073Y2448671D01*
X448073Y2448951D01*
X448823Y2449324D01*
X449448Y2449884D01*
X449698Y2450631D01*
X449448Y2451378D01*
X448823Y2451938D01*
X448073Y2452311D01*
X447073Y2452591D01*
X445948Y2452684D01*
X444823Y2452591D01*
X443823Y2452311D01*
X443073Y2451938D01*
X442448Y2451378D01*
X442198Y2450631D01*
G01X449948Y2458131D02*
X449823Y2457944D01*
X449573D01*
X449448Y2458131D01*
X449573Y2458318D01*
X449823D01*
X449948Y2458131D01*
G01X448198Y2463578D02*
X449073Y2464138D01*
X449573Y2464884D01*
X449698Y2465724D01*
X449573Y2466471D01*
X448948Y2467218D01*
X448198Y2467684D01*
X447448Y2467778D01*
X446573Y2467591D01*
X445948Y2466938D01*
X445698Y2466284D01*
Y2465444D01*
G01Y2466284D02*
X445323Y2466844D01*
X444698Y2467311D01*
X443948Y2467498D01*
X443198Y2467311D01*
X442573Y2466844D01*
X442198Y2466004D01*
X442323Y2465164D01*
X442823Y2464324D01*
G01X446573Y2471358D02*
X445698Y2472011D01*
X445198Y2472571D01*
X444948Y2473318D01*
X445198Y2473971D01*
X445698Y2474438D01*
X446448Y2474811D01*
X447323Y2474904D01*
X448073Y2474811D01*
X448823Y2474438D01*
X449448Y2473878D01*
X449698Y2473224D01*
X449448Y2472478D01*
X448698Y2471824D01*
X447573Y2471451D01*
X446323Y2471358D01*
X444698Y2471544D01*
X443823Y2471824D01*
X442948Y2472291D01*
X442323Y2472944D01*
X442198Y2473598D01*
X442448Y2474251D01*
X443073Y2474718D01*
G01X449698Y2478204D02*
X442198D01*
X448448Y2480631D01*
X442198Y2483058D01*
X449698D01*
G01Y2485704D02*
X442198D01*
X448448Y2488131D01*
X442198Y2490558D01*
X449698D01*
G01Y2501358D02*
X442198D01*
Y2504904D01*
G01X445823Y2503598D02*
Y2501358D01*
G01X442198Y2509511D02*
Y2511751D01*
G01Y2510631D02*
X449698D01*
G01Y2509511D02*
Y2511751D01*
G01Y2515984D02*
X442198D01*
X449698Y2520278D01*
X442198D01*
G01Y2524511D02*
Y2526751D01*
G01Y2525631D02*
X449698D01*
G01Y2524511D02*
Y2526751D01*
G01X448698Y2531171D02*
X449323Y2531918D01*
X449698Y2532758D01*
Y2533504D01*
X449323Y2534251D01*
X448698Y2534811D01*
X447823Y2535091D01*
X446948Y2534904D01*
X446198Y2534438D01*
X445698Y2533598D01*
X445448Y2532478D01*
X444948Y2531824D01*
X444073Y2531544D01*
X443198Y2531731D01*
X442573Y2532198D01*
X442198Y2532851D01*
Y2533504D01*
X442448Y2534158D01*
X443073Y2534718D01*
G01X449698Y2538671D02*
X442198D01*
G01Y2542591D02*
X449698D01*
G01X445948D02*
Y2538671D01*
G01X449698Y2549998D02*
Y2546264D01*
X442198D01*
Y2549998D01*
G01X445823Y2548504D02*
Y2546264D01*
G01X449698Y2553578D02*
X442198D01*
Y2555444D01*
X442573Y2556191D01*
X443073Y2556751D01*
X443823Y2557218D01*
X444698Y2557591D01*
X445948Y2557684D01*
X447198Y2557591D01*
X448073Y2557218D01*
X448823Y2556751D01*
X449323Y2556191D01*
X449698Y2555444D01*
Y2553578D01*
G01Y2568764D02*
X442198D01*
Y2571004D01*
X442573Y2571751D01*
X443448Y2572311D01*
X444448Y2572498D01*
X445448Y2572311D01*
X446198Y2571844D01*
X446573Y2571004D01*
Y2568764D01*
G01X442198Y2578131D02*
X449698D01*
G01X442198Y2575984D02*
Y2580278D01*
G01X449698Y2583671D02*
X442198D01*
G01Y2587591D02*
X449698D01*
G01X445948D02*
Y2583671D01*
G01X442198Y2599511D02*
Y2601751D01*
G01Y2600631D02*
X449698D01*
G01Y2599511D02*
Y2601751D01*
G01X448698Y2606171D02*
X449323Y2606918D01*
X449698Y2607758D01*
Y2608504D01*
X449323Y2609251D01*
X448698Y2609811D01*
X447823Y2610091D01*
X446948Y2609904D01*
X446198Y2609438D01*
X445698Y2608598D01*
X445448Y2607478D01*
X444948Y2606824D01*
X444073Y2606544D01*
X443198Y2606731D01*
X442573Y2607198D01*
X442198Y2607851D01*
Y2608504D01*
X442448Y2609158D01*
X443073Y2609718D01*
G01X442198Y2623131D02*
X442448Y2622384D01*
X443073Y2621824D01*
X443823Y2621451D01*
X444823Y2621171D01*
X445948Y2621078D01*
X447073Y2621171D01*
X448073Y2621451D01*
X448823Y2621824D01*
X449448Y2622384D01*
X449698Y2623131D01*
X449448Y2623878D01*
X448823Y2624438D01*
X448073Y2624811D01*
X447073Y2625091D01*
X445948Y2625184D01*
X444823Y2625091D01*
X443823Y2624811D01*
X443073Y2624438D01*
X442448Y2623878D01*
X442198Y2623131D01*
G01X449948Y2630631D02*
X449823Y2630444D01*
X449573D01*
X449448Y2630631D01*
X449573Y2630818D01*
X449823D01*
X449948Y2630631D01*
G01X449698Y2639251D02*
X442198D01*
X447573Y2635798D01*
Y2640464D01*
G01X448573Y2643578D02*
X449198Y2644138D01*
X449573Y2644791D01*
X449698Y2645631D01*
X449448Y2646471D01*
X448948Y2647124D01*
X448073Y2647591D01*
X447073Y2647684D01*
X446073Y2647498D01*
X445448Y2647031D01*
X444948Y2646378D01*
X444823Y2645724D01*
X444948Y2645071D01*
X445448Y2644231D01*
X442198Y2644511D01*
Y2647031D01*
G01X449698Y2650704D02*
X442198D01*
X448448Y2653131D01*
X442198Y2655558D01*
X449698D01*
G01Y2658204D02*
X442198D01*
X448448Y2660631D01*
X442198Y2663058D01*
X449698D01*
G01Y2673204D02*
X442198D01*
X448448Y2675631D01*
X442198Y2678058D01*
X449698D01*
G01Y2684998D02*
Y2681264D01*
X442198D01*
Y2684998D01*
G01X445823Y2683504D02*
Y2681264D01*
G01X442198Y2690631D02*
X449698D01*
G01X442198Y2688484D02*
Y2692778D01*
G01X449698Y2696264D02*
X442198D01*
Y2698598D01*
X442573Y2699344D01*
X443073Y2699811D01*
X444073Y2699998D01*
X445073Y2699811D01*
X445698Y2699251D01*
X446073Y2698598D01*
Y2696264D01*
G01Y2698598D02*
X449698Y2699998D01*
G01X442198Y2704511D02*
Y2706751D01*
G01Y2705631D02*
X449698D01*
G01Y2704511D02*
Y2706751D01*
G01X442823Y2715184D02*
X442448Y2714624D01*
X442198Y2713971D01*
Y2713224D01*
X442573Y2712384D01*
X443198Y2711731D01*
X443948Y2711264D01*
X445198Y2710891D01*
X446323Y2710798D01*
X447448Y2710984D01*
X448198Y2711264D01*
X448948Y2711824D01*
X449448Y2712478D01*
X449698Y2713131D01*
Y2713784D01*
X449448Y2714438D01*
X449073Y2714998D01*
X448573Y2715464D01*
G01X449698Y2726078D02*
X442198D01*
Y2727944D01*
X442573Y2728691D01*
X443073Y2729251D01*
X443823Y2729718D01*
X444698Y2730091D01*
X445948Y2730184D01*
X447198Y2730091D01*
X448073Y2729718D01*
X448823Y2729251D01*
X449323Y2728691D01*
X449698Y2727944D01*
Y2726078D01*
G01Y2733764D02*
X442198D01*
Y2736098D01*
X442573Y2736844D01*
X443073Y2737311D01*
X444073Y2737498D01*
X445073Y2737311D01*
X445698Y2736751D01*
X446073Y2736098D01*
Y2733764D01*
G01Y2736098D02*
X449698Y2737498D01*
G01X442198Y2742011D02*
Y2744251D01*
G01Y2743131D02*
X449698D01*
G01Y2742011D02*
Y2744251D01*
G01X442198Y2748764D02*
X449698D01*
Y2752498D01*
G01X442198Y2756264D02*
X449698D01*
Y2759998D01*
G01X452198Y2765164D02*
X450948Y2764231D01*
X449698Y2763764D01*
X444698D01*
X443448Y2764231D01*
X442198Y2765164D01*
G01Y2773131D02*
X442448Y2772384D01*
X443073Y2771824D01*
X443823Y2771451D01*
X444823Y2771171D01*
X445948Y2771078D01*
X447073Y2771171D01*
X448073Y2771451D01*
X448823Y2771824D01*
X449448Y2772384D01*
X449698Y2773131D01*
X449448Y2773878D01*
X448823Y2774438D01*
X448073Y2774811D01*
X447073Y2775091D01*
X445948Y2775184D01*
X444823Y2775091D01*
X443823Y2774811D01*
X443073Y2774438D01*
X442448Y2773878D01*
X442198Y2773131D01*
G01X449948Y2780631D02*
X449823Y2780444D01*
X449573D01*
X449448Y2780631D01*
X449573Y2780818D01*
X449823D01*
X449948Y2780631D01*
G01X442198Y2788131D02*
X442448Y2787384D01*
X443073Y2786824D01*
X443823Y2786451D01*
X444823Y2786171D01*
X445948Y2786078D01*
X447073Y2786171D01*
X448073Y2786451D01*
X448823Y2786824D01*
X449448Y2787384D01*
X449698Y2788131D01*
X449448Y2788878D01*
X448823Y2789438D01*
X448073Y2789811D01*
X447073Y2790091D01*
X445948Y2790184D01*
X444823Y2790091D01*
X443823Y2789811D01*
X443073Y2789438D01*
X442448Y2788878D01*
X442198Y2788131D01*
G01X449698Y2795631D02*
X442198D01*
X443698Y2794511D01*
G01X449698D02*
Y2796751D01*
G01Y2802944D02*
X448073Y2803131D01*
X446698Y2803411D01*
X445448Y2803784D01*
X444073Y2804251D01*
X442198Y2804998D01*
Y2801264D01*
G01X449698Y2810444D02*
X448073Y2810631D01*
X446698Y2810911D01*
X445448Y2811284D01*
X444073Y2811751D01*
X442198Y2812498D01*
Y2808764D01*
G01X443823Y2817291D02*
X442198Y2817758D01*
G01Y2818971D02*
X443823Y2818504D01*
G01X452198Y2826098D02*
X450948Y2827031D01*
X449698Y2827498D01*
X444698D01*
X443448Y2827031D01*
X442198Y2826098D01*
G01X449948Y2833131D02*
X449823Y2832944D01*
X449573D01*
X449448Y2833131D01*
X449573Y2833318D01*
X449823D01*
X449948Y2833131D01*
G01X459650Y-534979D02*
Y-526979D01*
X458450Y-528579D01*
G01Y-534979D02*
X460850D01*
G01X467450D02*
X467650Y-533246D01*
X467950Y-531779D01*
X468350Y-530446D01*
X468850Y-528979D01*
X469650Y-526979D01*
X465650D01*
G01X475650Y-535246D02*
X475450Y-535112D01*
Y-534846D01*
X475650Y-534712D01*
X475850Y-534846D01*
Y-535112D01*
X475650Y-535246D01*
G01X481750Y-528312D02*
X482350Y-527512D01*
X483050Y-527112D01*
X483850Y-526979D01*
X484850Y-527246D01*
X485550Y-527912D01*
X485750Y-528712D01*
X485650Y-529513D01*
X485250Y-530179D01*
X483250Y-531512D01*
X482350Y-532446D01*
X481750Y-533779D01*
X481550Y-534979D01*
X485750D01*
G01X460678Y2049999D02*
X461303Y2050746D01*
X461678Y2051586D01*
Y2052332D01*
X461303Y2053079D01*
X460678Y2053639D01*
X459803Y2053919D01*
X458928Y2053732D01*
X458178Y2053266D01*
X457678Y2052426D01*
X457428Y2051306D01*
X456928Y2050652D01*
X456053Y2050372D01*
X455178Y2050559D01*
X454553Y2051026D01*
X454178Y2051679D01*
Y2052332D01*
X454428Y2052986D01*
X455053Y2053546D01*
G01X454178Y2058339D02*
Y2060579D01*
G01Y2059459D02*
X461678D01*
G01Y2058339D02*
Y2060579D01*
G01X454178Y2065092D02*
X461678D01*
Y2068826D01*
G01X454178Y2072126D02*
X461678Y2074459D01*
X454178Y2076792D01*
G01X461678Y2083826D02*
Y2080092D01*
X454178D01*
Y2083826D01*
G01X457803Y2082332D02*
Y2080092D01*
G01X461678Y2087592D02*
X454178D01*
Y2089926D01*
X454553Y2090672D01*
X455053Y2091139D01*
X456053Y2091326D01*
X457053Y2091139D01*
X457678Y2090579D01*
X458053Y2089926D01*
Y2087592D01*
G01Y2089926D02*
X461678Y2091326D01*
G01X464178Y2096492D02*
X462928Y2095559D01*
X461678Y2095092D01*
X456678D01*
X455428Y2095559D01*
X454178Y2096492D01*
G01Y2103339D02*
Y2105579D01*
G01Y2104459D02*
X461678D01*
G01Y2103339D02*
Y2105579D01*
G01Y2109532D02*
X454178D01*
X460428Y2111959D01*
X454178Y2114386D01*
X461678D01*
G01Y2117032D02*
X454178D01*
X460428Y2119459D01*
X454178Y2121886D01*
X461678D01*
G01Y2128826D02*
Y2125092D01*
X454178D01*
Y2128826D01*
G01X457803Y2127332D02*
Y2125092D01*
G01X461678Y2132592D02*
X454178D01*
Y2134926D01*
X454553Y2135672D01*
X455053Y2136139D01*
X456053Y2136326D01*
X457053Y2136139D01*
X457678Y2135579D01*
X458053Y2134926D01*
Y2132592D01*
G01Y2134926D02*
X461678Y2136326D01*
G01X460678Y2139999D02*
X461303Y2140746D01*
X461678Y2141586D01*
Y2142332D01*
X461303Y2143079D01*
X460678Y2143639D01*
X459803Y2143919D01*
X458928Y2143732D01*
X458178Y2143266D01*
X457678Y2142426D01*
X457428Y2141306D01*
X456928Y2140652D01*
X456053Y2140372D01*
X455178Y2140559D01*
X454553Y2141026D01*
X454178Y2141679D01*
Y2142332D01*
X454428Y2142986D01*
X455053Y2143546D01*
G01X454178Y2148339D02*
Y2150579D01*
G01Y2149459D02*
X461678D01*
G01Y2148339D02*
Y2150579D01*
G01Y2156959D02*
X461553Y2156212D01*
X461053Y2155559D01*
X460303Y2154999D01*
X459428Y2154626D01*
X458428Y2154439D01*
X457428D01*
X456428Y2154626D01*
X455553Y2154999D01*
X454803Y2155559D01*
X454303Y2156212D01*
X454178Y2156959D01*
X454303Y2157706D01*
X454803Y2158359D01*
X455553Y2158919D01*
X456428Y2159292D01*
X457428Y2159479D01*
X458428D01*
X459428Y2159292D01*
X460303Y2158919D01*
X461053Y2158359D01*
X461553Y2157706D01*
X461678Y2156959D01*
G01Y2162312D02*
X454178D01*
X461678Y2166606D01*
X454178D01*
G01X464178Y2172426D02*
X462928Y2173359D01*
X461678Y2173826D01*
X456678D01*
X455428Y2173359D01*
X454178Y2172426D01*
G01X461928Y2179459D02*
X461803Y2179272D01*
X461553D01*
X461428Y2179459D01*
X461553Y2179646D01*
X461803D01*
X461928Y2179459D01*
G01X458553D02*
X458428Y2179272D01*
X458178D01*
X458053Y2179459D01*
X458178Y2179646D01*
X458428D01*
X458553Y2179459D01*
G01X461678Y2185092D02*
X454178D01*
Y2187426D01*
X454553Y2188172D01*
X455053Y2188639D01*
X456053Y2188826D01*
X457053Y2188639D01*
X457678Y2188079D01*
X458053Y2187426D01*
Y2185092D01*
G01Y2187426D02*
X461678Y2188826D01*
G01Y2196326D02*
Y2192592D01*
X454178D01*
Y2196326D01*
G01X457803Y2194832D02*
Y2192592D01*
G01X454803Y2204012D02*
X454428Y2203452D01*
X454178Y2202799D01*
Y2202052D01*
X454553Y2201212D01*
X455178Y2200559D01*
X455928Y2200092D01*
X457178Y2199719D01*
X458303Y2199626D01*
X459428Y2199812D01*
X460178Y2200092D01*
X460928Y2200652D01*
X461428Y2201306D01*
X461678Y2201959D01*
Y2202612D01*
X461428Y2203266D01*
X461053Y2203826D01*
X460553Y2204292D01*
G01X461678Y2209459D02*
X461553Y2208712D01*
X461053Y2208059D01*
X460303Y2207499D01*
X459428Y2207126D01*
X458428Y2206939D01*
X457428D01*
X456428Y2207126D01*
X455553Y2207499D01*
X454803Y2208059D01*
X454303Y2208712D01*
X454178Y2209459D01*
X454303Y2210206D01*
X454803Y2210859D01*
X455553Y2211419D01*
X456428Y2211792D01*
X457428Y2211979D01*
X458428D01*
X459428Y2211792D01*
X460303Y2211419D01*
X461053Y2210859D01*
X461553Y2210206D01*
X461678Y2209459D01*
G01Y2214532D02*
X454178D01*
X460428Y2216959D01*
X454178Y2219386D01*
X461678D01*
G01Y2222032D02*
X454178D01*
X460428Y2224459D01*
X454178Y2226886D01*
X461678D01*
G01Y2233826D02*
Y2230092D01*
X454178D01*
Y2233826D01*
G01X457803Y2232332D02*
Y2230092D01*
G01X461678Y2237312D02*
X454178D01*
X461678Y2241606D01*
X454178D01*
G01X461678Y2244906D02*
X454178D01*
Y2246772D01*
X454553Y2247519D01*
X455053Y2248079D01*
X455803Y2248546D01*
X456678Y2248919D01*
X457928Y2249012D01*
X459178Y2248919D01*
X460053Y2248546D01*
X460803Y2248079D01*
X461303Y2247519D01*
X461678Y2246772D01*
Y2244906D01*
G01Y2256326D02*
Y2252592D01*
X454178D01*
Y2256326D01*
G01X457803Y2254832D02*
Y2252592D01*
G01X461678Y2259906D02*
X454178D01*
Y2261772D01*
X454553Y2262519D01*
X455053Y2263079D01*
X455803Y2263546D01*
X456678Y2263919D01*
X457928Y2264012D01*
X459178Y2263919D01*
X460053Y2263546D01*
X460803Y2263079D01*
X461303Y2262519D01*
X461678Y2261772D01*
Y2259906D01*
G01Y2274906D02*
X454178D01*
Y2276772D01*
X454553Y2277519D01*
X455053Y2278079D01*
X455803Y2278546D01*
X456678Y2278919D01*
X457928Y2279012D01*
X459178Y2278919D01*
X460053Y2278546D01*
X460803Y2278079D01*
X461303Y2277519D01*
X461678Y2276772D01*
Y2274906D01*
G01Y2282592D02*
X454178D01*
Y2284926D01*
X454553Y2285672D01*
X455053Y2286139D01*
X456053Y2286326D01*
X457053Y2286139D01*
X457678Y2285579D01*
X458053Y2284926D01*
Y2282592D01*
G01Y2284926D02*
X461678Y2286326D01*
G01X454178Y2290839D02*
Y2293079D01*
G01Y2291959D02*
X461678D01*
G01Y2290839D02*
Y2293079D01*
G01X454178Y2297592D02*
X461678D01*
Y2301326D01*
G01X454178Y2305092D02*
X461678D01*
Y2308826D01*
G01X460678Y2319999D02*
X461303Y2320746D01*
X461678Y2321586D01*
Y2322332D01*
X461303Y2323079D01*
X460678Y2323639D01*
X459803Y2323919D01*
X458928Y2323732D01*
X458178Y2323266D01*
X457678Y2322426D01*
X457428Y2321306D01*
X456928Y2320652D01*
X456053Y2320372D01*
X455178Y2320559D01*
X454553Y2321026D01*
X454178Y2321679D01*
Y2322332D01*
X454428Y2322986D01*
X455053Y2323546D01*
G01X454178Y2328339D02*
Y2330579D01*
G01Y2329459D02*
X461678D01*
G01Y2328339D02*
Y2330579D01*
G01X454178Y2335186D02*
Y2338732D01*
X461678Y2335186D01*
Y2338732D01*
G01Y2346326D02*
Y2342592D01*
X454178D01*
Y2346326D01*
G01X457803Y2344832D02*
Y2342592D01*
G01X461678Y2357686D02*
X454178D01*
Y2361232D01*
G01X457803Y2359926D02*
Y2357686D01*
G01X461678Y2366959D02*
X461553Y2366212D01*
X461053Y2365559D01*
X460303Y2364999D01*
X459428Y2364626D01*
X458428Y2364439D01*
X457428D01*
X456428Y2364626D01*
X455553Y2364999D01*
X454803Y2365559D01*
X454303Y2366212D01*
X454178Y2366959D01*
X454303Y2367706D01*
X454803Y2368359D01*
X455553Y2368919D01*
X456428Y2369292D01*
X457428Y2369479D01*
X458428D01*
X459428Y2369292D01*
X460303Y2368919D01*
X461053Y2368359D01*
X461553Y2367706D01*
X461678Y2366959D01*
G01Y2372592D02*
X454178D01*
Y2374926D01*
X454553Y2375672D01*
X455053Y2376139D01*
X456053Y2376326D01*
X457053Y2376139D01*
X457678Y2375579D01*
X458053Y2374926D01*
Y2372592D01*
G01Y2374926D02*
X461678Y2376326D01*
G01X454178Y2389459D02*
X454428Y2388712D01*
X455053Y2388152D01*
X455803Y2387779D01*
X456803Y2387499D01*
X457928Y2387406D01*
X459053Y2387499D01*
X460053Y2387779D01*
X460803Y2388152D01*
X461428Y2388712D01*
X461678Y2389459D01*
X461428Y2390206D01*
X460803Y2390766D01*
X460053Y2391139D01*
X459053Y2391419D01*
X457928Y2391512D01*
X456803Y2391419D01*
X455803Y2391139D01*
X455053Y2390766D01*
X454428Y2390206D01*
X454178Y2389459D01*
G01X461928Y2396959D02*
X461803Y2396772D01*
X461553D01*
X461428Y2396959D01*
X461553Y2397146D01*
X461803D01*
X461928Y2396959D01*
G01X460178Y2402406D02*
X461053Y2402966D01*
X461553Y2403712D01*
X461678Y2404552D01*
X461553Y2405299D01*
X460928Y2406046D01*
X460178Y2406512D01*
X459428Y2406606D01*
X458553Y2406419D01*
X457928Y2405766D01*
X457678Y2405112D01*
Y2404272D01*
G01Y2405112D02*
X457303Y2405672D01*
X456678Y2406139D01*
X455928Y2406326D01*
X455178Y2406139D01*
X454553Y2405672D01*
X454178Y2404832D01*
X454303Y2403992D01*
X454803Y2403152D01*
G01X458553Y2410186D02*
X457678Y2410839D01*
X457178Y2411399D01*
X456928Y2412146D01*
X457178Y2412799D01*
X457678Y2413266D01*
X458428Y2413639D01*
X459303Y2413732D01*
X460053Y2413639D01*
X460803Y2413266D01*
X461428Y2412706D01*
X461678Y2412052D01*
X461428Y2411306D01*
X460678Y2410652D01*
X459553Y2410279D01*
X458303Y2410186D01*
X456678Y2410372D01*
X455803Y2410652D01*
X454928Y2411119D01*
X454303Y2411772D01*
X454178Y2412426D01*
X454428Y2413079D01*
X455053Y2413546D01*
G01X461678Y2417032D02*
X454178D01*
X460428Y2419459D01*
X454178Y2421886D01*
X461678D01*
G01Y2424532D02*
X454178D01*
X460428Y2426959D01*
X454178Y2429386D01*
X461678D01*
G01Y2440186D02*
X454178D01*
Y2443732D01*
G01X457803Y2442426D02*
Y2440186D01*
G01X454178Y2448339D02*
Y2450579D01*
G01Y2449459D02*
X461678D01*
G01Y2448339D02*
Y2450579D01*
G01Y2454812D02*
X454178D01*
X461678Y2459106D01*
X454178D01*
G01Y2463339D02*
Y2465579D01*
G01Y2464459D02*
X461678D01*
G01Y2463339D02*
Y2465579D01*
G01X460678Y2469999D02*
X461303Y2470746D01*
X461678Y2471586D01*
Y2472332D01*
X461303Y2473079D01*
X460678Y2473639D01*
X459803Y2473919D01*
X458928Y2473732D01*
X458178Y2473266D01*
X457678Y2472426D01*
X457428Y2471306D01*
X456928Y2470652D01*
X456053Y2470372D01*
X455178Y2470559D01*
X454553Y2471026D01*
X454178Y2471679D01*
Y2472332D01*
X454428Y2472986D01*
X455053Y2473546D01*
G01X461678Y2477499D02*
X454178D01*
G01Y2481419D02*
X461678D01*
G01X457928D02*
Y2477499D01*
G01X461678Y2488826D02*
Y2485092D01*
X454178D01*
Y2488826D01*
G01X457803Y2487332D02*
Y2485092D01*
G01X461678Y2492406D02*
X454178D01*
Y2494272D01*
X454553Y2495019D01*
X455053Y2495579D01*
X455803Y2496046D01*
X456678Y2496419D01*
X457928Y2496512D01*
X459178Y2496419D01*
X460053Y2496046D01*
X460803Y2495579D01*
X461303Y2495019D01*
X461678Y2494272D01*
Y2492406D01*
G01Y2507592D02*
X454178D01*
Y2509832D01*
X454553Y2510579D01*
X455428Y2511139D01*
X456428Y2511326D01*
X457428Y2511139D01*
X458178Y2510672D01*
X458553Y2509832D01*
Y2507592D01*
G01X454178Y2516959D02*
X461678D01*
G01X454178Y2514812D02*
Y2519106D01*
G01X461678Y2522499D02*
X454178D01*
G01Y2526419D02*
X461678D01*
G01X457928D02*
Y2522499D01*
G01X454178Y2538339D02*
Y2540579D01*
G01Y2539459D02*
X461678D01*
G01Y2538339D02*
Y2540579D01*
G01X460678Y2544999D02*
X461303Y2545746D01*
X461678Y2546586D01*
Y2547332D01*
X461303Y2548079D01*
X460678Y2548639D01*
X459803Y2548919D01*
X458928Y2548732D01*
X458178Y2548266D01*
X457678Y2547426D01*
X457428Y2546306D01*
X456928Y2545652D01*
X456053Y2545372D01*
X455178Y2545559D01*
X454553Y2546026D01*
X454178Y2546679D01*
Y2547332D01*
X454428Y2547986D01*
X455053Y2548546D01*
G01X454178Y2561959D02*
X454428Y2561212D01*
X455053Y2560652D01*
X455803Y2560279D01*
X456803Y2559999D01*
X457928Y2559906D01*
X459053Y2559999D01*
X460053Y2560279D01*
X460803Y2560652D01*
X461428Y2561212D01*
X461678Y2561959D01*
X461428Y2562706D01*
X460803Y2563266D01*
X460053Y2563639D01*
X459053Y2563919D01*
X457928Y2564012D01*
X456803Y2563919D01*
X455803Y2563639D01*
X455053Y2563266D01*
X454428Y2562706D01*
X454178Y2561959D01*
G01X461928Y2569459D02*
X461803Y2569272D01*
X461553D01*
X461428Y2569459D01*
X461553Y2569646D01*
X461803D01*
X461928Y2569459D01*
G01X461678Y2578079D02*
X454178D01*
X459553Y2574626D01*
Y2579292D01*
G01X460553Y2582406D02*
X461178Y2582966D01*
X461553Y2583619D01*
X461678Y2584459D01*
X461428Y2585299D01*
X460928Y2585952D01*
X460053Y2586419D01*
X459053Y2586512D01*
X458053Y2586326D01*
X457428Y2585859D01*
X456928Y2585206D01*
X456803Y2584552D01*
X456928Y2583899D01*
X457428Y2583059D01*
X454178Y2583339D01*
Y2585859D01*
G01X461678Y2589532D02*
X454178D01*
X460428Y2591959D01*
X454178Y2594386D01*
X461678D01*
G01Y2597032D02*
X454178D01*
X460428Y2599459D01*
X454178Y2601886D01*
X461678D01*
G01Y2612032D02*
X454178D01*
X460428Y2614459D01*
X454178Y2616886D01*
X461678D01*
G01Y2623826D02*
Y2620092D01*
X454178D01*
Y2623826D01*
G01X457803Y2622332D02*
Y2620092D01*
G01X454178Y2629459D02*
X461678D01*
G01X454178Y2627312D02*
Y2631606D01*
G01X461678Y2635092D02*
X454178D01*
Y2637426D01*
X454553Y2638172D01*
X455053Y2638639D01*
X456053Y2638826D01*
X457053Y2638639D01*
X457678Y2638079D01*
X458053Y2637426D01*
Y2635092D01*
G01Y2637426D02*
X461678Y2638826D01*
G01X454178Y2643339D02*
Y2645579D01*
G01Y2644459D02*
X461678D01*
G01Y2643339D02*
Y2645579D01*
G01X454803Y2654012D02*
X454428Y2653452D01*
X454178Y2652799D01*
Y2652052D01*
X454553Y2651212D01*
X455178Y2650559D01*
X455928Y2650092D01*
X457178Y2649719D01*
X458303Y2649626D01*
X459428Y2649812D01*
X460178Y2650092D01*
X460928Y2650652D01*
X461428Y2651306D01*
X461678Y2651959D01*
Y2652612D01*
X461428Y2653266D01*
X461053Y2653826D01*
X460553Y2654292D01*
G01X461678Y2664906D02*
X454178D01*
Y2666772D01*
X454553Y2667519D01*
X455053Y2668079D01*
X455803Y2668546D01*
X456678Y2668919D01*
X457928Y2669012D01*
X459178Y2668919D01*
X460053Y2668546D01*
X460803Y2668079D01*
X461303Y2667519D01*
X461678Y2666772D01*
Y2664906D01*
G01Y2672592D02*
X454178D01*
Y2674926D01*
X454553Y2675672D01*
X455053Y2676139D01*
X456053Y2676326D01*
X457053Y2676139D01*
X457678Y2675579D01*
X458053Y2674926D01*
Y2672592D01*
G01Y2674926D02*
X461678Y2676326D01*
G01X454178Y2680839D02*
Y2683079D01*
G01Y2681959D02*
X461678D01*
G01Y2680839D02*
Y2683079D01*
G01X454178Y2687592D02*
X461678D01*
Y2691326D01*
G01X454178Y2695092D02*
X461678D01*
Y2698826D01*
G01X464178Y2703992D02*
X462928Y2703059D01*
X461678Y2702592D01*
X456678D01*
X455428Y2703059D01*
X454178Y2703992D01*
G01Y2711959D02*
X454428Y2711212D01*
X455053Y2710652D01*
X455803Y2710279D01*
X456803Y2709999D01*
X457928Y2709906D01*
X459053Y2709999D01*
X460053Y2710279D01*
X460803Y2710652D01*
X461428Y2711212D01*
X461678Y2711959D01*
X461428Y2712706D01*
X460803Y2713266D01*
X460053Y2713639D01*
X459053Y2713919D01*
X457928Y2714012D01*
X456803Y2713919D01*
X455803Y2713639D01*
X455053Y2713266D01*
X454428Y2712706D01*
X454178Y2711959D01*
G01X461928Y2719459D02*
X461803Y2719272D01*
X461553D01*
X461428Y2719459D01*
X461553Y2719646D01*
X461803D01*
X461928Y2719459D01*
G01X454178Y2726959D02*
X454428Y2726212D01*
X455053Y2725652D01*
X455803Y2725279D01*
X456803Y2724999D01*
X457928Y2724906D01*
X459053Y2724999D01*
X460053Y2725279D01*
X460803Y2725652D01*
X461428Y2726212D01*
X461678Y2726959D01*
X461428Y2727706D01*
X460803Y2728266D01*
X460053Y2728639D01*
X459053Y2728919D01*
X457928Y2729012D01*
X456803Y2728919D01*
X455803Y2728639D01*
X455053Y2728266D01*
X454428Y2727706D01*
X454178Y2726959D01*
G01X461678Y2734459D02*
X454178D01*
X455678Y2733339D01*
G01X461678D02*
Y2735579D01*
G01Y2741772D02*
X460053Y2741959D01*
X458678Y2742239D01*
X457428Y2742612D01*
X456053Y2743079D01*
X454178Y2743826D01*
Y2740092D01*
G01X461678Y2749272D02*
X460053Y2749459D01*
X458678Y2749739D01*
X457428Y2750112D01*
X456053Y2750579D01*
X454178Y2751326D01*
Y2747592D01*
G01X455803Y2756119D02*
X454178Y2756586D01*
G01Y2757799D02*
X455803Y2757332D01*
G01X464178Y2764926D02*
X462928Y2765859D01*
X461678Y2766326D01*
X456678D01*
X455428Y2765859D01*
X454178Y2764926D01*
G01X461928Y2771959D02*
X461803Y2771772D01*
X461553D01*
X461428Y2771959D01*
X461553Y2772146D01*
X461803D01*
X461928Y2771959D01*
G01X479650Y-508379D02*
X480150Y-509179D01*
X480750Y-509712D01*
X481450Y-509979D01*
X482250Y-509712D01*
X482850Y-509179D01*
X483450Y-508379D01*
X483650Y-507312D01*
Y-501979D01*
G01X505453Y1676732D02*
G03I-2500J0D01*
G01X497579Y1672795D02*
G03I-2500J0D01*
G01X505453Y1690905D02*
G03I-2500J0D01*
G01X497579Y1686968D02*
G03I-2500J0D01*
G01X505453Y1705078D02*
G03I-2500J0D01*
G01X497579Y1701141D02*
G03I-2500J0D01*
G01Y1715314D02*
G03I-2500J0D01*
G01X505453Y1719251D02*
G03I-2500J0D01*
G01X497579Y1729488D02*
G03I-2500J0D01*
G01X505453Y1733425D02*
G03I-2500J0D01*
G01X519031Y-381333D02*
X520073Y-380403D01*
X520698Y-379318D01*
X520906Y-377923D01*
X520489Y-376528D01*
X519656Y-375443D01*
X518198Y-374668D01*
X516531Y-374513D01*
X514864Y-374823D01*
X513823Y-375598D01*
X512989Y-376683D01*
X512781Y-377768D01*
X512989Y-378853D01*
X513823Y-380248D01*
X508406Y-379783D01*
Y-375598D01*
G01X510489Y-368468D02*
X509240Y-367538D01*
X508614Y-366453D01*
X508406Y-365213D01*
X508823Y-363663D01*
X509864Y-362578D01*
X511114Y-362268D01*
X512365Y-362423D01*
X513406Y-363043D01*
X515489Y-366143D01*
X516948Y-367538D01*
X519031Y-368468D01*
X520906Y-368778D01*
Y-362268D01*
G01X519031Y-356533D02*
X520073Y-355603D01*
X520698Y-354518D01*
X520906Y-353123D01*
X520489Y-351728D01*
X519656Y-350643D01*
X518198Y-349868D01*
X516531Y-349713D01*
X514864Y-350023D01*
X513823Y-350798D01*
X512989Y-351883D01*
X512781Y-352968D01*
X512989Y-354053D01*
X513823Y-355448D01*
X508406Y-354983D01*
Y-350798D01*
G01X510489Y-343668D02*
X509240Y-342738D01*
X508614Y-341653D01*
X508406Y-340413D01*
X508823Y-338863D01*
X509864Y-337778D01*
X511114Y-337468D01*
X512365Y-337623D01*
X513406Y-338243D01*
X515489Y-341343D01*
X516948Y-342738D01*
X519031Y-343668D01*
X520906Y-343978D01*
Y-337468D01*
G01X521323Y-328323D02*
X521114Y-328633D01*
X520698D01*
X520489Y-328323D01*
X520698Y-328013D01*
X521114D01*
X521323Y-328323D01*
G01X520906Y-316233D02*
X518198Y-315923D01*
X515906Y-315458D01*
X513823Y-314838D01*
X511531Y-314063D01*
X508406Y-312823D01*
Y-319023D01*
G01X515698Y-306468D02*
X514239Y-305383D01*
X513406Y-304453D01*
X512989Y-303213D01*
X513406Y-302128D01*
X514239Y-301353D01*
X515489Y-300733D01*
X516948Y-300578D01*
X518198Y-300733D01*
X519448Y-301353D01*
X520489Y-302283D01*
X520906Y-303368D01*
X520489Y-304608D01*
X519240Y-305693D01*
X517364Y-306313D01*
X515281Y-306468D01*
X512573Y-306158D01*
X511114Y-305693D01*
X509656Y-304918D01*
X508614Y-303833D01*
X508406Y-302748D01*
X508823Y-301663D01*
X509864Y-300888D01*
G01X520906Y-268923D02*
X508406D01*
X510906Y-270783D01*
G01X520906D02*
Y-267063D01*
G01X518406Y-259933D02*
X519865Y-259003D01*
X520698Y-257763D01*
X520906Y-256368D01*
X520698Y-255128D01*
X519656Y-253888D01*
X518406Y-253113D01*
X517156Y-252958D01*
X515698Y-253268D01*
X514656Y-254353D01*
X514239Y-255438D01*
Y-256833D01*
G01Y-255438D02*
X513614Y-254508D01*
X512573Y-253733D01*
X511323Y-253423D01*
X510073Y-253733D01*
X509031Y-254508D01*
X508406Y-255903D01*
X508614Y-257298D01*
X509448Y-258693D01*
G01X518406Y-247533D02*
X519865Y-246603D01*
X520698Y-245363D01*
X520906Y-243968D01*
X520698Y-242728D01*
X519656Y-241488D01*
X518406Y-240713D01*
X517156Y-240558D01*
X515698Y-240868D01*
X514656Y-241953D01*
X514239Y-243038D01*
Y-244433D01*
G01Y-243038D02*
X513614Y-242108D01*
X512573Y-241333D01*
X511323Y-241023D01*
X510073Y-241333D01*
X509031Y-242108D01*
X508406Y-243503D01*
X508614Y-244898D01*
X509448Y-246293D01*
G01X521323Y-231723D02*
X521114Y-232033D01*
X520698D01*
X520489Y-231723D01*
X520698Y-231413D01*
X521114D01*
X521323Y-231723D01*
G01X520906Y-217463D02*
X508406D01*
X517364Y-223198D01*
Y-215448D01*
G01X510489Y-209868D02*
X509240Y-208938D01*
X508614Y-207853D01*
X508406Y-206613D01*
X508823Y-205063D01*
X509864Y-203978D01*
X511114Y-203668D01*
X512365Y-203823D01*
X513406Y-204443D01*
X515489Y-207543D01*
X516948Y-208938D01*
X519031Y-209868D01*
X520906Y-210178D01*
Y-203668D01*
G01X521201Y1676732D02*
G03I-2500J0D01*
G01X513327Y1672795D02*
G03I-2500J0D01*
G01X521201Y1690905D02*
G03I-2500J0D01*
G01X513327Y1686968D02*
G03I-2500J0D01*
G01X521201Y1705078D02*
G03I-2500J0D01*
G01X513327Y1701141D02*
G03I-2500J0D01*
G01Y1715314D02*
G03I-2500J0D01*
G01X521201Y1719251D02*
G03I-2500J0D01*
G01X513327Y1729488D02*
G03I-2500J0D01*
G01X521201Y1733425D02*
G03I-2500J0D01*
G01X535615Y-381333D02*
X536657Y-380403D01*
X537282Y-379318D01*
X537490Y-377923D01*
X537073Y-376528D01*
X536240Y-375443D01*
X534782Y-374668D01*
X533115Y-374513D01*
X531448Y-374823D01*
X530407Y-375598D01*
X529573Y-376683D01*
X529365Y-377768D01*
X529573Y-378853D01*
X530407Y-380248D01*
X524990Y-379783D01*
Y-375598D01*
G01X534990Y-368933D02*
X536449Y-368003D01*
X537282Y-366763D01*
X537490Y-365368D01*
X537282Y-364128D01*
X536240Y-362888D01*
X534990Y-362113D01*
X533740Y-361958D01*
X532282Y-362268D01*
X531240Y-363353D01*
X530823Y-364438D01*
Y-365833D01*
G01Y-364438D02*
X530198Y-363508D01*
X529157Y-362733D01*
X527907Y-362423D01*
X526657Y-362733D01*
X525615Y-363508D01*
X524990Y-364903D01*
X525198Y-366298D01*
X526032Y-367693D01*
G01X537490Y-353123D02*
X524990D01*
X527490Y-354983D01*
G01X537490D02*
Y-351263D01*
G01X527073Y-343668D02*
X525824Y-342738D01*
X525198Y-341653D01*
X524990Y-340413D01*
X525407Y-338863D01*
X526448Y-337778D01*
X527698Y-337468D01*
X528949Y-337623D01*
X529990Y-338243D01*
X532073Y-341343D01*
X533532Y-342738D01*
X535615Y-343668D01*
X537490Y-343978D01*
Y-337468D01*
G01X537907Y-328323D02*
X537698Y-328633D01*
X537282D01*
X537073Y-328323D01*
X537282Y-328013D01*
X537698D01*
X537907Y-328323D01*
G01X537490Y-314063D02*
X524990D01*
X533948Y-319798D01*
Y-312048D01*
G01X524990Y-303523D02*
X525407Y-304763D01*
X526448Y-305693D01*
X527698Y-306313D01*
X529365Y-306778D01*
X531240Y-306933D01*
X533115Y-306778D01*
X534782Y-306313D01*
X536032Y-305693D01*
X537073Y-304763D01*
X537490Y-303523D01*
X537073Y-302283D01*
X536032Y-301353D01*
X534782Y-300733D01*
X533115Y-300268D01*
X531240Y-300113D01*
X529365Y-300268D01*
X527698Y-300733D01*
X526448Y-301353D01*
X525407Y-302283D01*
X524990Y-303523D01*
G01X537490Y-268923D02*
X524990D01*
X527490Y-270783D01*
G01X537490D02*
Y-267063D01*
G01X534990Y-259933D02*
X536449Y-259003D01*
X537282Y-257763D01*
X537490Y-256368D01*
X537282Y-255128D01*
X536240Y-253888D01*
X534990Y-253113D01*
X533740Y-252958D01*
X532282Y-253268D01*
X531240Y-254353D01*
X530823Y-255438D01*
Y-256833D01*
G01Y-255438D02*
X530198Y-254508D01*
X529157Y-253733D01*
X527907Y-253423D01*
X526657Y-253733D01*
X525615Y-254508D01*
X524990Y-255903D01*
X525198Y-257298D01*
X526032Y-258693D01*
G01X537490Y-242263D02*
X524990D01*
X533948Y-247998D01*
Y-240248D01*
G01X537907Y-231723D02*
X537698Y-232033D01*
X537282D01*
X537073Y-231723D01*
X537282Y-231413D01*
X537698D01*
X537907Y-231723D01*
G01X536032Y-221958D02*
X537073Y-220873D01*
X537490Y-219633D01*
X537073Y-218393D01*
X535824Y-217308D01*
X533948Y-216533D01*
X532073Y-216223D01*
X529782D01*
X527907Y-216533D01*
X526240Y-217308D01*
X525407Y-218238D01*
X524990Y-219323D01*
X525407Y-220563D01*
X526240Y-221493D01*
X527490Y-222113D01*
X529157Y-222423D01*
X530615Y-222113D01*
X532073Y-221338D01*
X532907Y-220408D01*
X533115Y-219323D01*
X532699Y-218083D01*
X531657Y-217153D01*
X529782Y-216223D01*
G01X534990Y-210333D02*
X536449Y-209403D01*
X537282Y-208163D01*
X537490Y-206768D01*
X537282Y-205528D01*
X536240Y-204288D01*
X534990Y-203513D01*
X533740Y-203358D01*
X532282Y-203668D01*
X531240Y-204753D01*
X530823Y-205838D01*
Y-207233D01*
G01Y-205838D02*
X530198Y-204908D01*
X529157Y-204133D01*
X527907Y-203823D01*
X526657Y-204133D01*
X525615Y-204908D01*
X524990Y-206303D01*
X525198Y-207698D01*
X526032Y-209093D01*
G01X530359Y1184948D02*
Y1192448D01*
X534653Y1184948D01*
Y1192448D01*
G01X538139Y1184948D02*
Y1192448D01*
X540379D01*
X541126Y1192073D01*
X541686Y1191198D01*
X541873Y1190198D01*
X541686Y1189198D01*
X541219Y1188448D01*
X540379Y1188073D01*
X538139D01*
G01X547506Y1192448D02*
Y1184948D01*
G01X545359Y1192448D02*
X549653D01*
G01X553046Y1184948D02*
Y1192448D01*
G01X556966D02*
Y1184948D01*
G01Y1188698D02*
X553046D01*
G01X536949Y1676732D02*
G03I-2500J0D01*
G01X529075Y1672795D02*
G03I-2500J0D01*
G01X536949Y1690905D02*
G03I-2500J0D01*
G01X529075Y1686968D02*
G03I-2500J0D01*
G01X536949Y1705078D02*
G03I-2500J0D01*
G01X529075Y1701141D02*
G03I-2500J0D01*
G01Y1715314D02*
G03I-2500J0D01*
G01X536949Y1719251D02*
G03I-2500J0D01*
G01X529075Y1729488D02*
G03I-2500J0D01*
G01X536949Y1733425D02*
G03I-2500J0D01*
G01X554016Y-381333D02*
X555058Y-380403D01*
X555683Y-379318D01*
X555891Y-377923D01*
X555474Y-376528D01*
X554641Y-375443D01*
X553183Y-374668D01*
X551516Y-374513D01*
X549849Y-374823D01*
X548808Y-375598D01*
X547974Y-376683D01*
X547766Y-377768D01*
X547974Y-378853D01*
X548808Y-380248D01*
X543391Y-379783D01*
Y-375598D01*
G01X553391Y-368933D02*
X554850Y-368003D01*
X555683Y-366763D01*
X555891Y-365368D01*
X555683Y-364128D01*
X554641Y-362888D01*
X553391Y-362113D01*
X552141Y-361958D01*
X550683Y-362268D01*
X549641Y-363353D01*
X549224Y-364438D01*
Y-365833D01*
G01Y-364438D02*
X548599Y-363508D01*
X547558Y-362733D01*
X546308Y-362423D01*
X545058Y-362733D01*
X544016Y-363508D01*
X543391Y-364903D01*
X543599Y-366298D01*
X544433Y-367693D01*
G01X555891Y-353433D02*
X553183Y-353123D01*
X550891Y-352658D01*
X548808Y-352038D01*
X546516Y-351263D01*
X543391Y-350023D01*
Y-356223D01*
G01X555891Y-338863D02*
X543391D01*
X552349Y-344598D01*
Y-336848D01*
G01X556308Y-328323D02*
X556099Y-328633D01*
X555683D01*
X555474Y-328323D01*
X555683Y-328013D01*
X556099D01*
X556308Y-328323D01*
G01X555891Y-316233D02*
X553183Y-315923D01*
X550891Y-315458D01*
X548808Y-314838D01*
X546516Y-314063D01*
X543391Y-312823D01*
Y-319023D01*
G01X555891Y-303833D02*
X553183Y-303523D01*
X550891Y-303058D01*
X548808Y-302438D01*
X546516Y-301663D01*
X543391Y-300423D01*
Y-306623D01*
G01X555891Y-268923D02*
X543391D01*
X545891Y-270783D01*
G01X555891D02*
Y-267063D01*
G01X553391Y-259933D02*
X554850Y-259003D01*
X555683Y-257763D01*
X555891Y-256368D01*
X555683Y-255128D01*
X554641Y-253888D01*
X553391Y-253113D01*
X552141Y-252958D01*
X550683Y-253268D01*
X549641Y-254353D01*
X549224Y-255438D01*
Y-256833D01*
G01Y-255438D02*
X548599Y-254508D01*
X547558Y-253733D01*
X546308Y-253423D01*
X545058Y-253733D01*
X544016Y-254508D01*
X543391Y-255903D01*
X543599Y-257298D01*
X544433Y-258693D01*
G01X550683Y-247068D02*
X549224Y-245983D01*
X548391Y-245053D01*
X547974Y-243813D01*
X548391Y-242728D01*
X549224Y-241953D01*
X550474Y-241333D01*
X551933Y-241178D01*
X553183Y-241333D01*
X554433Y-241953D01*
X555474Y-242883D01*
X555891Y-243968D01*
X555474Y-245208D01*
X554225Y-246293D01*
X552349Y-246913D01*
X550266Y-247068D01*
X547558Y-246758D01*
X546099Y-246293D01*
X544641Y-245518D01*
X543599Y-244433D01*
X543391Y-243348D01*
X543808Y-242263D01*
X544849Y-241488D01*
G01X556308Y-231723D02*
X556099Y-232033D01*
X555683D01*
X555474Y-231723D01*
X555683Y-231413D01*
X556099D01*
X556308Y-231723D01*
G01X554016Y-222733D02*
X555058Y-221803D01*
X555683Y-220718D01*
X555891Y-219323D01*
X555474Y-217928D01*
X554641Y-216843D01*
X553183Y-216068D01*
X551516Y-215913D01*
X549849Y-216223D01*
X548808Y-216998D01*
X547974Y-218083D01*
X547766Y-219168D01*
X547974Y-220253D01*
X548808Y-221648D01*
X543391Y-221183D01*
Y-216998D01*
G01X545474Y-209868D02*
X544225Y-208938D01*
X543599Y-207853D01*
X543391Y-206613D01*
X543808Y-205063D01*
X544849Y-203978D01*
X546099Y-203668D01*
X547350Y-203823D01*
X548391Y-204443D01*
X550474Y-207543D01*
X551933Y-208938D01*
X554016Y-209868D01*
X555891Y-210178D01*
Y-203668D01*
G01X535248Y826179D02*
Y833679D01*
X539542Y826179D01*
Y833679D01*
G01X543028Y826179D02*
Y833679D01*
X545268D01*
X546015Y833304D01*
X546575Y832429D01*
X546762Y831429D01*
X546575Y830429D01*
X546108Y829679D01*
X545268Y829304D01*
X543028D01*
G01X552395Y833679D02*
Y826179D01*
G01X550248Y833679D02*
X554542D01*
G01X557935Y826179D02*
Y833679D01*
G01X561855D02*
Y826179D01*
G01Y829929D02*
X557935D01*
G01X552697Y1676732D02*
G03I-2500J0D01*
G01X544823Y1672795D02*
G03I-2500J0D01*
G01X552697Y1690905D02*
G03I-2500J0D01*
G01X544823Y1686968D02*
G03I-2500J0D01*
G01X552697Y1705078D02*
G03I-2500J0D01*
G01X544823Y1701141D02*
G03I-2500J0D01*
G01Y1715314D02*
G03I-2500J0D01*
G01X552697Y1719251D02*
G03I-2500J0D01*
G01X544823Y1729488D02*
G03I-2500J0D01*
G01X552697Y1733425D02*
G03I-2500J0D01*
G01X564508Y1672795D02*
G03I-2500J0D01*
G01Y1686968D02*
G03I-2500J0D01*
G01Y1701141D02*
G03I-2500J0D01*
G01Y1715314D02*
G03I-2500J0D01*
G01Y1729488D02*
G03I-2500J0D01*
G01X578942Y-381330D02*
X579984Y-380400D01*
X580609Y-379315D01*
X580817Y-377920D01*
X580400Y-376525D01*
X579567Y-375440D01*
X578109Y-374665D01*
X576442Y-374510D01*
X574775Y-374820D01*
X573734Y-375595D01*
X572900Y-376680D01*
X572692Y-377765D01*
X572900Y-378850D01*
X573734Y-380245D01*
X568317Y-379780D01*
Y-375595D01*
G01X580817Y-365830D02*
X578109Y-365520D01*
X575817Y-365055D01*
X573734Y-364435D01*
X571442Y-363660D01*
X568317Y-362420D01*
Y-368620D01*
G01X580817Y-351260D02*
X568317D01*
X577275Y-356995D01*
Y-349245D01*
G01X578942Y-344130D02*
X579984Y-343200D01*
X580609Y-342115D01*
X580817Y-340720D01*
X580400Y-339325D01*
X579567Y-338240D01*
X578109Y-337465D01*
X576442Y-337310D01*
X574775Y-337620D01*
X573734Y-338395D01*
X572900Y-339480D01*
X572692Y-340565D01*
X572900Y-341650D01*
X573734Y-343045D01*
X568317Y-342580D01*
Y-338395D01*
G01X581234Y-328320D02*
X581025Y-328630D01*
X580609D01*
X580400Y-328320D01*
X580609Y-328010D01*
X581025D01*
X581234Y-328320D01*
G01X575609Y-318865D02*
X574150Y-317780D01*
X573317Y-316850D01*
X572900Y-315610D01*
X573317Y-314525D01*
X574150Y-313750D01*
X575400Y-313130D01*
X576859Y-312975D01*
X578109Y-313130D01*
X579359Y-313750D01*
X580400Y-314680D01*
X580817Y-315765D01*
X580400Y-317005D01*
X579151Y-318090D01*
X577275Y-318710D01*
X575192Y-318865D01*
X572484Y-318555D01*
X571025Y-318090D01*
X569567Y-317315D01*
X568525Y-316230D01*
X568317Y-315145D01*
X568734Y-314060D01*
X569775Y-313285D01*
G01X580817Y-303830D02*
X578109Y-303520D01*
X575817Y-303055D01*
X573734Y-302435D01*
X571442Y-301660D01*
X568317Y-300420D01*
Y-306620D01*
G01X580817Y-268920D02*
X568317D01*
X570817Y-270780D01*
G01X580817D02*
Y-267060D01*
G01Y-254660D02*
X568317D01*
X577275Y-260395D01*
Y-252645D01*
G01X578942Y-247530D02*
X579984Y-246600D01*
X580609Y-245515D01*
X580817Y-244120D01*
X580400Y-242725D01*
X579567Y-241640D01*
X578109Y-240865D01*
X576442Y-240710D01*
X574775Y-241020D01*
X573734Y-241795D01*
X572900Y-242880D01*
X572692Y-243965D01*
X572900Y-245050D01*
X573734Y-246445D01*
X568317Y-245980D01*
Y-241795D01*
G01X581234Y-231720D02*
X581025Y-232030D01*
X580609D01*
X580400Y-231720D01*
X580609Y-231410D01*
X581025D01*
X581234Y-231720D01*
G01X579359Y-221955D02*
X580400Y-220870D01*
X580817Y-219630D01*
X580400Y-218390D01*
X579151Y-217305D01*
X577275Y-216530D01*
X575400Y-216220D01*
X573109D01*
X571234Y-216530D01*
X569567Y-217305D01*
X568734Y-218235D01*
X568317Y-219320D01*
X568734Y-220560D01*
X569567Y-221490D01*
X570817Y-222110D01*
X572484Y-222420D01*
X573942Y-222110D01*
X575400Y-221335D01*
X576234Y-220405D01*
X576442Y-219320D01*
X576026Y-218080D01*
X574984Y-217150D01*
X573109Y-216220D01*
G01X580817Y-205060D02*
X568317D01*
X577275Y-210795D01*
Y-203045D01*
G01X577744Y1009307D02*
Y1016807D01*
X582038Y1009307D01*
Y1016807D01*
G01X585524Y1009307D02*
Y1016807D01*
X587764D01*
X588511Y1016432D01*
X589071Y1015557D01*
X589258Y1014557D01*
X589071Y1013557D01*
X588604Y1012807D01*
X587764Y1012432D01*
X585524D01*
G01X594891Y1016807D02*
Y1009307D01*
G01X592744Y1016807D02*
X597038D01*
G01X600431Y1009307D02*
Y1016807D01*
G01X604351D02*
Y1009307D01*
G01Y1013057D02*
X600431D01*
G01X580256Y1672795D02*
G03I-2500J0D01*
G01X572382Y1676732D02*
G03I-2500J0D01*
G01X580256Y1686968D02*
G03I-2500J0D01*
G01X572382Y1690905D02*
G03I-2500J0D01*
G01X580256Y1701141D02*
G03I-2500J0D01*
G01Y1715314D02*
G03I-2500J0D01*
G01X572382Y1705078D02*
G03I-2500J0D01*
G01X580256Y1729488D02*
G03I-2500J0D01*
G01X572382Y1719251D02*
G03I-2500J0D01*
G01Y1733425D02*
G03I-2500J0D01*
G01X588130Y1676732D02*
G03I-2500J0D01*
G01X596004Y1672795D02*
G03I-2500J0D01*
G01X588130Y1690905D02*
G03I-2500J0D01*
G01X596004Y1686968D02*
G03I-2500J0D01*
G01X588130Y1705078D02*
G03I-2500J0D01*
G01X596004Y1701141D02*
G03I-2500J0D01*
G01Y1715314D02*
G03I-2500J0D01*
G01X588130Y1719251D02*
G03I-2500J0D01*
G01X596004Y1729488D02*
G03I-2500J0D01*
G01X588130Y1733425D02*
G03I-2500J0D01*
G01X619626Y1676732D02*
G03I-2500J0D01*
G01X603878D02*
G03I-2500J0D01*
G01X611752Y1672795D02*
G03I-2500J0D01*
G01X619626Y1690905D02*
G03I-2500J0D01*
G01X603878D02*
G03I-2500J0D01*
G01X611752Y1686968D02*
G03I-2500J0D01*
G01X619626Y1705078D02*
G03I-2500J0D01*
G01X603878D02*
G03I-2500J0D01*
G01X611752Y1701141D02*
G03I-2500J0D01*
G01Y1715314D02*
G03I-2500J0D01*
G01X619626Y1719251D02*
G03I-2500J0D01*
G01X603878D02*
G03I-2500J0D01*
G01X611752Y1729488D02*
G03I-2500J0D01*
G01X619626Y1733425D02*
G03I-2500J0D01*
G01X603878D02*
G03I-2500J0D01*
G01X662065Y-369066D02*
X660606Y-367981D01*
X659773Y-367051D01*
X659356Y-365811D01*
X659773Y-364726D01*
X660606Y-363951D01*
X661856Y-363331D01*
X663315Y-363176D01*
X664565Y-363331D01*
X665815Y-363951D01*
X666856Y-364881D01*
X667273Y-365966D01*
X666856Y-367206D01*
X665607Y-368291D01*
X663731Y-368911D01*
X661648Y-369066D01*
X658940Y-368756D01*
X657481Y-368291D01*
X656023Y-367516D01*
X654981Y-366431D01*
X654773Y-365346D01*
X655190Y-364261D01*
X656231Y-363486D01*
G01X662065Y-356666D02*
X660606Y-355581D01*
X659773Y-354651D01*
X659356Y-353411D01*
X659773Y-352326D01*
X660606Y-351551D01*
X661856Y-350931D01*
X663315Y-350776D01*
X664565Y-350931D01*
X665815Y-351551D01*
X666856Y-352481D01*
X667273Y-353566D01*
X666856Y-354806D01*
X665607Y-355891D01*
X663731Y-356511D01*
X661648Y-356666D01*
X658940Y-356356D01*
X657481Y-355891D01*
X656023Y-355116D01*
X654981Y-354031D01*
X654773Y-352946D01*
X655190Y-351861D01*
X656231Y-351086D01*
G01X667273Y-341321D02*
X654773D01*
X657273Y-343181D01*
G01X667273D02*
Y-339461D01*
G01X654773Y-328921D02*
X655190Y-330161D01*
X656231Y-331091D01*
X657481Y-331711D01*
X659148Y-332176D01*
X661023Y-332331D01*
X662898Y-332176D01*
X664565Y-331711D01*
X665815Y-331091D01*
X666856Y-330161D01*
X667273Y-328921D01*
X666856Y-327681D01*
X665815Y-326751D01*
X664565Y-326131D01*
X662898Y-325666D01*
X661023Y-325511D01*
X659148Y-325666D01*
X657481Y-326131D01*
X656231Y-326751D01*
X655190Y-327681D01*
X654773Y-328921D01*
G01X667690Y-316521D02*
X667481Y-316831D01*
X667065D01*
X666856Y-316521D01*
X667065Y-316211D01*
X667481D01*
X667690Y-316521D01*
G01X656856Y-307066D02*
X655607Y-306136D01*
X654981Y-305051D01*
X654773Y-303811D01*
X655190Y-302261D01*
X656231Y-301176D01*
X657481Y-300866D01*
X658732Y-301021D01*
X659773Y-301641D01*
X661856Y-304741D01*
X663315Y-306136D01*
X665398Y-307066D01*
X667273Y-307376D01*
Y-300866D01*
G01X664773Y-295131D02*
X666232Y-294201D01*
X667065Y-292961D01*
X667273Y-291566D01*
X667065Y-290326D01*
X666023Y-289086D01*
X664773Y-288311D01*
X663523Y-288156D01*
X662065Y-288466D01*
X661023Y-289551D01*
X660606Y-290636D01*
Y-292031D01*
G01Y-290636D02*
X659981Y-289706D01*
X658940Y-288931D01*
X657690Y-288621D01*
X656440Y-288931D01*
X655398Y-289706D01*
X654773Y-291101D01*
X654981Y-292496D01*
X655815Y-293891D01*
G01X667273Y-257121D02*
X654773D01*
X657273Y-258981D01*
G01X667273D02*
Y-255261D01*
G01X662065Y-247666D02*
X660606Y-246581D01*
X659773Y-245651D01*
X659356Y-244411D01*
X659773Y-243326D01*
X660606Y-242551D01*
X661856Y-241931D01*
X663315Y-241776D01*
X664565Y-241931D01*
X665815Y-242551D01*
X666856Y-243481D01*
X667273Y-244566D01*
X666856Y-245806D01*
X665607Y-246891D01*
X663731Y-247511D01*
X661648Y-247666D01*
X658940Y-247356D01*
X657481Y-246891D01*
X656023Y-246116D01*
X654981Y-245031D01*
X654773Y-243946D01*
X655190Y-242861D01*
X656231Y-242086D01*
G01X667273Y-232631D02*
X664565Y-232321D01*
X662273Y-231856D01*
X660190Y-231236D01*
X657898Y-230461D01*
X654773Y-229221D01*
Y-235421D01*
G01X667690Y-219921D02*
X667481Y-220231D01*
X667065D01*
X666856Y-219921D01*
X667065Y-219611D01*
X667481D01*
X667690Y-219921D01*
G01X665815Y-210156D02*
X666856Y-209071D01*
X667273Y-207831D01*
X666856Y-206591D01*
X665607Y-205506D01*
X663731Y-204731D01*
X661856Y-204421D01*
X659565D01*
X657690Y-204731D01*
X656023Y-205506D01*
X655190Y-206436D01*
X654773Y-207521D01*
X655190Y-208761D01*
X656023Y-209691D01*
X657273Y-210311D01*
X658940Y-210621D01*
X660398Y-210311D01*
X661856Y-209536D01*
X662690Y-208606D01*
X662898Y-207521D01*
X662482Y-206281D01*
X661440Y-205351D01*
X659565Y-204421D01*
G01X687142Y-378690D02*
X684434Y-378380D01*
X682142Y-377915D01*
X680059Y-377295D01*
X677767Y-376520D01*
X674642Y-375280D01*
Y-381480D01*
G01Y-365980D02*
X675059Y-367220D01*
X676100Y-368150D01*
X677350Y-368770D01*
X679017Y-369235D01*
X680892Y-369390D01*
X682767Y-369235D01*
X684434Y-368770D01*
X685684Y-368150D01*
X686725Y-367220D01*
X687142Y-365980D01*
X686725Y-364740D01*
X685684Y-363810D01*
X684434Y-363190D01*
X682767Y-362725D01*
X680892Y-362570D01*
X679017Y-362725D01*
X677350Y-363190D01*
X676100Y-363810D01*
X675059Y-364740D01*
X674642Y-365980D01*
G01X687142Y-351720D02*
X674642D01*
X683600Y-357455D01*
Y-349705D01*
G01X674642Y-341180D02*
X675059Y-342420D01*
X676100Y-343350D01*
X677350Y-343970D01*
X679017Y-344435D01*
X680892Y-344590D01*
X682767Y-344435D01*
X684434Y-343970D01*
X685684Y-343350D01*
X686725Y-342420D01*
X687142Y-341180D01*
X686725Y-339940D01*
X685684Y-339010D01*
X684434Y-338390D01*
X682767Y-337925D01*
X680892Y-337770D01*
X679017Y-337925D01*
X677350Y-338390D01*
X676100Y-339010D01*
X675059Y-339940D01*
X674642Y-341180D01*
G01X687559Y-328780D02*
X687350Y-329090D01*
X686934D01*
X686725Y-328780D01*
X686934Y-328470D01*
X687350D01*
X687559Y-328780D01*
G01X685684Y-319015D02*
X686725Y-317930D01*
X687142Y-316690D01*
X686725Y-315450D01*
X685476Y-314365D01*
X683600Y-313590D01*
X681725Y-313280D01*
X679434D01*
X677559Y-313590D01*
X675892Y-314365D01*
X675059Y-315295D01*
X674642Y-316380D01*
X675059Y-317620D01*
X675892Y-318550D01*
X677142Y-319170D01*
X678809Y-319480D01*
X680267Y-319170D01*
X681725Y-318395D01*
X682559Y-317465D01*
X682767Y-316380D01*
X682351Y-315140D01*
X681309Y-314210D01*
X679434Y-313280D01*
G01X687142Y-303980D02*
X674642D01*
X677142Y-305840D01*
G01X687142D02*
Y-302120D01*
G01Y-269380D02*
X674642D01*
X677142Y-271240D01*
G01X687142D02*
Y-267520D01*
G01Y-257290D02*
X684434Y-256980D01*
X682142Y-256515D01*
X680059Y-255895D01*
X677767Y-255120D01*
X674642Y-253880D01*
Y-260080D01*
G01X687142Y-244580D02*
X686934Y-243495D01*
X686309Y-242255D01*
X685267Y-241480D01*
X683809Y-241170D01*
X682351Y-241480D01*
X681100Y-242410D01*
X680475Y-243805D01*
Y-245355D01*
X680059Y-246285D01*
X679017Y-247060D01*
X677559Y-247370D01*
X676100Y-246905D01*
X675059Y-245820D01*
X674642Y-244580D01*
X675059Y-243340D01*
X676100Y-242255D01*
X677559Y-241790D01*
X679017Y-242100D01*
X680059Y-242875D01*
X680475Y-243805D01*
Y-245355D01*
X681100Y-246750D01*
X682351Y-247680D01*
X683809Y-247990D01*
X685267Y-247680D01*
X686309Y-246905D01*
X686934Y-245665D01*
X687142Y-244580D01*
G01X687559Y-232180D02*
X687350Y-232490D01*
X686934D01*
X686725Y-232180D01*
X686934Y-231870D01*
X687350D01*
X687559Y-232180D01*
G01X687142Y-219780D02*
X686934Y-218695D01*
X686309Y-217455D01*
X685267Y-216680D01*
X683809Y-216370D01*
X682351Y-216680D01*
X681100Y-217610D01*
X680475Y-219005D01*
Y-220555D01*
X680059Y-221485D01*
X679017Y-222260D01*
X677559Y-222570D01*
X676100Y-222105D01*
X675059Y-221020D01*
X674642Y-219780D01*
X675059Y-218540D01*
X676100Y-217455D01*
X677559Y-216990D01*
X679017Y-217300D01*
X680059Y-218075D01*
X680475Y-219005D01*
Y-220555D01*
X681100Y-221950D01*
X682351Y-222880D01*
X683809Y-223190D01*
X685267Y-222880D01*
X686309Y-222105D01*
X686934Y-220865D01*
X687142Y-219780D01*
G01Y-205520D02*
X674642D01*
X683600Y-211255D01*
Y-203505D01*
G01X702692Y-378461D02*
X699984Y-378151D01*
X697692Y-377686D01*
X695609Y-377066D01*
X693317Y-376291D01*
X690192Y-375051D01*
Y-381251D01*
G01Y-365751D02*
X690609Y-366991D01*
X691650Y-367921D01*
X692900Y-368541D01*
X694567Y-369006D01*
X696442Y-369161D01*
X698317Y-369006D01*
X699984Y-368541D01*
X701234Y-367921D01*
X702275Y-366991D01*
X702692Y-365751D01*
X702275Y-364511D01*
X701234Y-363581D01*
X699984Y-362961D01*
X698317Y-362496D01*
X696442Y-362341D01*
X694567Y-362496D01*
X692900Y-362961D01*
X691650Y-363581D01*
X690609Y-364511D01*
X690192Y-365751D01*
G01X702692Y-351491D02*
X690192D01*
X699150Y-357226D01*
Y-349476D01*
G01X702692Y-340951D02*
X690192D01*
X692692Y-342811D01*
G01X702692D02*
Y-339091D01*
G01X703109Y-328551D02*
X702900Y-328861D01*
X702484D01*
X702275Y-328551D01*
X702484Y-328241D01*
X702900D01*
X703109Y-328551D01*
G01X702692Y-316151D02*
X702484Y-315066D01*
X701859Y-313826D01*
X700817Y-313051D01*
X699359Y-312741D01*
X697901Y-313051D01*
X696650Y-313981D01*
X696025Y-315376D01*
Y-316926D01*
X695609Y-317856D01*
X694567Y-318631D01*
X693109Y-318941D01*
X691650Y-318476D01*
X690609Y-317391D01*
X690192Y-316151D01*
X690609Y-314911D01*
X691650Y-313826D01*
X693109Y-313361D01*
X694567Y-313671D01*
X695609Y-314446D01*
X696025Y-315376D01*
Y-316926D01*
X696650Y-318321D01*
X697901Y-319251D01*
X699359Y-319561D01*
X700817Y-319251D01*
X701859Y-318476D01*
X702484Y-317236D01*
X702692Y-316151D01*
G01X700817Y-307161D02*
X701859Y-306231D01*
X702484Y-305146D01*
X702692Y-303751D01*
X702275Y-302356D01*
X701442Y-301271D01*
X699984Y-300496D01*
X698317Y-300341D01*
X696650Y-300651D01*
X695609Y-301426D01*
X694775Y-302511D01*
X694567Y-303596D01*
X694775Y-304681D01*
X695609Y-306076D01*
X690192Y-305611D01*
Y-301426D01*
G01X702692Y-269151D02*
X690192D01*
X692692Y-271011D01*
G01X702692D02*
Y-267291D01*
G01Y-257061D02*
X699984Y-256751D01*
X697692Y-256286D01*
X695609Y-255666D01*
X693317Y-254891D01*
X690192Y-253651D01*
Y-259851D01*
G01X702692Y-244351D02*
X702484Y-243266D01*
X701859Y-242026D01*
X700817Y-241251D01*
X699359Y-240941D01*
X697901Y-241251D01*
X696650Y-242181D01*
X696025Y-243576D01*
Y-245126D01*
X695609Y-246056D01*
X694567Y-246831D01*
X693109Y-247141D01*
X691650Y-246676D01*
X690609Y-245591D01*
X690192Y-244351D01*
X690609Y-243111D01*
X691650Y-242026D01*
X693109Y-241561D01*
X694567Y-241871D01*
X695609Y-242646D01*
X696025Y-243576D01*
Y-245126D01*
X696650Y-246521D01*
X697901Y-247451D01*
X699359Y-247761D01*
X700817Y-247451D01*
X701859Y-246676D01*
X702484Y-245436D01*
X702692Y-244351D01*
G01X703109Y-231951D02*
X702900Y-232261D01*
X702484D01*
X702275Y-231951D01*
X702484Y-231641D01*
X702900D01*
X703109Y-231951D01*
G01X702692Y-219551D02*
X702484Y-218466D01*
X701859Y-217226D01*
X700817Y-216451D01*
X699359Y-216141D01*
X697901Y-216451D01*
X696650Y-217381D01*
X696025Y-218776D01*
Y-220326D01*
X695609Y-221256D01*
X694567Y-222031D01*
X693109Y-222341D01*
X691650Y-221876D01*
X690609Y-220791D01*
X690192Y-219551D01*
X690609Y-218311D01*
X691650Y-217226D01*
X693109Y-216761D01*
X694567Y-217071D01*
X695609Y-217846D01*
X696025Y-218776D01*
Y-220326D01*
X696650Y-221721D01*
X697901Y-222651D01*
X699359Y-222961D01*
X700817Y-222651D01*
X701859Y-221876D01*
X702484Y-220636D01*
X702692Y-219551D01*
G01X697484Y-210096D02*
X696025Y-209011D01*
X695192Y-208081D01*
X694775Y-206841D01*
X695192Y-205756D01*
X696025Y-204981D01*
X697275Y-204361D01*
X698734Y-204206D01*
X699984Y-204361D01*
X701234Y-204981D01*
X702275Y-205911D01*
X702692Y-206996D01*
X702275Y-208236D01*
X701026Y-209321D01*
X699150Y-209941D01*
X697067Y-210096D01*
X694359Y-209786D01*
X692900Y-209321D01*
X691442Y-208546D01*
X690400Y-207461D01*
X690192Y-206376D01*
X690609Y-205291D01*
X691650Y-204516D01*
G01X723156Y-378346D02*
X720448Y-378036D01*
X718156Y-377571D01*
X716073Y-376951D01*
X713781Y-376176D01*
X710656Y-374936D01*
Y-381136D01*
G01Y-365636D02*
X711073Y-366876D01*
X712114Y-367806D01*
X713364Y-368426D01*
X715031Y-368891D01*
X716906Y-369046D01*
X718781Y-368891D01*
X720448Y-368426D01*
X721698Y-367806D01*
X722739Y-366876D01*
X723156Y-365636D01*
X722739Y-364396D01*
X721698Y-363466D01*
X720448Y-362846D01*
X718781Y-362381D01*
X716906Y-362226D01*
X715031Y-362381D01*
X713364Y-362846D01*
X712114Y-363466D01*
X711073Y-364396D01*
X710656Y-365636D01*
G01X723156Y-353546D02*
X720448Y-353236D01*
X718156Y-352771D01*
X716073Y-352151D01*
X713781Y-351376D01*
X710656Y-350136D01*
Y-356336D01*
G01X717948Y-343781D02*
X716489Y-342696D01*
X715656Y-341766D01*
X715239Y-340526D01*
X715656Y-339441D01*
X716489Y-338666D01*
X717739Y-338046D01*
X719198Y-337891D01*
X720448Y-338046D01*
X721698Y-338666D01*
X722739Y-339596D01*
X723156Y-340681D01*
X722739Y-341921D01*
X721490Y-343006D01*
X719614Y-343626D01*
X717531Y-343781D01*
X714823Y-343471D01*
X713364Y-343006D01*
X711906Y-342231D01*
X710864Y-341146D01*
X710656Y-340061D01*
X711073Y-338976D01*
X712114Y-338201D01*
G01X723573Y-328436D02*
X723364Y-328746D01*
X722948D01*
X722739Y-328436D01*
X722948Y-328126D01*
X723364D01*
X723573Y-328436D01*
G01X723156Y-316346D02*
X720448Y-316036D01*
X718156Y-315571D01*
X716073Y-314951D01*
X713781Y-314176D01*
X710656Y-312936D01*
Y-319136D01*
G01X723156Y-303946D02*
X720448Y-303636D01*
X718156Y-303171D01*
X716073Y-302551D01*
X713781Y-301776D01*
X710656Y-300536D01*
Y-306736D01*
G01X723156Y-269036D02*
X710656D01*
X713156Y-270896D01*
G01X723156D02*
Y-267176D01*
G01Y-256946D02*
X720448Y-256636D01*
X718156Y-256171D01*
X716073Y-255551D01*
X713781Y-254776D01*
X710656Y-253536D01*
Y-259736D01*
G01X721698Y-246871D02*
X722739Y-245786D01*
X723156Y-244546D01*
X722739Y-243306D01*
X721490Y-242221D01*
X719614Y-241446D01*
X717739Y-241136D01*
X715448D01*
X713573Y-241446D01*
X711906Y-242221D01*
X711073Y-243151D01*
X710656Y-244236D01*
X711073Y-245476D01*
X711906Y-246406D01*
X713156Y-247026D01*
X714823Y-247336D01*
X716281Y-247026D01*
X717739Y-246251D01*
X718573Y-245321D01*
X718781Y-244236D01*
X718365Y-242996D01*
X717323Y-242066D01*
X715448Y-241136D01*
G01X723573Y-231836D02*
X723364Y-232146D01*
X722948D01*
X722739Y-231836D01*
X722948Y-231526D01*
X723364D01*
X723573Y-231836D01*
G01X723156Y-219746D02*
X720448Y-219436D01*
X718156Y-218971D01*
X716073Y-218351D01*
X713781Y-217576D01*
X710656Y-216336D01*
Y-222536D01*
G01X721281Y-210446D02*
X722323Y-209516D01*
X722948Y-208431D01*
X723156Y-207036D01*
X722739Y-205641D01*
X721906Y-204556D01*
X720448Y-203781D01*
X718781Y-203626D01*
X717114Y-203936D01*
X716073Y-204711D01*
X715239Y-205796D01*
X715031Y-206881D01*
X715239Y-207966D01*
X716073Y-209361D01*
X710656Y-208896D01*
Y-204711D01*
G01X712265Y320821D02*
Y328321D01*
X716559Y320821D01*
Y328321D01*
G01X720045Y320821D02*
Y328321D01*
X722285D01*
X723032Y327946D01*
X723592Y327071D01*
X723779Y326071D01*
X723592Y325071D01*
X723125Y324321D01*
X722285Y323946D01*
X720045D01*
G01X729412Y328321D02*
Y320821D01*
G01X727265Y328321D02*
X731559D01*
G01X734952Y320821D02*
Y328321D01*
G01X738872D02*
Y320821D01*
G01Y324571D02*
X734952D01*
G01X769851Y-378231D02*
X767143Y-377921D01*
X764851Y-377456D01*
X762768Y-376836D01*
X760476Y-376061D01*
X757351Y-374821D01*
Y-381021D01*
G01X764643Y-368466D02*
X763184Y-367381D01*
X762351Y-366451D01*
X761934Y-365211D01*
X762351Y-364126D01*
X763184Y-363351D01*
X764434Y-362731D01*
X765893Y-362576D01*
X767143Y-362731D01*
X768393Y-363351D01*
X769434Y-364281D01*
X769851Y-365366D01*
X769434Y-366606D01*
X768185Y-367691D01*
X766309Y-368311D01*
X764226Y-368466D01*
X761518Y-368156D01*
X760059Y-367691D01*
X758601Y-366916D01*
X757559Y-365831D01*
X757351Y-364746D01*
X757768Y-363661D01*
X758809Y-362886D01*
G01X767351Y-356531D02*
X768810Y-355601D01*
X769643Y-354361D01*
X769851Y-352966D01*
X769643Y-351726D01*
X768601Y-350486D01*
X767351Y-349711D01*
X766101Y-349556D01*
X764643Y-349866D01*
X763601Y-350951D01*
X763184Y-352036D01*
Y-353431D01*
G01Y-352036D02*
X762559Y-351106D01*
X761518Y-350331D01*
X760268Y-350021D01*
X759018Y-350331D01*
X757976Y-351106D01*
X757351Y-352501D01*
X757559Y-353896D01*
X758393Y-355291D01*
G01X764643Y-343666D02*
X763184Y-342581D01*
X762351Y-341651D01*
X761934Y-340411D01*
X762351Y-339326D01*
X763184Y-338551D01*
X764434Y-337931D01*
X765893Y-337776D01*
X767143Y-337931D01*
X768393Y-338551D01*
X769434Y-339481D01*
X769851Y-340566D01*
X769434Y-341806D01*
X768185Y-342891D01*
X766309Y-343511D01*
X764226Y-343666D01*
X761518Y-343356D01*
X760059Y-342891D01*
X758601Y-342116D01*
X757559Y-341031D01*
X757351Y-339946D01*
X757768Y-338861D01*
X758809Y-338086D01*
G01X770268Y-328321D02*
X770059Y-328631D01*
X769643D01*
X769434Y-328321D01*
X769643Y-328011D01*
X770059D01*
X770268Y-328321D01*
G01X757351Y-315921D02*
X757768Y-317161D01*
X758809Y-318091D01*
X760059Y-318711D01*
X761726Y-319176D01*
X763601Y-319331D01*
X765476Y-319176D01*
X767143Y-318711D01*
X768393Y-318091D01*
X769434Y-317161D01*
X769851Y-315921D01*
X769434Y-314681D01*
X768393Y-313751D01*
X767143Y-313131D01*
X765476Y-312666D01*
X763601Y-312511D01*
X761726Y-312666D01*
X760059Y-313131D01*
X758809Y-313751D01*
X757768Y-314681D01*
X757351Y-315921D01*
G01X769851Y-303521D02*
X757351D01*
X759851Y-305381D01*
G01X769851D02*
Y-301661D01*
G01Y-268921D02*
X757351D01*
X759851Y-270781D01*
G01X769851D02*
Y-267061D01*
G01X768393Y-259156D02*
X769434Y-258071D01*
X769851Y-256831D01*
X769434Y-255591D01*
X768185Y-254506D01*
X766309Y-253731D01*
X764434Y-253421D01*
X762143D01*
X760268Y-253731D01*
X758601Y-254506D01*
X757768Y-255436D01*
X757351Y-256521D01*
X757768Y-257761D01*
X758601Y-258691D01*
X759851Y-259311D01*
X761518Y-259621D01*
X762976Y-259311D01*
X764434Y-258536D01*
X765268Y-257606D01*
X765476Y-256521D01*
X765060Y-255281D01*
X764018Y-254351D01*
X762143Y-253421D01*
G01X767351Y-247531D02*
X768810Y-246601D01*
X769643Y-245361D01*
X769851Y-243966D01*
X769643Y-242726D01*
X768601Y-241486D01*
X767351Y-240711D01*
X766101Y-240556D01*
X764643Y-240866D01*
X763601Y-241951D01*
X763184Y-243036D01*
Y-244431D01*
G01Y-243036D02*
X762559Y-242106D01*
X761518Y-241331D01*
X760268Y-241021D01*
X759018Y-241331D01*
X757976Y-242106D01*
X757351Y-243501D01*
X757559Y-244896D01*
X758393Y-246291D01*
G01X770268Y-231721D02*
X770059Y-232031D01*
X769643D01*
X769434Y-231721D01*
X769643Y-231411D01*
X770059D01*
X770268Y-231721D01*
G01X768393Y-221956D02*
X769434Y-220871D01*
X769851Y-219631D01*
X769434Y-218391D01*
X768185Y-217306D01*
X766309Y-216531D01*
X764434Y-216221D01*
X762143D01*
X760268Y-216531D01*
X758601Y-217306D01*
X757768Y-218236D01*
X757351Y-219321D01*
X757768Y-220561D01*
X758601Y-221491D01*
X759851Y-222111D01*
X761518Y-222421D01*
X762976Y-222111D01*
X764434Y-221336D01*
X765268Y-220406D01*
X765476Y-219321D01*
X765060Y-218081D01*
X764018Y-217151D01*
X762143Y-216221D01*
G01X767976Y-210331D02*
X769018Y-209401D01*
X769643Y-208316D01*
X769851Y-206921D01*
X769434Y-205526D01*
X768601Y-204441D01*
X767143Y-203666D01*
X765476Y-203511D01*
X763809Y-203821D01*
X762768Y-204596D01*
X761934Y-205681D01*
X761726Y-206766D01*
X761934Y-207851D01*
X762768Y-209246D01*
X757351Y-208781D01*
Y-204596D01*
G01X766684Y638162D02*
Y645662D01*
X770978Y638162D01*
Y645662D01*
G01X774464Y638162D02*
Y645662D01*
X776704D01*
X777451Y645287D01*
X778011Y644412D01*
X778198Y643412D01*
X778011Y642412D01*
X777544Y641662D01*
X776704Y641287D01*
X774464D01*
G01X783831Y645662D02*
Y638162D01*
G01X781684Y645662D02*
X785978D01*
G01X789371Y638162D02*
Y645662D01*
G01X793291D02*
Y638162D01*
G01Y641912D02*
X789371D01*
G01X791205Y-365151D02*
X790997Y-364066D01*
X790372Y-362826D01*
X789330Y-362051D01*
X787872Y-361741D01*
X786414Y-362051D01*
X785163Y-362981D01*
X784538Y-364376D01*
Y-365926D01*
X784122Y-366856D01*
X783080Y-367631D01*
X781622Y-367941D01*
X780163Y-367476D01*
X779122Y-366391D01*
X778705Y-365151D01*
X779122Y-363911D01*
X780163Y-362826D01*
X781622Y-362361D01*
X783080Y-362671D01*
X784122Y-363446D01*
X784538Y-364376D01*
Y-365926D01*
X785163Y-367321D01*
X786414Y-368251D01*
X787872Y-368561D01*
X789330Y-368251D01*
X790372Y-367476D01*
X790997Y-366236D01*
X791205Y-365151D01*
G01X778705Y-352751D02*
X779122Y-353991D01*
X780163Y-354921D01*
X781413Y-355541D01*
X783080Y-356006D01*
X784955Y-356161D01*
X786830Y-356006D01*
X788497Y-355541D01*
X789747Y-354921D01*
X790788Y-353991D01*
X791205Y-352751D01*
X790788Y-351511D01*
X789747Y-350581D01*
X788497Y-349961D01*
X786830Y-349496D01*
X784955Y-349341D01*
X783080Y-349496D01*
X781413Y-349961D01*
X780163Y-350581D01*
X779122Y-351511D01*
X778705Y-352751D01*
G01Y-340351D02*
X779122Y-341591D01*
X780163Y-342521D01*
X781413Y-343141D01*
X783080Y-343606D01*
X784955Y-343761D01*
X786830Y-343606D01*
X788497Y-343141D01*
X789747Y-342521D01*
X790788Y-341591D01*
X791205Y-340351D01*
X790788Y-339111D01*
X789747Y-338181D01*
X788497Y-337561D01*
X786830Y-337096D01*
X784955Y-336941D01*
X783080Y-337096D01*
X781413Y-337561D01*
X780163Y-338181D01*
X779122Y-339111D01*
X778705Y-340351D01*
G01X791205Y-328261D02*
X788497Y-327951D01*
X786205Y-327486D01*
X784122Y-326866D01*
X781830Y-326091D01*
X778705Y-324851D01*
Y-331051D01*
G01X791622Y-315551D02*
X791413Y-315861D01*
X790997D01*
X790788Y-315551D01*
X790997Y-315241D01*
X791413D01*
X791622Y-315551D01*
G01X791205Y-303151D02*
X790997Y-302066D01*
X790372Y-300826D01*
X789330Y-300051D01*
X787872Y-299741D01*
X786414Y-300051D01*
X785163Y-300981D01*
X784538Y-302376D01*
Y-303926D01*
X784122Y-304856D01*
X783080Y-305631D01*
X781622Y-305941D01*
X780163Y-305476D01*
X779122Y-304391D01*
X778705Y-303151D01*
X779122Y-301911D01*
X780163Y-300826D01*
X781622Y-300361D01*
X783080Y-300671D01*
X784122Y-301446D01*
X784538Y-302376D01*
Y-303926D01*
X785163Y-305321D01*
X786414Y-306251D01*
X787872Y-306561D01*
X789330Y-306251D01*
X790372Y-305476D01*
X790997Y-304236D01*
X791205Y-303151D01*
G01Y-291061D02*
X788497Y-290751D01*
X786205Y-290286D01*
X784122Y-289666D01*
X781830Y-288891D01*
X778705Y-287651D01*
Y-293851D01*
G01X780788Y-259096D02*
X779539Y-258166D01*
X778913Y-257081D01*
X778705Y-255841D01*
X779122Y-254291D01*
X780163Y-253206D01*
X781413Y-252896D01*
X782664Y-253051D01*
X783705Y-253671D01*
X785788Y-256771D01*
X787247Y-258166D01*
X789330Y-259096D01*
X791205Y-259406D01*
Y-252896D01*
G01X778705Y-243751D02*
X779122Y-244991D01*
X780163Y-245921D01*
X781413Y-246541D01*
X783080Y-247006D01*
X784955Y-247161D01*
X786830Y-247006D01*
X788497Y-246541D01*
X789747Y-245921D01*
X790788Y-244991D01*
X791205Y-243751D01*
X790788Y-242511D01*
X789747Y-241581D01*
X788497Y-240961D01*
X786830Y-240496D01*
X784955Y-240341D01*
X783080Y-240496D01*
X781413Y-240961D01*
X780163Y-241581D01*
X779122Y-242511D01*
X778705Y-243751D01*
G01X788705Y-234761D02*
X790164Y-233831D01*
X790997Y-232591D01*
X791205Y-231196D01*
X790997Y-229956D01*
X789955Y-228716D01*
X788705Y-227941D01*
X787455Y-227786D01*
X785997Y-228096D01*
X784955Y-229181D01*
X784538Y-230266D01*
Y-231661D01*
G01Y-230266D02*
X783913Y-229336D01*
X782872Y-228561D01*
X781622Y-228251D01*
X780372Y-228561D01*
X779330Y-229336D01*
X778705Y-230731D01*
X778913Y-232126D01*
X779747Y-233521D01*
G01X791622Y-218951D02*
X791413Y-219261D01*
X790997D01*
X790788Y-218951D01*
X790997Y-218641D01*
X791413D01*
X791622Y-218951D01*
G01X791205Y-204691D02*
X778705D01*
X787663Y-210426D01*
Y-202676D01*
G01X811940Y-377892D02*
X811732Y-376807D01*
X811107Y-375567D01*
X810065Y-374792D01*
X808607Y-374482D01*
X807149Y-374792D01*
X805898Y-375722D01*
X805273Y-377117D01*
Y-378667D01*
X804857Y-379597D01*
X803815Y-380372D01*
X802357Y-380682D01*
X800898Y-380217D01*
X799857Y-379132D01*
X799440Y-377892D01*
X799857Y-376652D01*
X800898Y-375567D01*
X802357Y-375102D01*
X803815Y-375412D01*
X804857Y-376187D01*
X805273Y-377117D01*
Y-378667D01*
X805898Y-380062D01*
X807149Y-380992D01*
X808607Y-381302D01*
X810065Y-380992D01*
X811107Y-380217D01*
X811732Y-378977D01*
X811940Y-377892D01*
G01X799440Y-365492D02*
X799857Y-366732D01*
X800898Y-367662D01*
X802148Y-368282D01*
X803815Y-368747D01*
X805690Y-368902D01*
X807565Y-368747D01*
X809232Y-368282D01*
X810482Y-367662D01*
X811523Y-366732D01*
X811940Y-365492D01*
X811523Y-364252D01*
X810482Y-363322D01*
X809232Y-362702D01*
X807565Y-362237D01*
X805690Y-362082D01*
X803815Y-362237D01*
X802148Y-362702D01*
X800898Y-363322D01*
X799857Y-364252D01*
X799440Y-365492D01*
G01X810065Y-356502D02*
X811107Y-355572D01*
X811732Y-354487D01*
X811940Y-353092D01*
X811523Y-351697D01*
X810690Y-350612D01*
X809232Y-349837D01*
X807565Y-349682D01*
X805898Y-349992D01*
X804857Y-350767D01*
X804023Y-351852D01*
X803815Y-352937D01*
X804023Y-354022D01*
X804857Y-355417D01*
X799440Y-354952D01*
Y-350767D01*
G01X806732Y-343637D02*
X805273Y-342552D01*
X804440Y-341622D01*
X804023Y-340382D01*
X804440Y-339297D01*
X805273Y-338522D01*
X806523Y-337902D01*
X807982Y-337747D01*
X809232Y-337902D01*
X810482Y-338522D01*
X811523Y-339452D01*
X811940Y-340537D01*
X811523Y-341777D01*
X810274Y-342862D01*
X808398Y-343482D01*
X806315Y-343637D01*
X803607Y-343327D01*
X802148Y-342862D01*
X800690Y-342087D01*
X799648Y-341002D01*
X799440Y-339917D01*
X799857Y-338832D01*
X800898Y-338057D01*
G01X812357Y-328292D02*
X812148Y-328602D01*
X811732D01*
X811523Y-328292D01*
X811732Y-327982D01*
X812148D01*
X812357Y-328292D01*
G01X810482Y-318527D02*
X811523Y-317442D01*
X811940Y-316202D01*
X811523Y-314962D01*
X810274Y-313877D01*
X808398Y-313102D01*
X806523Y-312792D01*
X804232D01*
X802357Y-313102D01*
X800690Y-313877D01*
X799857Y-314807D01*
X799440Y-315892D01*
X799857Y-317132D01*
X800690Y-318062D01*
X801940Y-318682D01*
X803607Y-318992D01*
X805065Y-318682D01*
X806523Y-317907D01*
X807357Y-316977D01*
X807565Y-315892D01*
X807149Y-314652D01*
X806107Y-313722D01*
X804232Y-312792D01*
G01X799440Y-303492D02*
X799857Y-304732D01*
X800898Y-305662D01*
X802148Y-306282D01*
X803815Y-306747D01*
X805690Y-306902D01*
X807565Y-306747D01*
X809232Y-306282D01*
X810482Y-305662D01*
X811523Y-304732D01*
X811940Y-303492D01*
X811523Y-302252D01*
X810482Y-301322D01*
X809232Y-300702D01*
X807565Y-300237D01*
X805690Y-300082D01*
X803815Y-300237D01*
X802148Y-300702D01*
X800898Y-301322D01*
X799857Y-302252D01*
X799440Y-303492D01*
G01X801523Y-271837D02*
X800274Y-270907D01*
X799648Y-269822D01*
X799440Y-268582D01*
X799857Y-267032D01*
X800898Y-265947D01*
X802148Y-265637D01*
X803399Y-265792D01*
X804440Y-266412D01*
X806523Y-269512D01*
X807982Y-270907D01*
X810065Y-271837D01*
X811940Y-272147D01*
Y-265637D01*
G01X799440Y-256492D02*
X799857Y-257732D01*
X800898Y-258662D01*
X802148Y-259282D01*
X803815Y-259747D01*
X805690Y-259902D01*
X807565Y-259747D01*
X809232Y-259282D01*
X810482Y-258662D01*
X811523Y-257732D01*
X811940Y-256492D01*
X811523Y-255252D01*
X810482Y-254322D01*
X809232Y-253702D01*
X807565Y-253237D01*
X805690Y-253082D01*
X803815Y-253237D01*
X802148Y-253702D01*
X800898Y-254322D01*
X799857Y-255252D01*
X799440Y-256492D01*
G01X811940Y-242232D02*
X799440D01*
X808398Y-247967D01*
Y-240217D01*
G01X812357Y-231692D02*
X812148Y-232002D01*
X811732D01*
X811523Y-231692D01*
X811732Y-231382D01*
X812148D01*
X812357Y-231692D01*
G01X806732Y-222237D02*
X805273Y-221152D01*
X804440Y-220222D01*
X804023Y-218982D01*
X804440Y-217897D01*
X805273Y-217122D01*
X806523Y-216502D01*
X807982Y-216347D01*
X809232Y-216502D01*
X810482Y-217122D01*
X811523Y-218052D01*
X811940Y-219137D01*
X811523Y-220377D01*
X810274Y-221462D01*
X808398Y-222082D01*
X806315Y-222237D01*
X803607Y-221927D01*
X802148Y-221462D01*
X800690Y-220687D01*
X799648Y-219602D01*
X799440Y-218517D01*
X799857Y-217432D01*
X800898Y-216657D01*
G01X810065Y-210302D02*
X811107Y-209372D01*
X811732Y-208287D01*
X811940Y-206892D01*
X811523Y-205497D01*
X810690Y-204412D01*
X809232Y-203637D01*
X807565Y-203482D01*
X805898Y-203792D01*
X804857Y-204567D01*
X804023Y-205652D01*
X803815Y-206737D01*
X804023Y-207822D01*
X804857Y-209217D01*
X799440Y-208752D01*
Y-204567D01*
G01X849316Y-377891D02*
X849108Y-376806D01*
X848483Y-375566D01*
X847441Y-374791D01*
X845983Y-374481D01*
X844525Y-374791D01*
X843274Y-375721D01*
X842649Y-377116D01*
Y-378666D01*
X842233Y-379596D01*
X841191Y-380371D01*
X839733Y-380681D01*
X838274Y-380216D01*
X837233Y-379131D01*
X836816Y-377891D01*
X837233Y-376651D01*
X838274Y-375566D01*
X839733Y-375101D01*
X841191Y-375411D01*
X842233Y-376186D01*
X842649Y-377116D01*
Y-378666D01*
X843274Y-380061D01*
X844525Y-380991D01*
X845983Y-381301D01*
X847441Y-380991D01*
X848483Y-380216D01*
X849108Y-378976D01*
X849316Y-377891D01*
G01Y-363631D02*
X836816D01*
X845774Y-369366D01*
Y-361616D01*
G01X846816Y-356501D02*
X848275Y-355571D01*
X849108Y-354331D01*
X849316Y-352936D01*
X849108Y-351696D01*
X848066Y-350456D01*
X846816Y-349681D01*
X845566Y-349526D01*
X844108Y-349836D01*
X843066Y-350921D01*
X842649Y-352006D01*
Y-353401D01*
G01Y-352006D02*
X842024Y-351076D01*
X840983Y-350301D01*
X839733Y-349991D01*
X838483Y-350301D01*
X837441Y-351076D01*
X836816Y-352471D01*
X837024Y-353866D01*
X837858Y-355261D01*
G01X836816Y-340691D02*
X837233Y-341931D01*
X838274Y-342861D01*
X839524Y-343481D01*
X841191Y-343946D01*
X843066Y-344101D01*
X844941Y-343946D01*
X846608Y-343481D01*
X847858Y-342861D01*
X848899Y-341931D01*
X849316Y-340691D01*
X848899Y-339451D01*
X847858Y-338521D01*
X846608Y-337901D01*
X844941Y-337436D01*
X843066Y-337281D01*
X841191Y-337436D01*
X839524Y-337901D01*
X838274Y-338521D01*
X837233Y-339451D01*
X836816Y-340691D01*
G01X849733Y-328291D02*
X849524Y-328601D01*
X849108D01*
X848899Y-328291D01*
X849108Y-327981D01*
X849524D01*
X849733Y-328291D01*
G01X844108Y-318836D02*
X842649Y-317751D01*
X841816Y-316821D01*
X841399Y-315581D01*
X841816Y-314496D01*
X842649Y-313721D01*
X843899Y-313101D01*
X845358Y-312946D01*
X846608Y-313101D01*
X847858Y-313721D01*
X848899Y-314651D01*
X849316Y-315736D01*
X848899Y-316976D01*
X847650Y-318061D01*
X845774Y-318681D01*
X843691Y-318836D01*
X840983Y-318526D01*
X839524Y-318061D01*
X838066Y-317286D01*
X837024Y-316201D01*
X836816Y-315116D01*
X837233Y-314031D01*
X838274Y-313256D01*
G01X844108Y-306436D02*
X842649Y-305351D01*
X841816Y-304421D01*
X841399Y-303181D01*
X841816Y-302096D01*
X842649Y-301321D01*
X843899Y-300701D01*
X845358Y-300546D01*
X846608Y-300701D01*
X847858Y-301321D01*
X848899Y-302251D01*
X849316Y-303336D01*
X848899Y-304576D01*
X847650Y-305661D01*
X845774Y-306281D01*
X843691Y-306436D01*
X840983Y-306126D01*
X839524Y-305661D01*
X838066Y-304886D01*
X837024Y-303801D01*
X836816Y-302716D01*
X837233Y-301631D01*
X838274Y-300856D01*
G01X838899Y-271836D02*
X837650Y-270906D01*
X837024Y-269821D01*
X836816Y-268581D01*
X837233Y-267031D01*
X838274Y-265946D01*
X839524Y-265636D01*
X840775Y-265791D01*
X841816Y-266411D01*
X843899Y-269511D01*
X845358Y-270906D01*
X847441Y-271836D01*
X849316Y-272146D01*
Y-265636D01*
G01Y-256491D02*
X836816D01*
X839316Y-258351D01*
G01X849316D02*
Y-254631D01*
G01Y-242231D02*
X836816D01*
X845774Y-247966D01*
Y-240216D01*
G01X849733Y-231691D02*
X849524Y-232001D01*
X849108D01*
X848899Y-231691D01*
X849108Y-231381D01*
X849524D01*
X849733Y-231691D01*
G01X849316Y-219291D02*
X836816D01*
X839316Y-221151D01*
G01X849316D02*
Y-217431D01*
G01Y-205031D02*
X836816D01*
X845774Y-210766D01*
Y-203016D01*
G01X845340Y1786368D02*
Y1798868D01*
X843480Y1796368D01*
G01Y1786368D02*
X847200D01*
G01X857740D02*
X858825Y1786576D01*
X860065Y1787201D01*
X860840Y1788243D01*
X861150Y1789701D01*
X860840Y1791159D01*
X859910Y1792410D01*
X858515Y1793035D01*
X856965D01*
X856035Y1793451D01*
X855260Y1794493D01*
X854950Y1795951D01*
X855415Y1797410D01*
X856500Y1798451D01*
X857740Y1798868D01*
X858980Y1798451D01*
X860065Y1797410D01*
X860530Y1795951D01*
X860220Y1794493D01*
X859445Y1793451D01*
X858515Y1793035D01*
X856965D01*
X855570Y1792410D01*
X854640Y1791159D01*
X854330Y1789701D01*
X854640Y1788243D01*
X855415Y1787201D01*
X856655Y1786576D01*
X857740Y1786368D01*
G01X866730Y1788243D02*
X867660Y1787201D01*
X868745Y1786576D01*
X870140Y1786368D01*
X871535Y1786785D01*
X872620Y1787618D01*
X873395Y1789076D01*
X873550Y1790743D01*
X873240Y1792410D01*
X872465Y1793451D01*
X871380Y1794285D01*
X870295Y1794493D01*
X869210Y1794285D01*
X867815Y1793451D01*
X868280Y1798868D01*
X872465D01*
G01X882230Y1786368D02*
X882540Y1789076D01*
X883005Y1791368D01*
X883625Y1793451D01*
X884400Y1795743D01*
X885640Y1798868D01*
X879440D01*
G01X896800Y1786368D02*
Y1798868D01*
X891065Y1789910D01*
X898815D01*
G01X907340Y1785951D02*
X907030Y1786160D01*
Y1786576D01*
X907340Y1786785D01*
X907650Y1786576D01*
Y1786160D01*
X907340Y1785951D01*
G01X919740Y1786368D02*
X920825Y1786576D01*
X922065Y1787201D01*
X922840Y1788243D01*
X923150Y1789701D01*
X922840Y1791159D01*
X921910Y1792410D01*
X920515Y1793035D01*
X918965D01*
X918035Y1793451D01*
X917260Y1794493D01*
X916950Y1795951D01*
X917415Y1797410D01*
X918500Y1798451D01*
X919740Y1798868D01*
X920980Y1798451D01*
X922065Y1797410D01*
X922530Y1795951D01*
X922220Y1794493D01*
X921445Y1793451D01*
X920515Y1793035D01*
X918965D01*
X917570Y1792410D01*
X916640Y1791159D01*
X916330Y1789701D01*
X916640Y1788243D01*
X917415Y1787201D01*
X918655Y1786576D01*
X919740Y1786368D01*
G01X932140Y1798868D02*
X930900Y1798451D01*
X929970Y1797410D01*
X929350Y1796160D01*
X928885Y1794493D01*
X928730Y1792618D01*
X928885Y1790743D01*
X929350Y1789076D01*
X929970Y1787826D01*
X930900Y1786785D01*
X932140Y1786368D01*
X933380Y1786785D01*
X934310Y1787826D01*
X934930Y1789076D01*
X935395Y1790743D01*
X935550Y1792618D01*
X935395Y1794493D01*
X934930Y1796160D01*
X934310Y1797410D01*
X933380Y1798451D01*
X932140Y1798868D01*
G01X852542Y348781D02*
Y355156D01*
X852729Y355781D01*
X853102Y356156D01*
X853662Y356281D01*
X854222Y356031D01*
X854502Y355406D01*
G01X853382Y353281D02*
X851515D01*
G01X860602Y348781D02*
X860042Y348906D01*
X859482Y349406D01*
X859109Y350281D01*
X858922Y351281D01*
X859109Y352281D01*
X859482Y353156D01*
X860042Y353656D01*
X860602Y353781D01*
X861162Y353656D01*
X861722Y353156D01*
X862095Y352281D01*
X862189Y351281D01*
X862095Y350281D01*
X861722Y349406D01*
X861162Y348906D01*
X860602Y348781D01*
G01X868102D02*
Y356281D01*
G01X875602Y348781D02*
Y356281D01*
G01X883102Y348781D02*
X882542Y348906D01*
X881982Y349406D01*
X881609Y350281D01*
X881422Y351281D01*
X881609Y352281D01*
X881982Y353156D01*
X882542Y353656D01*
X883102Y353781D01*
X883662Y353656D01*
X884222Y353156D01*
X884595Y352281D01*
X884689Y351281D01*
X884595Y350281D01*
X884222Y349406D01*
X883662Y348906D01*
X883102Y348781D01*
G01X888269Y353781D02*
X889389Y348781D01*
X890602Y353781D01*
X891815Y348781D01*
X892935Y353781D01*
G01X905602Y348781D02*
X905042Y348906D01*
X904482Y349406D01*
X904109Y350281D01*
X903922Y351281D01*
X904109Y352281D01*
X904482Y353156D01*
X905042Y353656D01*
X905602Y353781D01*
X906162Y353656D01*
X906722Y353156D01*
X907095Y352281D01*
X907189Y351281D01*
X907095Y350281D01*
X906722Y349406D01*
X906162Y348906D01*
X905602Y348781D01*
G01X911515Y353781D02*
Y350281D01*
X911889Y349406D01*
X912449Y348906D01*
X913102Y348781D01*
X913755Y348906D01*
X914315Y349406D01*
X914689Y350281D01*
G01Y348781D02*
Y353781D01*
G01X920602Y356281D02*
Y348781D01*
G01X919295Y353781D02*
X921909D01*
G01X928102Y348781D02*
Y356281D01*
G01X935602Y353781D02*
Y348781D01*
G01Y355781D02*
X935415Y355906D01*
Y356156D01*
X935602Y356281D01*
X935789Y356156D01*
Y355906D01*
X935602Y355781D01*
G01X941515Y348781D02*
Y353781D01*
G01Y352531D02*
X941889Y353156D01*
X942449Y353656D01*
X943195Y353781D01*
X943849Y353656D01*
X944409Y353156D01*
X944689Y352281D01*
Y348781D01*
G01X949202Y352156D02*
X952189D01*
X951909Y353031D01*
X951442Y353531D01*
X950789Y353781D01*
X950135Y353656D01*
X949575Y353281D01*
X949202Y352406D01*
X949015Y351656D01*
Y350906D01*
X949202Y350156D01*
X949669Y349406D01*
X950229Y348906D01*
X950882Y348781D01*
X951535Y349031D01*
X952189Y349781D01*
G01X865950Y1761368D02*
Y1773868D01*
X860215Y1764910D01*
X867965D01*
G01X876180Y1761368D02*
X876490Y1764076D01*
X876955Y1766368D01*
X877575Y1768451D01*
X878350Y1770743D01*
X879590Y1773868D01*
X873390D01*
G01X888890Y1761368D02*
Y1773868D01*
X887030Y1771368D01*
G01Y1761368D02*
X890750D01*
G01X901290Y1760951D02*
X900980Y1761160D01*
Y1761576D01*
X901290Y1761785D01*
X901600Y1761576D01*
Y1761160D01*
X901290Y1760951D01*
G01X913690Y1761368D02*
X914775Y1761576D01*
X916015Y1762201D01*
X916790Y1763243D01*
X917100Y1764701D01*
X916790Y1766159D01*
X915860Y1767410D01*
X914465Y1768035D01*
X912915D01*
X911985Y1768451D01*
X911210Y1769493D01*
X910900Y1770951D01*
X911365Y1772410D01*
X912450Y1773451D01*
X913690Y1773868D01*
X914930Y1773451D01*
X916015Y1772410D01*
X916480Y1770951D01*
X916170Y1769493D01*
X915395Y1768451D01*
X914465Y1768035D01*
X912915D01*
X911520Y1767410D01*
X910590Y1766159D01*
X910280Y1764701D01*
X910590Y1763243D01*
X911365Y1762201D01*
X912605Y1761576D01*
X913690Y1761368D01*
G01X892771Y1461834D02*
Y1469334D01*
X895011D01*
X895758Y1468959D01*
X896318Y1468084D01*
X896505Y1467084D01*
X896318Y1466084D01*
X895851Y1465334D01*
X895011Y1464959D01*
X892771D01*
G01X904191Y1468709D02*
X903631Y1469084D01*
X902978Y1469334D01*
X902231D01*
X901391Y1468959D01*
X900738Y1468334D01*
X900271Y1467584D01*
X899898Y1466334D01*
X899805Y1465209D01*
X899991Y1464084D01*
X900271Y1463334D01*
X900831Y1462584D01*
X901485Y1462084D01*
X902138Y1461834D01*
X902791D01*
X903445Y1462084D01*
X904005Y1462459D01*
X904471Y1462959D01*
G01X910385Y1465834D02*
X910758Y1466209D01*
X911038Y1466834D01*
X911225Y1467709D01*
X911038Y1468459D01*
X910665Y1468959D01*
X910011Y1469334D01*
X907491D01*
Y1461834D01*
X910571D01*
X911225Y1462334D01*
X911598Y1463084D01*
X911785Y1463959D01*
X911598Y1464834D01*
X911038Y1465584D01*
X910385Y1465834D01*
X907491D01*
G01X922305Y1469334D02*
X924638Y1461834D01*
X926971Y1469334D01*
G01X934005Y1461834D02*
X930271D01*
Y1469334D01*
X934005D01*
G01X932511Y1465709D02*
X930271D01*
G01X937491Y1461834D02*
Y1469334D01*
X941785Y1461834D01*
Y1469334D01*
G01X945085Y1461834D02*
Y1469334D01*
X946951D01*
X947698Y1468959D01*
X948258Y1468459D01*
X948725Y1467709D01*
X949098Y1466834D01*
X949191Y1465584D01*
X949098Y1464334D01*
X948725Y1463459D01*
X948258Y1462709D01*
X947698Y1462209D01*
X946951Y1461834D01*
X945085D01*
G01X954638D02*
X953891Y1461959D01*
X953238Y1462459D01*
X952678Y1463209D01*
X952305Y1464084D01*
X952118Y1465084D01*
Y1466084D01*
X952305Y1467084D01*
X952678Y1467959D01*
X953238Y1468709D01*
X953891Y1469209D01*
X954638Y1469334D01*
X955385Y1469209D01*
X956038Y1468709D01*
X956598Y1467959D01*
X956971Y1467084D01*
X957158Y1466084D01*
Y1465084D01*
X956971Y1464084D01*
X956598Y1463209D01*
X956038Y1462459D01*
X955385Y1461959D01*
X954638Y1461834D01*
G01X960271D02*
Y1469334D01*
X962605D01*
X963351Y1468959D01*
X963818Y1468459D01*
X964005Y1467459D01*
X963818Y1466459D01*
X963258Y1465834D01*
X962605Y1465459D01*
X960271D01*
G01X962605D02*
X964005Y1461834D01*
G01X915271Y1453586D02*
Y1446086D01*
X919005D01*
G01X924638D02*
X923891Y1446211D01*
X923238Y1446711D01*
X922678Y1447461D01*
X922305Y1448336D01*
X922118Y1449336D01*
Y1450336D01*
X922305Y1451336D01*
X922678Y1452211D01*
X923238Y1452961D01*
X923891Y1453461D01*
X924638Y1453586D01*
X925385Y1453461D01*
X926038Y1452961D01*
X926598Y1452211D01*
X926971Y1451336D01*
X927158Y1450336D01*
Y1449336D01*
X926971Y1448336D01*
X926598Y1447461D01*
X926038Y1446711D01*
X925385Y1446211D01*
X924638Y1446086D01*
G01X932698Y1449836D02*
X934565D01*
Y1447586D01*
X934005Y1446836D01*
X933351Y1446336D01*
X932418Y1446086D01*
X931485Y1446336D01*
X930831Y1446836D01*
X930271Y1447586D01*
X929898Y1448461D01*
X929711Y1449461D01*
Y1450336D01*
X929898Y1451086D01*
X930271Y1451961D01*
X930831Y1452711D01*
X931391Y1453211D01*
X932138Y1453586D01*
X932791D01*
X933538Y1453336D01*
X934098Y1452836D01*
G01X939638Y1446086D02*
X938891Y1446211D01*
X938238Y1446711D01*
X937678Y1447461D01*
X937305Y1448336D01*
X937118Y1449336D01*
Y1450336D01*
X937305Y1451336D01*
X937678Y1452211D01*
X938238Y1452961D01*
X938891Y1453461D01*
X939638Y1453586D01*
X940385Y1453461D01*
X941038Y1452961D01*
X941598Y1452211D01*
X941971Y1451336D01*
X942158Y1450336D01*
Y1449336D01*
X941971Y1448336D01*
X941598Y1447461D01*
X941038Y1446711D01*
X940385Y1446211D01*
X939638Y1446086D01*
G01X936484Y-380527D02*
X937525Y-379442D01*
X937942Y-378202D01*
X937525Y-376962D01*
X936276Y-375877D01*
X934400Y-375102D01*
X932525Y-374792D01*
X930234D01*
X928359Y-375102D01*
X926692Y-375877D01*
X925859Y-376807D01*
X925442Y-377892D01*
X925859Y-379132D01*
X926692Y-380062D01*
X927942Y-380682D01*
X929609Y-380992D01*
X931067Y-380682D01*
X932525Y-379907D01*
X933359Y-378977D01*
X933567Y-377892D01*
X933151Y-376652D01*
X932109Y-375722D01*
X930234Y-374792D01*
G01X935442Y-368902D02*
X936901Y-367972D01*
X937734Y-366732D01*
X937942Y-365337D01*
X937734Y-364097D01*
X936692Y-362857D01*
X935442Y-362082D01*
X934192Y-361927D01*
X932734Y-362237D01*
X931692Y-363322D01*
X931275Y-364407D01*
Y-365802D01*
G01Y-364407D02*
X930650Y-363477D01*
X929609Y-362702D01*
X928359Y-362392D01*
X927109Y-362702D01*
X926067Y-363477D01*
X925442Y-364872D01*
X925650Y-366267D01*
X926484Y-367662D01*
G01X937942Y-353092D02*
X925442D01*
X927942Y-354952D01*
G01X937942D02*
Y-351232D01*
G01X932734Y-343637D02*
X931275Y-342552D01*
X930442Y-341622D01*
X930025Y-340382D01*
X930442Y-339297D01*
X931275Y-338522D01*
X932525Y-337902D01*
X933984Y-337747D01*
X935234Y-337902D01*
X936484Y-338522D01*
X937525Y-339452D01*
X937942Y-340537D01*
X937525Y-341777D01*
X936276Y-342862D01*
X934400Y-343482D01*
X932317Y-343637D01*
X929609Y-343327D01*
X928150Y-342862D01*
X926692Y-342087D01*
X925650Y-341002D01*
X925442Y-339917D01*
X925859Y-338832D01*
X926900Y-338057D01*
G01X938359Y-328292D02*
X938150Y-328602D01*
X937734D01*
X937525Y-328292D01*
X937734Y-327982D01*
X938150D01*
X938359Y-328292D01*
G01X936484Y-318527D02*
X937525Y-317442D01*
X937942Y-316202D01*
X937525Y-314962D01*
X936276Y-313877D01*
X934400Y-313102D01*
X932525Y-312792D01*
X930234D01*
X928359Y-313102D01*
X926692Y-313877D01*
X925859Y-314807D01*
X925442Y-315892D01*
X925859Y-317132D01*
X926692Y-318062D01*
X927942Y-318682D01*
X929609Y-318992D01*
X931067Y-318682D01*
X932525Y-317907D01*
X933359Y-316977D01*
X933567Y-315892D01*
X933151Y-314652D01*
X932109Y-313722D01*
X930234Y-312792D01*
G01X927525Y-306437D02*
X926276Y-305507D01*
X925650Y-304422D01*
X925442Y-303182D01*
X925859Y-301632D01*
X926900Y-300547D01*
X928150Y-300237D01*
X929401Y-300392D01*
X930442Y-301012D01*
X932525Y-304112D01*
X933984Y-305507D01*
X936067Y-306437D01*
X937942Y-306747D01*
Y-300237D01*
G01X927525Y-271837D02*
X926276Y-270907D01*
X925650Y-269822D01*
X925442Y-268582D01*
X925859Y-267032D01*
X926900Y-265947D01*
X928150Y-265637D01*
X929401Y-265792D01*
X930442Y-266412D01*
X932525Y-269512D01*
X933984Y-270907D01*
X936067Y-271837D01*
X937942Y-272147D01*
Y-265637D01*
G01X935442Y-259902D02*
X936901Y-258972D01*
X937734Y-257732D01*
X937942Y-256337D01*
X937734Y-255097D01*
X936692Y-253857D01*
X935442Y-253082D01*
X934192Y-252927D01*
X932734Y-253237D01*
X931692Y-254322D01*
X931275Y-255407D01*
Y-256802D01*
G01Y-255407D02*
X930650Y-254477D01*
X929609Y-253702D01*
X928359Y-253392D01*
X927109Y-253702D01*
X926067Y-254477D01*
X925442Y-255872D01*
X925650Y-257267D01*
X926484Y-258662D01*
G01X932734Y-247037D02*
X931275Y-245952D01*
X930442Y-245022D01*
X930025Y-243782D01*
X930442Y-242697D01*
X931275Y-241922D01*
X932525Y-241302D01*
X933984Y-241147D01*
X935234Y-241302D01*
X936484Y-241922D01*
X937525Y-242852D01*
X937942Y-243937D01*
X937525Y-245177D01*
X936276Y-246262D01*
X934400Y-246882D01*
X932317Y-247037D01*
X929609Y-246727D01*
X928150Y-246262D01*
X926692Y-245487D01*
X925650Y-244402D01*
X925442Y-243317D01*
X925859Y-242232D01*
X926900Y-241457D01*
G01X938359Y-231692D02*
X938150Y-232002D01*
X937734D01*
X937525Y-231692D01*
X937734Y-231382D01*
X938150D01*
X938359Y-231692D01*
G01X932734Y-222237D02*
X931275Y-221152D01*
X930442Y-220222D01*
X930025Y-218982D01*
X930442Y-217897D01*
X931275Y-217122D01*
X932525Y-216502D01*
X933984Y-216347D01*
X935234Y-216502D01*
X936484Y-217122D01*
X937525Y-218052D01*
X937942Y-219137D01*
X937525Y-220377D01*
X936276Y-221462D01*
X934400Y-222082D01*
X932317Y-222237D01*
X929609Y-221927D01*
X928150Y-221462D01*
X926692Y-220687D01*
X925650Y-219602D01*
X925442Y-218517D01*
X925859Y-217432D01*
X926900Y-216657D01*
G01X936067Y-210302D02*
X937109Y-209372D01*
X937734Y-208287D01*
X937942Y-206892D01*
X937525Y-205497D01*
X936692Y-204412D01*
X935234Y-203637D01*
X933567Y-203482D01*
X931900Y-203792D01*
X930859Y-204567D01*
X930025Y-205652D01*
X929817Y-206737D01*
X930025Y-207822D01*
X930859Y-209217D01*
X925442Y-208752D01*
Y-204567D01*
G01X1020738Y-390296D02*
X1008238D01*
X1010738Y-392156D01*
G01X1020738D02*
Y-388436D01*
G01X1008238Y-377896D02*
X1008655Y-379136D01*
X1009696Y-380066D01*
X1010946Y-380686D01*
X1012613Y-381151D01*
X1014488Y-381306D01*
X1016363Y-381151D01*
X1018030Y-380686D01*
X1019280Y-380066D01*
X1020321Y-379136D01*
X1020738Y-377896D01*
X1020321Y-376656D01*
X1019280Y-375726D01*
X1018030Y-375106D01*
X1016363Y-374641D01*
X1014488Y-374486D01*
X1012613Y-374641D01*
X1010946Y-375106D01*
X1009696Y-375726D01*
X1008655Y-376656D01*
X1008238Y-377896D01*
G01X1020738Y-365496D02*
X1008238D01*
X1010738Y-367356D01*
G01X1020738D02*
Y-363636D01*
G01Y-351236D02*
X1008238D01*
X1017196Y-356971D01*
Y-349221D01*
G01X1020738Y-338836D02*
X1008238D01*
X1017196Y-344571D01*
Y-336821D01*
G01X1021155Y-328296D02*
X1020946Y-328606D01*
X1020530D01*
X1020321Y-328296D01*
X1020530Y-327986D01*
X1020946D01*
X1021155Y-328296D01*
G01X1020738Y-315896D02*
X1020530Y-314811D01*
X1019905Y-313571D01*
X1018863Y-312796D01*
X1017405Y-312486D01*
X1015947Y-312796D01*
X1014696Y-313726D01*
X1014071Y-315121D01*
Y-316671D01*
X1013655Y-317601D01*
X1012613Y-318376D01*
X1011155Y-318686D01*
X1009696Y-318221D01*
X1008655Y-317136D01*
X1008238Y-315896D01*
X1008655Y-314656D01*
X1009696Y-313571D01*
X1011155Y-313106D01*
X1012613Y-313416D01*
X1013655Y-314191D01*
X1014071Y-315121D01*
Y-316671D01*
X1014696Y-318066D01*
X1015947Y-318996D01*
X1017405Y-319306D01*
X1018863Y-318996D01*
X1019905Y-318221D01*
X1020530Y-316981D01*
X1020738Y-315896D01*
G01Y-303496D02*
X1020530Y-302411D01*
X1019905Y-301171D01*
X1018863Y-300396D01*
X1017405Y-300086D01*
X1015947Y-300396D01*
X1014696Y-301326D01*
X1014071Y-302721D01*
Y-304271D01*
X1013655Y-305201D01*
X1012613Y-305976D01*
X1011155Y-306286D01*
X1009696Y-305821D01*
X1008655Y-304736D01*
X1008238Y-303496D01*
X1008655Y-302256D01*
X1009696Y-301171D01*
X1011155Y-300706D01*
X1012613Y-301016D01*
X1013655Y-301791D01*
X1014071Y-302721D01*
Y-304271D01*
X1014696Y-305666D01*
X1015947Y-306596D01*
X1017405Y-306906D01*
X1018863Y-306596D01*
X1019905Y-305821D01*
X1020530Y-304581D01*
X1020738Y-303496D01*
G01X1010321Y-271841D02*
X1009072Y-270911D01*
X1008446Y-269826D01*
X1008238Y-268586D01*
X1008655Y-267036D01*
X1009696Y-265951D01*
X1010946Y-265641D01*
X1012197Y-265796D01*
X1013238Y-266416D01*
X1015321Y-269516D01*
X1016780Y-270911D01*
X1018863Y-271841D01*
X1020738Y-272151D01*
Y-265641D01*
G01X1018863Y-259906D02*
X1019905Y-258976D01*
X1020530Y-257891D01*
X1020738Y-256496D01*
X1020321Y-255101D01*
X1019488Y-254016D01*
X1018030Y-253241D01*
X1016363Y-253086D01*
X1014696Y-253396D01*
X1013655Y-254171D01*
X1012821Y-255256D01*
X1012613Y-256341D01*
X1012821Y-257426D01*
X1013655Y-258821D01*
X1008238Y-258356D01*
Y-254171D01*
G01X1020738Y-244406D02*
X1018030Y-244096D01*
X1015738Y-243631D01*
X1013655Y-243011D01*
X1011363Y-242236D01*
X1008238Y-240996D01*
Y-247196D01*
G01X1021155Y-231696D02*
X1020946Y-232006D01*
X1020530D01*
X1020321Y-231696D01*
X1020530Y-231386D01*
X1020946D01*
X1021155Y-231696D01*
G01X1015530Y-222241D02*
X1014071Y-221156D01*
X1013238Y-220226D01*
X1012821Y-218986D01*
X1013238Y-217901D01*
X1014071Y-217126D01*
X1015321Y-216506D01*
X1016780Y-216351D01*
X1018030Y-216506D01*
X1019280Y-217126D01*
X1020321Y-218056D01*
X1020738Y-219141D01*
X1020321Y-220381D01*
X1019072Y-221466D01*
X1017196Y-222086D01*
X1015113Y-222241D01*
X1012405Y-221931D01*
X1010946Y-221466D01*
X1009488Y-220691D01*
X1008446Y-219606D01*
X1008238Y-218521D01*
X1008655Y-217436D01*
X1009696Y-216661D01*
G01X1020738Y-206896D02*
X1020530Y-205811D01*
X1019905Y-204571D01*
X1018863Y-203796D01*
X1017405Y-203486D01*
X1015947Y-203796D01*
X1014696Y-204726D01*
X1014071Y-206121D01*
Y-207671D01*
X1013655Y-208601D01*
X1012613Y-209376D01*
X1011155Y-209686D01*
X1009696Y-209221D01*
X1008655Y-208136D01*
X1008238Y-206896D01*
X1008655Y-205656D01*
X1009696Y-204571D01*
X1011155Y-204106D01*
X1012613Y-204416D01*
X1013655Y-205191D01*
X1014071Y-206121D01*
Y-207671D01*
X1014696Y-209066D01*
X1015947Y-209996D01*
X1017405Y-210306D01*
X1018863Y-209996D01*
X1019905Y-209221D01*
X1020530Y-207981D01*
X1020738Y-206896D01*
G01X1015750Y2048253D02*
X1008250D01*
Y2050587D01*
X1008625Y2051333D01*
X1009125Y2051800D01*
X1010125Y2051987D01*
X1011125Y2051800D01*
X1011750Y2051240D01*
X1012125Y2050587D01*
Y2048253D01*
G01Y2050587D02*
X1015750Y2051987D01*
G01Y2059487D02*
Y2055753D01*
X1008250D01*
Y2059487D01*
G01X1011875Y2057993D02*
Y2055753D01*
G01X1008875Y2067173D02*
X1008500Y2066613D01*
X1008250Y2065960D01*
Y2065213D01*
X1008625Y2064373D01*
X1009250Y2063720D01*
X1010000Y2063253D01*
X1011250Y2062880D01*
X1012375Y2062787D01*
X1013500Y2062973D01*
X1014250Y2063253D01*
X1015000Y2063813D01*
X1015500Y2064467D01*
X1015750Y2065120D01*
Y2065773D01*
X1015500Y2066427D01*
X1015125Y2066987D01*
X1014625Y2067453D01*
G01X1015750Y2072620D02*
X1015625Y2071873D01*
X1015125Y2071220D01*
X1014375Y2070660D01*
X1013500Y2070287D01*
X1012500Y2070100D01*
X1011500D01*
X1010500Y2070287D01*
X1009625Y2070660D01*
X1008875Y2071220D01*
X1008375Y2071873D01*
X1008250Y2072620D01*
X1008375Y2073367D01*
X1008875Y2074020D01*
X1009625Y2074580D01*
X1010500Y2074953D01*
X1011500Y2075140D01*
X1012500D01*
X1013500Y2074953D01*
X1014375Y2074580D01*
X1015125Y2074020D01*
X1015625Y2073367D01*
X1015750Y2072620D01*
G01Y2077693D02*
X1008250D01*
X1014500Y2080120D01*
X1008250Y2082547D01*
X1015750D01*
G01Y2085193D02*
X1008250D01*
X1014500Y2087620D01*
X1008250Y2090047D01*
X1015750D01*
G01Y2096987D02*
Y2093253D01*
X1008250D01*
Y2096987D01*
G01X1011875Y2095493D02*
Y2093253D01*
G01X1015750Y2100473D02*
X1008250D01*
X1015750Y2104767D01*
X1008250D01*
G01X1015750Y2108067D02*
X1008250D01*
Y2109933D01*
X1008625Y2110680D01*
X1009125Y2111240D01*
X1009875Y2111707D01*
X1010750Y2112080D01*
X1012000Y2112173D01*
X1013250Y2112080D01*
X1014125Y2111707D01*
X1014875Y2111240D01*
X1015375Y2110680D01*
X1015750Y2109933D01*
Y2108067D01*
G01Y2119487D02*
Y2115753D01*
X1008250D01*
Y2119487D01*
G01X1011875Y2117993D02*
Y2115753D01*
G01X1015750Y2123067D02*
X1008250D01*
Y2124933D01*
X1008625Y2125680D01*
X1009125Y2126240D01*
X1009875Y2126707D01*
X1010750Y2127080D01*
X1012000Y2127173D01*
X1013250Y2127080D01*
X1014125Y2126707D01*
X1014875Y2126240D01*
X1015375Y2125680D01*
X1015750Y2124933D01*
Y2123067D01*
G01Y2138067D02*
X1008250D01*
Y2139933D01*
X1008625Y2140680D01*
X1009125Y2141240D01*
X1009875Y2141707D01*
X1010750Y2142080D01*
X1012000Y2142173D01*
X1013250Y2142080D01*
X1014125Y2141707D01*
X1014875Y2141240D01*
X1015375Y2140680D01*
X1015750Y2139933D01*
Y2138067D01*
G01Y2145753D02*
X1008250D01*
Y2148087D01*
X1008625Y2148833D01*
X1009125Y2149300D01*
X1010125Y2149487D01*
X1011125Y2149300D01*
X1011750Y2148740D01*
X1012125Y2148087D01*
Y2145753D01*
G01Y2148087D02*
X1015750Y2149487D01*
G01X1008250Y2154000D02*
Y2156240D01*
G01Y2155120D02*
X1015750D01*
G01Y2154000D02*
Y2156240D01*
G01X1008250Y2160753D02*
X1015750D01*
Y2164487D01*
G01X1008250Y2168253D02*
X1015750D01*
Y2171987D01*
G01X1014750Y2183160D02*
X1015375Y2183907D01*
X1015750Y2184747D01*
Y2185493D01*
X1015375Y2186240D01*
X1014750Y2186800D01*
X1013875Y2187080D01*
X1013000Y2186893D01*
X1012250Y2186427D01*
X1011750Y2185587D01*
X1011500Y2184467D01*
X1011000Y2183813D01*
X1010125Y2183533D01*
X1009250Y2183720D01*
X1008625Y2184187D01*
X1008250Y2184840D01*
Y2185493D01*
X1008500Y2186147D01*
X1009125Y2186707D01*
G01X1008250Y2191500D02*
Y2193740D01*
G01Y2192620D02*
X1015750D01*
G01Y2191500D02*
Y2193740D01*
G01X1008250Y2198347D02*
Y2201893D01*
X1015750Y2198347D01*
Y2201893D01*
G01Y2209487D02*
Y2205753D01*
X1008250D01*
Y2209487D01*
G01X1011875Y2207993D02*
Y2205753D01*
G01X1015750Y2220847D02*
X1008250D01*
Y2224393D01*
G01X1011875Y2223087D02*
Y2220847D01*
G01X1015750Y2230120D02*
X1015625Y2229373D01*
X1015125Y2228720D01*
X1014375Y2228160D01*
X1013500Y2227787D01*
X1012500Y2227600D01*
X1011500D01*
X1010500Y2227787D01*
X1009625Y2228160D01*
X1008875Y2228720D01*
X1008375Y2229373D01*
X1008250Y2230120D01*
X1008375Y2230867D01*
X1008875Y2231520D01*
X1009625Y2232080D01*
X1010500Y2232453D01*
X1011500Y2232640D01*
X1012500D01*
X1013500Y2232453D01*
X1014375Y2232080D01*
X1015125Y2231520D01*
X1015625Y2230867D01*
X1015750Y2230120D01*
G01Y2235753D02*
X1008250D01*
Y2238087D01*
X1008625Y2238833D01*
X1009125Y2239300D01*
X1010125Y2239487D01*
X1011125Y2239300D01*
X1011750Y2238740D01*
X1012125Y2238087D01*
Y2235753D01*
G01Y2238087D02*
X1015750Y2239487D01*
G01Y2252620D02*
X1008250D01*
X1009750Y2251500D01*
G01X1015750D02*
Y2253740D01*
G01X1016000Y2260120D02*
X1015875Y2259933D01*
X1015625D01*
X1015500Y2260120D01*
X1015625Y2260307D01*
X1015875D01*
X1016000Y2260120D01*
G01X1008250Y2267620D02*
X1008500Y2266873D01*
X1009125Y2266313D01*
X1009875Y2265940D01*
X1010875Y2265660D01*
X1012000Y2265567D01*
X1013125Y2265660D01*
X1014125Y2265940D01*
X1014875Y2266313D01*
X1015500Y2266873D01*
X1015750Y2267620D01*
X1015500Y2268367D01*
X1014875Y2268927D01*
X1014125Y2269300D01*
X1013125Y2269580D01*
X1012000Y2269673D01*
X1010875Y2269580D01*
X1009875Y2269300D01*
X1009125Y2268927D01*
X1008500Y2268367D01*
X1008250Y2267620D01*
G01X1009500Y2273347D02*
X1008750Y2273907D01*
X1008375Y2274560D01*
X1008250Y2275307D01*
X1008500Y2276240D01*
X1009125Y2276893D01*
X1009875Y2277080D01*
X1010625Y2276987D01*
X1011250Y2276613D01*
X1012500Y2274747D01*
X1013375Y2273907D01*
X1014625Y2273347D01*
X1015750Y2273160D01*
Y2277080D01*
G01Y2280193D02*
X1008250D01*
X1014500Y2282620D01*
X1008250Y2285047D01*
X1015750D01*
G01Y2287693D02*
X1008250D01*
X1014500Y2290120D01*
X1008250Y2292547D01*
X1015750D01*
G01Y2303347D02*
X1008250D01*
Y2306893D01*
G01X1011875Y2305587D02*
Y2303347D01*
G01X1008250Y2311500D02*
Y2313740D01*
G01Y2312620D02*
X1015750D01*
G01Y2311500D02*
Y2313740D01*
G01Y2317973D02*
X1008250D01*
X1015750Y2322267D01*
X1008250D01*
G01Y2326500D02*
Y2328740D01*
G01Y2327620D02*
X1015750D01*
G01Y2326500D02*
Y2328740D01*
G01X1014750Y2333160D02*
X1015375Y2333907D01*
X1015750Y2334747D01*
Y2335493D01*
X1015375Y2336240D01*
X1014750Y2336800D01*
X1013875Y2337080D01*
X1013000Y2336893D01*
X1012250Y2336427D01*
X1011750Y2335587D01*
X1011500Y2334467D01*
X1011000Y2333813D01*
X1010125Y2333533D01*
X1009250Y2333720D01*
X1008625Y2334187D01*
X1008250Y2334840D01*
Y2335493D01*
X1008500Y2336147D01*
X1009125Y2336707D01*
G01X1015750Y2340660D02*
X1008250D01*
G01Y2344580D02*
X1015750D01*
G01X1012000D02*
Y2340660D01*
G01X1015750Y2351987D02*
Y2348253D01*
X1008250D01*
Y2351987D01*
G01X1011875Y2350493D02*
Y2348253D01*
G01X1015750Y2355567D02*
X1008250D01*
Y2357433D01*
X1008625Y2358180D01*
X1009125Y2358740D01*
X1009875Y2359207D01*
X1010750Y2359580D01*
X1012000Y2359673D01*
X1013250Y2359580D01*
X1014125Y2359207D01*
X1014875Y2358740D01*
X1015375Y2358180D01*
X1015750Y2357433D01*
Y2355567D01*
G01Y2370753D02*
X1008250D01*
Y2372993D01*
X1008625Y2373740D01*
X1009500Y2374300D01*
X1010500Y2374487D01*
X1011500Y2374300D01*
X1012250Y2373833D01*
X1012625Y2372993D01*
Y2370753D01*
G01X1008250Y2380120D02*
X1015750D01*
G01X1008250Y2377973D02*
Y2382267D01*
G01X1015750Y2385660D02*
X1008250D01*
G01Y2389580D02*
X1015750D01*
G01X1012000D02*
Y2385660D01*
G01X1008250Y2401500D02*
Y2403740D01*
G01Y2402620D02*
X1015750D01*
G01Y2401500D02*
Y2403740D01*
G01X1014750Y2408160D02*
X1015375Y2408907D01*
X1015750Y2409747D01*
Y2410493D01*
X1015375Y2411240D01*
X1014750Y2411800D01*
X1013875Y2412080D01*
X1013000Y2411893D01*
X1012250Y2411427D01*
X1011750Y2410587D01*
X1011500Y2409467D01*
X1011000Y2408813D01*
X1010125Y2408533D01*
X1009250Y2408720D01*
X1008625Y2409187D01*
X1008250Y2409840D01*
Y2410493D01*
X1008500Y2411147D01*
X1009125Y2411707D01*
G01X1015750Y2425120D02*
X1008250D01*
X1009750Y2424000D01*
G01X1015750D02*
Y2426240D01*
G01X1016000Y2432620D02*
X1015875Y2432433D01*
X1015625D01*
X1015500Y2432620D01*
X1015625Y2432807D01*
X1015875D01*
X1016000Y2432620D01*
G01X1015750Y2440120D02*
X1008250D01*
X1009750Y2439000D01*
G01X1015750D02*
Y2441240D01*
G01X1014625Y2445567D02*
X1015250Y2446127D01*
X1015625Y2446780D01*
X1015750Y2447620D01*
X1015500Y2448460D01*
X1015000Y2449113D01*
X1014125Y2449580D01*
X1013125Y2449673D01*
X1012125Y2449487D01*
X1011500Y2449020D01*
X1011000Y2448367D01*
X1010875Y2447713D01*
X1011000Y2447060D01*
X1011500Y2446220D01*
X1008250Y2446500D01*
Y2449020D01*
G01X1013250Y2454093D02*
Y2456333D01*
G01X1011625Y2455120D02*
X1014875D01*
G01X1016000Y2460940D02*
X1008250Y2464300D01*
G01X1013250Y2468907D02*
Y2471333D01*
G01X1008250Y2477620D02*
X1008500Y2476873D01*
X1009125Y2476313D01*
X1009875Y2475940D01*
X1010875Y2475660D01*
X1012000Y2475567D01*
X1013125Y2475660D01*
X1014125Y2475940D01*
X1014875Y2476313D01*
X1015500Y2476873D01*
X1015750Y2477620D01*
X1015500Y2478367D01*
X1014875Y2478927D01*
X1014125Y2479300D01*
X1013125Y2479580D01*
X1012000Y2479673D01*
X1010875Y2479580D01*
X1009875Y2479300D01*
X1009125Y2478927D01*
X1008500Y2478367D01*
X1008250Y2477620D01*
G01X1016000Y2485120D02*
X1015875Y2484933D01*
X1015625D01*
X1015500Y2485120D01*
X1015625Y2485307D01*
X1015875D01*
X1016000Y2485120D01*
G01X1008250Y2492620D02*
X1008500Y2491873D01*
X1009125Y2491313D01*
X1009875Y2490940D01*
X1010875Y2490660D01*
X1012000Y2490567D01*
X1013125Y2490660D01*
X1014125Y2490940D01*
X1014875Y2491313D01*
X1015500Y2491873D01*
X1015750Y2492620D01*
X1015500Y2493367D01*
X1014875Y2493927D01*
X1014125Y2494300D01*
X1013125Y2494580D01*
X1012000Y2494673D01*
X1010875Y2494580D01*
X1009875Y2494300D01*
X1009125Y2493927D01*
X1008500Y2493367D01*
X1008250Y2492620D01*
G01X1009500Y2498347D02*
X1008750Y2498907D01*
X1008375Y2499560D01*
X1008250Y2500307D01*
X1008500Y2501240D01*
X1009125Y2501893D01*
X1009875Y2502080D01*
X1010625Y2501987D01*
X1011250Y2501613D01*
X1012500Y2499747D01*
X1013375Y2498907D01*
X1014625Y2498347D01*
X1015750Y2498160D01*
Y2502080D01*
G01X1014625Y2505567D02*
X1015250Y2506127D01*
X1015625Y2506780D01*
X1015750Y2507620D01*
X1015500Y2508460D01*
X1015000Y2509113D01*
X1014125Y2509580D01*
X1013125Y2509673D01*
X1012125Y2509487D01*
X1011500Y2509020D01*
X1011000Y2508367D01*
X1010875Y2507713D01*
X1011000Y2507060D01*
X1011500Y2506220D01*
X1008250Y2506500D01*
Y2509020D01*
G01X1015750Y2512693D02*
X1008250D01*
X1014500Y2515120D01*
X1008250Y2517547D01*
X1015750D01*
G01Y2520193D02*
X1008250D01*
X1014500Y2522620D01*
X1008250Y2525047D01*
X1015750D01*
G01X1044038Y-390085D02*
X1031538D01*
X1034038Y-391945D01*
G01X1044038D02*
Y-388225D01*
G01X1031538Y-377685D02*
X1031955Y-378925D01*
X1032996Y-379855D01*
X1034246Y-380475D01*
X1035913Y-380940D01*
X1037788Y-381095D01*
X1039663Y-380940D01*
X1041330Y-380475D01*
X1042580Y-379855D01*
X1043621Y-378925D01*
X1044038Y-377685D01*
X1043621Y-376445D01*
X1042580Y-375515D01*
X1041330Y-374895D01*
X1039663Y-374430D01*
X1037788Y-374275D01*
X1035913Y-374430D01*
X1034246Y-374895D01*
X1032996Y-375515D01*
X1031955Y-376445D01*
X1031538Y-377685D01*
G01X1044038Y-363425D02*
X1031538D01*
X1040496Y-369160D01*
Y-361410D01*
G01X1042163Y-356295D02*
X1043205Y-355365D01*
X1043830Y-354280D01*
X1044038Y-352885D01*
X1043621Y-351490D01*
X1042788Y-350405D01*
X1041330Y-349630D01*
X1039663Y-349475D01*
X1037996Y-349785D01*
X1036955Y-350560D01*
X1036121Y-351645D01*
X1035913Y-352730D01*
X1036121Y-353815D01*
X1036955Y-355210D01*
X1031538Y-354745D01*
Y-350560D01*
G01X1044038Y-340485D02*
X1043830Y-339400D01*
X1043205Y-338160D01*
X1042163Y-337385D01*
X1040705Y-337075D01*
X1039247Y-337385D01*
X1037996Y-338315D01*
X1037371Y-339710D01*
Y-341260D01*
X1036955Y-342190D01*
X1035913Y-342965D01*
X1034455Y-343275D01*
X1032996Y-342810D01*
X1031955Y-341725D01*
X1031538Y-340485D01*
X1031955Y-339245D01*
X1032996Y-338160D01*
X1034455Y-337695D01*
X1035913Y-338005D01*
X1036955Y-338780D01*
X1037371Y-339710D01*
Y-341260D01*
X1037996Y-342655D01*
X1039247Y-343585D01*
X1040705Y-343895D01*
X1042163Y-343585D01*
X1043205Y-342810D01*
X1043830Y-341570D01*
X1044038Y-340485D01*
G01X1044455Y-328085D02*
X1044246Y-328395D01*
X1043830D01*
X1043621Y-328085D01*
X1043830Y-327775D01*
X1044246D01*
X1044455Y-328085D01*
G01X1038830Y-318630D02*
X1037371Y-317545D01*
X1036538Y-316615D01*
X1036121Y-315375D01*
X1036538Y-314290D01*
X1037371Y-313515D01*
X1038621Y-312895D01*
X1040080Y-312740D01*
X1041330Y-312895D01*
X1042580Y-313515D01*
X1043621Y-314445D01*
X1044038Y-315530D01*
X1043621Y-316770D01*
X1042372Y-317855D01*
X1040496Y-318475D01*
X1038413Y-318630D01*
X1035705Y-318320D01*
X1034246Y-317855D01*
X1032788Y-317080D01*
X1031746Y-315995D01*
X1031538Y-314910D01*
X1031955Y-313825D01*
X1032996Y-313050D01*
G01X1042163Y-306695D02*
X1043205Y-305765D01*
X1043830Y-304680D01*
X1044038Y-303285D01*
X1043621Y-301890D01*
X1042788Y-300805D01*
X1041330Y-300030D01*
X1039663Y-299875D01*
X1037996Y-300185D01*
X1036955Y-300960D01*
X1036121Y-302045D01*
X1035913Y-303130D01*
X1036121Y-304215D01*
X1036955Y-305610D01*
X1031538Y-305145D01*
Y-300960D01*
G01X1033621Y-271630D02*
X1032372Y-270700D01*
X1031746Y-269615D01*
X1031538Y-268375D01*
X1031955Y-266825D01*
X1032996Y-265740D01*
X1034246Y-265430D01*
X1035497Y-265585D01*
X1036538Y-266205D01*
X1038621Y-269305D01*
X1040080Y-270700D01*
X1042163Y-271630D01*
X1044038Y-271940D01*
Y-265430D01*
G01X1038830Y-259230D02*
X1037371Y-258145D01*
X1036538Y-257215D01*
X1036121Y-255975D01*
X1036538Y-254890D01*
X1037371Y-254115D01*
X1038621Y-253495D01*
X1040080Y-253340D01*
X1041330Y-253495D01*
X1042580Y-254115D01*
X1043621Y-255045D01*
X1044038Y-256130D01*
X1043621Y-257370D01*
X1042372Y-258455D01*
X1040496Y-259075D01*
X1038413Y-259230D01*
X1035705Y-258920D01*
X1034246Y-258455D01*
X1032788Y-257680D01*
X1031746Y-256595D01*
X1031538Y-255510D01*
X1031955Y-254425D01*
X1032996Y-253650D01*
G01X1042163Y-247295D02*
X1043205Y-246365D01*
X1043830Y-245280D01*
X1044038Y-243885D01*
X1043621Y-242490D01*
X1042788Y-241405D01*
X1041330Y-240630D01*
X1039663Y-240475D01*
X1037996Y-240785D01*
X1036955Y-241560D01*
X1036121Y-242645D01*
X1035913Y-243730D01*
X1036121Y-244815D01*
X1036955Y-246210D01*
X1031538Y-245745D01*
Y-241560D01*
G01X1044455Y-231485D02*
X1044246Y-231795D01*
X1043830D01*
X1043621Y-231485D01*
X1043830Y-231175D01*
X1044246D01*
X1044455Y-231485D01*
G01X1038830Y-222030D02*
X1037371Y-220945D01*
X1036538Y-220015D01*
X1036121Y-218775D01*
X1036538Y-217690D01*
X1037371Y-216915D01*
X1038621Y-216295D01*
X1040080Y-216140D01*
X1041330Y-216295D01*
X1042580Y-216915D01*
X1043621Y-217845D01*
X1044038Y-218930D01*
X1043621Y-220170D01*
X1042372Y-221255D01*
X1040496Y-221875D01*
X1038413Y-222030D01*
X1035705Y-221720D01*
X1034246Y-221255D01*
X1032788Y-220480D01*
X1031746Y-219395D01*
X1031538Y-218310D01*
X1031955Y-217225D01*
X1032996Y-216450D01*
G01X1042163Y-210095D02*
X1043205Y-209165D01*
X1043830Y-208080D01*
X1044038Y-206685D01*
X1043621Y-205290D01*
X1042788Y-204205D01*
X1041330Y-203430D01*
X1039663Y-203275D01*
X1037996Y-203585D01*
X1036955Y-204360D01*
X1036121Y-205445D01*
X1035913Y-206530D01*
X1036121Y-207615D01*
X1036955Y-209010D01*
X1031538Y-208545D01*
Y-204360D01*
G01X1063908Y-390295D02*
X1051408D01*
X1053908Y-392155D01*
G01X1063908D02*
Y-388435D01*
G01X1051408Y-377895D02*
X1051825Y-379135D01*
X1052866Y-380065D01*
X1054116Y-380685D01*
X1055783Y-381150D01*
X1057658Y-381305D01*
X1059533Y-381150D01*
X1061200Y-380685D01*
X1062450Y-380065D01*
X1063491Y-379135D01*
X1063908Y-377895D01*
X1063491Y-376655D01*
X1062450Y-375725D01*
X1061200Y-375105D01*
X1059533Y-374640D01*
X1057658Y-374485D01*
X1055783Y-374640D01*
X1054116Y-375105D01*
X1052866Y-375725D01*
X1051825Y-376655D01*
X1051408Y-377895D01*
G01X1062033Y-368905D02*
X1063075Y-367975D01*
X1063700Y-366890D01*
X1063908Y-365495D01*
X1063491Y-364100D01*
X1062658Y-363015D01*
X1061200Y-362240D01*
X1059533Y-362085D01*
X1057866Y-362395D01*
X1056825Y-363170D01*
X1055991Y-364255D01*
X1055783Y-365340D01*
X1055991Y-366425D01*
X1056825Y-367820D01*
X1051408Y-367355D01*
Y-363170D01*
G01X1063908Y-353405D02*
X1061200Y-353095D01*
X1058908Y-352630D01*
X1056825Y-352010D01*
X1054533Y-351235D01*
X1051408Y-349995D01*
Y-356195D01*
G01X1058700Y-343640D02*
X1057241Y-342555D01*
X1056408Y-341625D01*
X1055991Y-340385D01*
X1056408Y-339300D01*
X1057241Y-338525D01*
X1058491Y-337905D01*
X1059950Y-337750D01*
X1061200Y-337905D01*
X1062450Y-338525D01*
X1063491Y-339455D01*
X1063908Y-340540D01*
X1063491Y-341780D01*
X1062242Y-342865D01*
X1060366Y-343485D01*
X1058283Y-343640D01*
X1055575Y-343330D01*
X1054116Y-342865D01*
X1052658Y-342090D01*
X1051616Y-341005D01*
X1051408Y-339920D01*
X1051825Y-338835D01*
X1052866Y-338060D01*
G01X1064325Y-328295D02*
X1064116Y-328605D01*
X1063700D01*
X1063491Y-328295D01*
X1063700Y-327985D01*
X1064116D01*
X1064325Y-328295D01*
G01X1062033Y-319305D02*
X1063075Y-318375D01*
X1063700Y-317290D01*
X1063908Y-315895D01*
X1063491Y-314500D01*
X1062658Y-313415D01*
X1061200Y-312640D01*
X1059533Y-312485D01*
X1057866Y-312795D01*
X1056825Y-313570D01*
X1055991Y-314655D01*
X1055783Y-315740D01*
X1055991Y-316825D01*
X1056825Y-318220D01*
X1051408Y-317755D01*
Y-313570D01*
G01X1063908Y-303495D02*
X1063700Y-302410D01*
X1063075Y-301170D01*
X1062033Y-300395D01*
X1060575Y-300085D01*
X1059117Y-300395D01*
X1057866Y-301325D01*
X1057241Y-302720D01*
Y-304270D01*
X1056825Y-305200D01*
X1055783Y-305975D01*
X1054325Y-306285D01*
X1052866Y-305820D01*
X1051825Y-304735D01*
X1051408Y-303495D01*
X1051825Y-302255D01*
X1052866Y-301170D01*
X1054325Y-300705D01*
X1055783Y-301015D01*
X1056825Y-301790D01*
X1057241Y-302720D01*
Y-304270D01*
X1057866Y-305665D01*
X1059117Y-306595D01*
X1060575Y-306905D01*
X1062033Y-306595D01*
X1063075Y-305820D01*
X1063700Y-304580D01*
X1063908Y-303495D01*
G01X1053491Y-271840D02*
X1052242Y-270910D01*
X1051616Y-269825D01*
X1051408Y-268585D01*
X1051825Y-267035D01*
X1052866Y-265950D01*
X1054116Y-265640D01*
X1055367Y-265795D01*
X1056408Y-266415D01*
X1058491Y-269515D01*
X1059950Y-270910D01*
X1062033Y-271840D01*
X1063908Y-272150D01*
Y-265640D01*
G01X1058700Y-259440D02*
X1057241Y-258355D01*
X1056408Y-257425D01*
X1055991Y-256185D01*
X1056408Y-255100D01*
X1057241Y-254325D01*
X1058491Y-253705D01*
X1059950Y-253550D01*
X1061200Y-253705D01*
X1062450Y-254325D01*
X1063491Y-255255D01*
X1063908Y-256340D01*
X1063491Y-257580D01*
X1062242Y-258665D01*
X1060366Y-259285D01*
X1058283Y-259440D01*
X1055575Y-259130D01*
X1054116Y-258665D01*
X1052658Y-257890D01*
X1051616Y-256805D01*
X1051408Y-255720D01*
X1051825Y-254635D01*
X1052866Y-253860D01*
G01X1063908Y-244095D02*
X1063700Y-243010D01*
X1063075Y-241770D01*
X1062033Y-240995D01*
X1060575Y-240685D01*
X1059117Y-240995D01*
X1057866Y-241925D01*
X1057241Y-243320D01*
Y-244870D01*
X1056825Y-245800D01*
X1055783Y-246575D01*
X1054325Y-246885D01*
X1052866Y-246420D01*
X1051825Y-245335D01*
X1051408Y-244095D01*
X1051825Y-242855D01*
X1052866Y-241770D01*
X1054325Y-241305D01*
X1055783Y-241615D01*
X1056825Y-242390D01*
X1057241Y-243320D01*
Y-244870D01*
X1057866Y-246265D01*
X1059117Y-247195D01*
X1060575Y-247505D01*
X1062033Y-247195D01*
X1063075Y-246420D01*
X1063700Y-245180D01*
X1063908Y-244095D01*
G01X1064325Y-231695D02*
X1064116Y-232005D01*
X1063700D01*
X1063491Y-231695D01*
X1063700Y-231385D01*
X1064116D01*
X1064325Y-231695D01*
G01X1058700Y-222240D02*
X1057241Y-221155D01*
X1056408Y-220225D01*
X1055991Y-218985D01*
X1056408Y-217900D01*
X1057241Y-217125D01*
X1058491Y-216505D01*
X1059950Y-216350D01*
X1061200Y-216505D01*
X1062450Y-217125D01*
X1063491Y-218055D01*
X1063908Y-219140D01*
X1063491Y-220380D01*
X1062242Y-221465D01*
X1060366Y-222085D01*
X1058283Y-222240D01*
X1055575Y-221930D01*
X1054116Y-221465D01*
X1052658Y-220690D01*
X1051616Y-219605D01*
X1051408Y-218520D01*
X1051825Y-217435D01*
X1052866Y-216660D01*
G01X1062033Y-210305D02*
X1063075Y-209375D01*
X1063700Y-208290D01*
X1063908Y-206895D01*
X1063491Y-205500D01*
X1062658Y-204415D01*
X1061200Y-203640D01*
X1059533Y-203485D01*
X1057866Y-203795D01*
X1056825Y-204570D01*
X1055991Y-205655D01*
X1055783Y-206740D01*
X1055991Y-207825D01*
X1056825Y-209220D01*
X1051408Y-208755D01*
Y-204570D01*
G01X1100324Y-390294D02*
X1087824D01*
X1090324Y-392154D01*
G01X1100324D02*
Y-388434D01*
G01X1087824Y-377894D02*
X1088241Y-379134D01*
X1089282Y-380064D01*
X1090532Y-380684D01*
X1092199Y-381149D01*
X1094074Y-381304D01*
X1095949Y-381149D01*
X1097616Y-380684D01*
X1098866Y-380064D01*
X1099907Y-379134D01*
X1100324Y-377894D01*
X1099907Y-376654D01*
X1098866Y-375724D01*
X1097616Y-375104D01*
X1095949Y-374639D01*
X1094074Y-374484D01*
X1092199Y-374639D01*
X1090532Y-375104D01*
X1089282Y-375724D01*
X1088241Y-376654D01*
X1087824Y-377894D01*
G01X1098866Y-368129D02*
X1099907Y-367044D01*
X1100324Y-365804D01*
X1099907Y-364564D01*
X1098658Y-363479D01*
X1096782Y-362704D01*
X1094907Y-362394D01*
X1092616D01*
X1090741Y-362704D01*
X1089074Y-363479D01*
X1088241Y-364409D01*
X1087824Y-365494D01*
X1088241Y-366734D01*
X1089074Y-367664D01*
X1090324Y-368284D01*
X1091991Y-368594D01*
X1093449Y-368284D01*
X1094907Y-367509D01*
X1095741Y-366579D01*
X1095949Y-365494D01*
X1095533Y-364254D01*
X1094491Y-363324D01*
X1092616Y-362394D01*
G01X1100324Y-351234D02*
X1087824D01*
X1096782Y-356969D01*
Y-349219D01*
G01X1087824Y-340694D02*
X1088241Y-341934D01*
X1089282Y-342864D01*
X1090532Y-343484D01*
X1092199Y-343949D01*
X1094074Y-344104D01*
X1095949Y-343949D01*
X1097616Y-343484D01*
X1098866Y-342864D01*
X1099907Y-341934D01*
X1100324Y-340694D01*
X1099907Y-339454D01*
X1098866Y-338524D01*
X1097616Y-337904D01*
X1095949Y-337439D01*
X1094074Y-337284D01*
X1092199Y-337439D01*
X1090532Y-337904D01*
X1089282Y-338524D01*
X1088241Y-339454D01*
X1087824Y-340694D01*
G01X1100741Y-328294D02*
X1100532Y-328604D01*
X1100116D01*
X1099907Y-328294D01*
X1100116Y-327984D01*
X1100532D01*
X1100741Y-328294D01*
G01X1100324Y-316204D02*
X1097616Y-315894D01*
X1095324Y-315429D01*
X1093241Y-314809D01*
X1090949Y-314034D01*
X1087824Y-312794D01*
Y-318994D01*
G01X1100324Y-301634D02*
X1087824D01*
X1096782Y-307369D01*
Y-299619D01*
G01X1089907Y-271839D02*
X1088658Y-270909D01*
X1088032Y-269824D01*
X1087824Y-268584D01*
X1088241Y-267034D01*
X1089282Y-265949D01*
X1090532Y-265639D01*
X1091783Y-265794D01*
X1092824Y-266414D01*
X1094907Y-269514D01*
X1096366Y-270909D01*
X1098449Y-271839D01*
X1100324Y-272149D01*
Y-265639D01*
G01Y-256804D02*
X1097616Y-256494D01*
X1095324Y-256029D01*
X1093241Y-255409D01*
X1090949Y-254634D01*
X1087824Y-253394D01*
Y-259594D01*
G01X1100324Y-244404D02*
X1097616Y-244094D01*
X1095324Y-243629D01*
X1093241Y-243009D01*
X1090949Y-242234D01*
X1087824Y-240994D01*
Y-247194D01*
G01X1100741Y-231694D02*
X1100532Y-232004D01*
X1100116D01*
X1099907Y-231694D01*
X1100116Y-231384D01*
X1100532D01*
X1100741Y-231694D01*
G01X1100324Y-219294D02*
X1100116Y-218209D01*
X1099491Y-216969D01*
X1098449Y-216194D01*
X1096991Y-215884D01*
X1095533Y-216194D01*
X1094282Y-217124D01*
X1093657Y-218519D01*
Y-220069D01*
X1093241Y-220999D01*
X1092199Y-221774D01*
X1090741Y-222084D01*
X1089282Y-221619D01*
X1088241Y-220534D01*
X1087824Y-219294D01*
X1088241Y-218054D01*
X1089282Y-216969D01*
X1090741Y-216504D01*
X1092199Y-216814D01*
X1093241Y-217589D01*
X1093657Y-218519D01*
Y-220069D01*
X1094282Y-221464D01*
X1095533Y-222394D01*
X1096991Y-222704D01*
X1098449Y-222394D01*
X1099491Y-221619D01*
X1100116Y-220379D01*
X1100324Y-219294D01*
G01X1098866Y-209529D02*
X1099907Y-208444D01*
X1100324Y-207204D01*
X1099907Y-205964D01*
X1098658Y-204879D01*
X1096782Y-204104D01*
X1094907Y-203794D01*
X1092616D01*
X1090741Y-204104D01*
X1089074Y-204879D01*
X1088241Y-205809D01*
X1087824Y-206894D01*
X1088241Y-208134D01*
X1089074Y-209064D01*
X1090324Y-209684D01*
X1091991Y-209994D01*
X1093449Y-209684D01*
X1094907Y-208909D01*
X1095741Y-207979D01*
X1095949Y-206894D01*
X1095533Y-205654D01*
X1094491Y-204724D01*
X1092616Y-203794D01*
G01X1095030Y636327D02*
Y643827D01*
X1099324Y636327D01*
Y643827D01*
G01X1102810Y636327D02*
Y643827D01*
X1105050D01*
X1105797Y643452D01*
X1106357Y642577D01*
X1106544Y641577D01*
X1106357Y640577D01*
X1105890Y639827D01*
X1105050Y639452D01*
X1102810D01*
G01X1112177Y643827D02*
Y636327D01*
G01X1110030Y643827D02*
X1114324D01*
G01X1117717Y636327D02*
Y643827D01*
G01X1121637D02*
Y636327D01*
G01Y640077D02*
X1117717D01*
G01X1143318Y-390297D02*
X1130818D01*
X1133318Y-392157D01*
G01X1143318D02*
Y-388437D01*
G01Y-377897D02*
X1130818D01*
X1133318Y-379757D01*
G01X1143318D02*
Y-376037D01*
G01X1141443Y-368907D02*
X1142485Y-367977D01*
X1143110Y-366892D01*
X1143318Y-365497D01*
X1142901Y-364102D01*
X1142068Y-363017D01*
X1140610Y-362242D01*
X1138943Y-362087D01*
X1137276Y-362397D01*
X1136235Y-363172D01*
X1135401Y-364257D01*
X1135193Y-365342D01*
X1135401Y-366427D01*
X1136235Y-367822D01*
X1130818Y-367357D01*
Y-363172D01*
G01X1140818Y-356507D02*
X1142277Y-355577D01*
X1143110Y-354337D01*
X1143318Y-352942D01*
X1143110Y-351702D01*
X1142068Y-350462D01*
X1140818Y-349687D01*
X1139568Y-349532D01*
X1138110Y-349842D01*
X1137068Y-350927D01*
X1136651Y-352012D01*
Y-353407D01*
G01Y-352012D02*
X1136026Y-351082D01*
X1134985Y-350307D01*
X1133735Y-349997D01*
X1132485Y-350307D01*
X1131443Y-351082D01*
X1130818Y-352477D01*
X1131026Y-353872D01*
X1131860Y-355267D01*
G01X1143318Y-338837D02*
X1130818D01*
X1139776Y-344572D01*
Y-336822D01*
G01X1143735Y-328297D02*
X1143526Y-328607D01*
X1143110D01*
X1142901Y-328297D01*
X1143110Y-327987D01*
X1143526D01*
X1143735Y-328297D01*
G01X1141443Y-319307D02*
X1142485Y-318377D01*
X1143110Y-317292D01*
X1143318Y-315897D01*
X1142901Y-314502D01*
X1142068Y-313417D01*
X1140610Y-312642D01*
X1138943Y-312487D01*
X1137276Y-312797D01*
X1136235Y-313572D01*
X1135401Y-314657D01*
X1135193Y-315742D01*
X1135401Y-316827D01*
X1136235Y-318222D01*
X1130818Y-317757D01*
Y-313572D01*
G01X1140818Y-306907D02*
X1142277Y-305977D01*
X1143110Y-304737D01*
X1143318Y-303342D01*
X1143110Y-302102D01*
X1142068Y-300862D01*
X1140818Y-300087D01*
X1139568Y-299932D01*
X1138110Y-300242D01*
X1137068Y-301327D01*
X1136651Y-302412D01*
Y-303807D01*
G01Y-302412D02*
X1136026Y-301482D01*
X1134985Y-300707D01*
X1133735Y-300397D01*
X1132485Y-300707D01*
X1131443Y-301482D01*
X1130818Y-302877D01*
X1131026Y-304272D01*
X1131860Y-305667D01*
G01X1132901Y-271842D02*
X1131652Y-270912D01*
X1131026Y-269827D01*
X1130818Y-268587D01*
X1131235Y-267037D01*
X1132276Y-265952D01*
X1133526Y-265642D01*
X1134777Y-265797D01*
X1135818Y-266417D01*
X1137901Y-269517D01*
X1139360Y-270912D01*
X1141443Y-271842D01*
X1143318Y-272152D01*
Y-265642D01*
G01X1141860Y-259132D02*
X1142901Y-258047D01*
X1143318Y-256807D01*
X1142901Y-255567D01*
X1141652Y-254482D01*
X1139776Y-253707D01*
X1137901Y-253397D01*
X1135610D01*
X1133735Y-253707D01*
X1132068Y-254482D01*
X1131235Y-255412D01*
X1130818Y-256497D01*
X1131235Y-257737D01*
X1132068Y-258667D01*
X1133318Y-259287D01*
X1134985Y-259597D01*
X1136443Y-259287D01*
X1137901Y-258512D01*
X1138735Y-257582D01*
X1138943Y-256497D01*
X1138527Y-255257D01*
X1137485Y-254327D01*
X1135610Y-253397D01*
G01X1132901Y-247042D02*
X1131652Y-246112D01*
X1131026Y-245027D01*
X1130818Y-243787D01*
X1131235Y-242237D01*
X1132276Y-241152D01*
X1133526Y-240842D01*
X1134777Y-240997D01*
X1135818Y-241617D01*
X1137901Y-244717D01*
X1139360Y-246112D01*
X1141443Y-247042D01*
X1143318Y-247352D01*
Y-240842D01*
G01X1143735Y-231697D02*
X1143526Y-232007D01*
X1143110D01*
X1142901Y-231697D01*
X1143110Y-231387D01*
X1143526D01*
X1143735Y-231697D01*
G01X1141860Y-221932D02*
X1142901Y-220847D01*
X1143318Y-219607D01*
X1142901Y-218367D01*
X1141652Y-217282D01*
X1139776Y-216507D01*
X1137901Y-216197D01*
X1135610D01*
X1133735Y-216507D01*
X1132068Y-217282D01*
X1131235Y-218212D01*
X1130818Y-219297D01*
X1131235Y-220537D01*
X1132068Y-221467D01*
X1133318Y-222087D01*
X1134985Y-222397D01*
X1136443Y-222087D01*
X1137901Y-221312D01*
X1138735Y-220382D01*
X1138943Y-219297D01*
X1138527Y-218057D01*
X1137485Y-217127D01*
X1135610Y-216197D01*
G01X1143318Y-206897D02*
X1143110Y-205812D01*
X1142485Y-204572D01*
X1141443Y-203797D01*
X1139985Y-203487D01*
X1138527Y-203797D01*
X1137276Y-204727D01*
X1136651Y-206122D01*
Y-207672D01*
X1136235Y-208602D01*
X1135193Y-209377D01*
X1133735Y-209687D01*
X1132276Y-209222D01*
X1131235Y-208137D01*
X1130818Y-206897D01*
X1131235Y-205657D01*
X1132276Y-204572D01*
X1133735Y-204107D01*
X1135193Y-204417D01*
X1136235Y-205192D01*
X1136651Y-206122D01*
Y-207672D01*
X1137276Y-209067D01*
X1138527Y-209997D01*
X1139985Y-210307D01*
X1141443Y-209997D01*
X1142485Y-209222D01*
X1143110Y-207982D01*
X1143318Y-206897D01*
G01X1159805Y-353176D02*
X1147305D01*
X1149805Y-355036D01*
G01X1159805D02*
Y-351316D01*
G01Y-340776D02*
X1147305D01*
X1149805Y-342636D01*
G01X1159805D02*
Y-338916D01*
G01X1157930Y-331786D02*
X1158972Y-330856D01*
X1159597Y-329771D01*
X1159805Y-328376D01*
X1159388Y-326981D01*
X1158555Y-325896D01*
X1157097Y-325121D01*
X1155430Y-324966D01*
X1153763Y-325276D01*
X1152722Y-326051D01*
X1151888Y-327136D01*
X1151680Y-328221D01*
X1151888Y-329306D01*
X1152722Y-330701D01*
X1147305Y-330236D01*
Y-326051D01*
G01X1157305Y-319386D02*
X1158764Y-318456D01*
X1159597Y-317216D01*
X1159805Y-315821D01*
X1159597Y-314581D01*
X1158555Y-313341D01*
X1157305Y-312566D01*
X1156055Y-312411D01*
X1154597Y-312721D01*
X1153555Y-313806D01*
X1153138Y-314891D01*
Y-316286D01*
G01Y-314891D02*
X1152513Y-313961D01*
X1151472Y-313186D01*
X1150222Y-312876D01*
X1148972Y-313186D01*
X1147930Y-313961D01*
X1147305Y-315356D01*
X1147513Y-316751D01*
X1148347Y-318146D01*
G01X1157930Y-306986D02*
X1158972Y-306056D01*
X1159597Y-304971D01*
X1159805Y-303576D01*
X1159388Y-302181D01*
X1158555Y-301096D01*
X1157097Y-300321D01*
X1155430Y-300166D01*
X1153763Y-300476D01*
X1152722Y-301251D01*
X1151888Y-302336D01*
X1151680Y-303421D01*
X1151888Y-304506D01*
X1152722Y-305901D01*
X1147305Y-305436D01*
Y-301251D01*
G01X1160222Y-291176D02*
X1160013Y-291486D01*
X1159597D01*
X1159388Y-291176D01*
X1159597Y-290866D01*
X1160013D01*
X1160222Y-291176D01*
G01X1157930Y-282186D02*
X1158972Y-281256D01*
X1159597Y-280171D01*
X1159805Y-278776D01*
X1159388Y-277381D01*
X1158555Y-276296D01*
X1157097Y-275521D01*
X1155430Y-275366D01*
X1153763Y-275676D01*
X1152722Y-276451D01*
X1151888Y-277536D01*
X1151680Y-278621D01*
X1151888Y-279706D01*
X1152722Y-281101D01*
X1147305Y-280636D01*
Y-276451D01*
G01X1157930Y-269786D02*
X1158972Y-268856D01*
X1159597Y-267771D01*
X1159805Y-266376D01*
X1159388Y-264981D01*
X1158555Y-263896D01*
X1157097Y-263121D01*
X1155430Y-262966D01*
X1153763Y-263276D01*
X1152722Y-264051D01*
X1151888Y-265136D01*
X1151680Y-266221D01*
X1151888Y-267306D01*
X1152722Y-268701D01*
X1147305Y-268236D01*
Y-264051D01*
G01X1149388Y-234721D02*
X1148139Y-233791D01*
X1147513Y-232706D01*
X1147305Y-231466D01*
X1147722Y-229916D01*
X1148763Y-228831D01*
X1150013Y-228521D01*
X1151264Y-228676D01*
X1152305Y-229296D01*
X1154388Y-232396D01*
X1155847Y-233791D01*
X1157930Y-234721D01*
X1159805Y-235031D01*
Y-228521D01*
G01X1158347Y-222011D02*
X1159388Y-220926D01*
X1159805Y-219686D01*
X1159388Y-218446D01*
X1158139Y-217361D01*
X1156263Y-216586D01*
X1154388Y-216276D01*
X1152097D01*
X1150222Y-216586D01*
X1148555Y-217361D01*
X1147722Y-218291D01*
X1147305Y-219376D01*
X1147722Y-220616D01*
X1148555Y-221546D01*
X1149805Y-222166D01*
X1151472Y-222476D01*
X1152930Y-222166D01*
X1154388Y-221391D01*
X1155222Y-220461D01*
X1155430Y-219376D01*
X1155014Y-218136D01*
X1153972Y-217206D01*
X1152097Y-216276D01*
G01X1157305Y-210386D02*
X1158764Y-209456D01*
X1159597Y-208216D01*
X1159805Y-206821D01*
X1159597Y-205581D01*
X1158555Y-204341D01*
X1157305Y-203566D01*
X1156055Y-203411D01*
X1154597Y-203721D01*
X1153555Y-204806D01*
X1153138Y-205891D01*
Y-207286D01*
G01Y-205891D02*
X1152513Y-204961D01*
X1151472Y-204186D01*
X1150222Y-203876D01*
X1148972Y-204186D01*
X1147930Y-204961D01*
X1147305Y-206356D01*
X1147513Y-207751D01*
X1148347Y-209146D01*
G01X1178761Y-390753D02*
X1166261D01*
X1168761Y-392613D01*
G01X1178761D02*
Y-388893D01*
G01Y-378353D02*
X1166261D01*
X1168761Y-380213D01*
G01X1178761D02*
Y-376493D01*
G01X1176886Y-369363D02*
X1177928Y-368433D01*
X1178553Y-367348D01*
X1178761Y-365953D01*
X1178344Y-364558D01*
X1177511Y-363473D01*
X1176053Y-362698D01*
X1174386Y-362543D01*
X1172719Y-362853D01*
X1171678Y-363628D01*
X1170844Y-364713D01*
X1170636Y-365798D01*
X1170844Y-366883D01*
X1171678Y-368278D01*
X1166261Y-367813D01*
Y-363628D01*
G01X1176886Y-356963D02*
X1177928Y-356033D01*
X1178553Y-354948D01*
X1178761Y-353553D01*
X1178344Y-352158D01*
X1177511Y-351073D01*
X1176053Y-350298D01*
X1174386Y-350143D01*
X1172719Y-350453D01*
X1171678Y-351228D01*
X1170844Y-352313D01*
X1170636Y-353398D01*
X1170844Y-354483D01*
X1171678Y-355878D01*
X1166261Y-355413D01*
Y-351228D01*
G01X1178761Y-341463D02*
X1176053Y-341153D01*
X1173761Y-340688D01*
X1171678Y-340068D01*
X1169386Y-339293D01*
X1166261Y-338053D01*
Y-344253D01*
G01X1179178Y-328753D02*
X1178969Y-329063D01*
X1178553D01*
X1178344Y-328753D01*
X1178553Y-328443D01*
X1178969D01*
X1179178Y-328753D01*
G01X1166261Y-316353D02*
X1166678Y-317593D01*
X1167719Y-318523D01*
X1168969Y-319143D01*
X1170636Y-319608D01*
X1172511Y-319763D01*
X1174386Y-319608D01*
X1176053Y-319143D01*
X1177303Y-318523D01*
X1178344Y-317593D01*
X1178761Y-316353D01*
X1178344Y-315113D01*
X1177303Y-314183D01*
X1176053Y-313563D01*
X1174386Y-313098D01*
X1172511Y-312943D01*
X1170636Y-313098D01*
X1168969Y-313563D01*
X1167719Y-314183D01*
X1166678Y-315113D01*
X1166261Y-316353D01*
G01X1178761Y-303953D02*
X1178553Y-302868D01*
X1177928Y-301628D01*
X1176886Y-300853D01*
X1175428Y-300543D01*
X1173970Y-300853D01*
X1172719Y-301783D01*
X1172094Y-303178D01*
Y-304728D01*
X1171678Y-305658D01*
X1170636Y-306433D01*
X1169178Y-306743D01*
X1167719Y-306278D01*
X1166678Y-305193D01*
X1166261Y-303953D01*
X1166678Y-302713D01*
X1167719Y-301628D01*
X1169178Y-301163D01*
X1170636Y-301473D01*
X1171678Y-302248D01*
X1172094Y-303178D01*
Y-304728D01*
X1172719Y-306123D01*
X1173970Y-307053D01*
X1175428Y-307363D01*
X1176886Y-307053D01*
X1177928Y-306278D01*
X1178553Y-305038D01*
X1178761Y-303953D01*
G01X1168344Y-272298D02*
X1167095Y-271368D01*
X1166469Y-270283D01*
X1166261Y-269043D01*
X1166678Y-267493D01*
X1167719Y-266408D01*
X1168969Y-266098D01*
X1170220Y-266253D01*
X1171261Y-266873D01*
X1173344Y-269973D01*
X1174803Y-271368D01*
X1176886Y-272298D01*
X1178761Y-272608D01*
Y-266098D01*
G01X1177303Y-259588D02*
X1178344Y-258503D01*
X1178761Y-257263D01*
X1178344Y-256023D01*
X1177095Y-254938D01*
X1175219Y-254163D01*
X1173344Y-253853D01*
X1171053D01*
X1169178Y-254163D01*
X1167511Y-254938D01*
X1166678Y-255868D01*
X1166261Y-256953D01*
X1166678Y-258193D01*
X1167511Y-259123D01*
X1168761Y-259743D01*
X1170428Y-260053D01*
X1171886Y-259743D01*
X1173344Y-258968D01*
X1174178Y-258038D01*
X1174386Y-256953D01*
X1173970Y-255713D01*
X1172928Y-254783D01*
X1171053Y-253853D01*
G01X1176261Y-247963D02*
X1177720Y-247033D01*
X1178553Y-245793D01*
X1178761Y-244398D01*
X1178553Y-243158D01*
X1177511Y-241918D01*
X1176261Y-241143D01*
X1175011Y-240988D01*
X1173553Y-241298D01*
X1172511Y-242383D01*
X1172094Y-243468D01*
Y-244863D01*
G01Y-243468D02*
X1171469Y-242538D01*
X1170428Y-241763D01*
X1169178Y-241453D01*
X1167928Y-241763D01*
X1166886Y-242538D01*
X1166261Y-243933D01*
X1166469Y-245328D01*
X1167303Y-246723D01*
G01X1179178Y-232153D02*
X1178969Y-232463D01*
X1178553D01*
X1178344Y-232153D01*
X1178553Y-231843D01*
X1178969D01*
X1179178Y-232153D01*
G01X1176886Y-223163D02*
X1177928Y-222233D01*
X1178553Y-221148D01*
X1178761Y-219753D01*
X1178344Y-218358D01*
X1177511Y-217273D01*
X1176053Y-216498D01*
X1174386Y-216343D01*
X1172719Y-216653D01*
X1171678Y-217428D01*
X1170844Y-218513D01*
X1170636Y-219598D01*
X1170844Y-220683D01*
X1171678Y-222078D01*
X1166261Y-221613D01*
Y-217428D01*
G01X1176886Y-210763D02*
X1177928Y-209833D01*
X1178553Y-208748D01*
X1178761Y-207353D01*
X1178344Y-205958D01*
X1177511Y-204873D01*
X1176053Y-204098D01*
X1174386Y-203943D01*
X1172719Y-204253D01*
X1171678Y-205028D01*
X1170844Y-206113D01*
X1170636Y-207198D01*
X1170844Y-208283D01*
X1171678Y-209678D01*
X1166261Y-209213D01*
Y-205028D01*
G01X1164124Y322655D02*
Y330155D01*
X1168418Y322655D01*
Y330155D01*
G01X1171904Y322655D02*
Y330155D01*
X1174144D01*
X1174891Y329780D01*
X1175451Y328905D01*
X1175638Y327905D01*
X1175451Y326905D01*
X1174984Y326155D01*
X1174144Y325780D01*
X1171904D01*
G01X1181271Y330155D02*
Y322655D01*
G01X1179124Y330155D02*
X1183418D01*
G01X1186811Y322655D02*
Y330155D01*
G01X1190731D02*
Y322655D01*
G01Y326405D02*
X1186811D01*
G01X1253888Y-378077D02*
X1241388D01*
X1243888Y-379937D01*
G01X1253888D02*
Y-376217D01*
G01X1243471Y-368622D02*
X1242222Y-367692D01*
X1241596Y-366607D01*
X1241388Y-365367D01*
X1241805Y-363817D01*
X1242846Y-362732D01*
X1244096Y-362422D01*
X1245347Y-362577D01*
X1246388Y-363197D01*
X1248471Y-366297D01*
X1249930Y-367692D01*
X1252013Y-368622D01*
X1253888Y-368932D01*
Y-362422D01*
G01Y-351417D02*
X1241388D01*
X1250346Y-357152D01*
Y-349402D01*
G01X1253888Y-341187D02*
X1251180Y-340877D01*
X1248888Y-340412D01*
X1246805Y-339792D01*
X1244513Y-339017D01*
X1241388Y-337777D01*
Y-343977D01*
G01X1248680Y-331422D02*
X1247221Y-330337D01*
X1246388Y-329407D01*
X1245971Y-328167D01*
X1246388Y-327082D01*
X1247221Y-326307D01*
X1248471Y-325687D01*
X1249930Y-325532D01*
X1251180Y-325687D01*
X1252430Y-326307D01*
X1253471Y-327237D01*
X1253888Y-328322D01*
X1253471Y-329562D01*
X1252222Y-330647D01*
X1250346Y-331267D01*
X1248263Y-331422D01*
X1245555Y-331112D01*
X1244096Y-330647D01*
X1242638Y-329872D01*
X1241596Y-328787D01*
X1241388Y-327702D01*
X1241805Y-326617D01*
X1242846Y-325842D01*
G01X1254305Y-316077D02*
X1254096Y-316387D01*
X1253680D01*
X1253471Y-316077D01*
X1253680Y-315767D01*
X1254096D01*
X1254305Y-316077D01*
G01X1251388Y-307087D02*
X1252847Y-306157D01*
X1253680Y-304917D01*
X1253888Y-303522D01*
X1253680Y-302282D01*
X1252638Y-301042D01*
X1251388Y-300267D01*
X1250138Y-300112D01*
X1248680Y-300422D01*
X1247638Y-301507D01*
X1247221Y-302592D01*
Y-303987D01*
G01Y-302592D02*
X1246596Y-301662D01*
X1245555Y-300887D01*
X1244305Y-300577D01*
X1243055Y-300887D01*
X1242013Y-301662D01*
X1241388Y-303057D01*
X1241596Y-304452D01*
X1242430Y-305847D01*
G01X1253888Y-291277D02*
X1253680Y-290192D01*
X1253055Y-288952D01*
X1252013Y-288177D01*
X1250555Y-287867D01*
X1249097Y-288177D01*
X1247846Y-289107D01*
X1247221Y-290502D01*
Y-292052D01*
X1246805Y-292982D01*
X1245763Y-293757D01*
X1244305Y-294067D01*
X1242846Y-293602D01*
X1241805Y-292517D01*
X1241388Y-291277D01*
X1241805Y-290037D01*
X1242846Y-288952D01*
X1244305Y-288487D01*
X1245763Y-288797D01*
X1246805Y-289572D01*
X1247221Y-290502D01*
Y-292052D01*
X1247846Y-293447D01*
X1249097Y-294377D01*
X1250555Y-294687D01*
X1252013Y-294377D01*
X1253055Y-293602D01*
X1253680Y-292362D01*
X1253888Y-291277D01*
G01X1251388Y-260087D02*
X1252847Y-259157D01*
X1253680Y-257917D01*
X1253888Y-256522D01*
X1253680Y-255282D01*
X1252638Y-254042D01*
X1251388Y-253267D01*
X1250138Y-253112D01*
X1248680Y-253422D01*
X1247638Y-254507D01*
X1247221Y-255592D01*
Y-256987D01*
G01Y-255592D02*
X1246596Y-254662D01*
X1245555Y-253887D01*
X1244305Y-253577D01*
X1243055Y-253887D01*
X1242013Y-254662D01*
X1241388Y-256057D01*
X1241596Y-257452D01*
X1242430Y-258847D01*
G01X1253888Y-244277D02*
X1241388D01*
X1243888Y-246137D01*
G01X1253888D02*
Y-242417D01*
G01X1248680Y-234822D02*
X1247221Y-233737D01*
X1246388Y-232807D01*
X1245971Y-231567D01*
X1246388Y-230482D01*
X1247221Y-229707D01*
X1248471Y-229087D01*
X1249930Y-228932D01*
X1251180Y-229087D01*
X1252430Y-229707D01*
X1253471Y-230637D01*
X1253888Y-231722D01*
X1253471Y-232962D01*
X1252222Y-234047D01*
X1250346Y-234667D01*
X1248263Y-234822D01*
X1245555Y-234512D01*
X1244096Y-234047D01*
X1242638Y-233272D01*
X1241596Y-232187D01*
X1241388Y-231102D01*
X1241805Y-230017D01*
X1242846Y-229242D01*
G01X1254305Y-219477D02*
X1254096Y-219787D01*
X1253680D01*
X1253471Y-219477D01*
X1253680Y-219167D01*
X1254096D01*
X1254305Y-219477D01*
G01X1252430Y-209712D02*
X1253471Y-208627D01*
X1253888Y-207387D01*
X1253471Y-206147D01*
X1252222Y-205062D01*
X1250346Y-204287D01*
X1248471Y-203977D01*
X1246180D01*
X1244305Y-204287D01*
X1242638Y-205062D01*
X1241805Y-205992D01*
X1241388Y-207077D01*
X1241805Y-208317D01*
X1242638Y-209247D01*
X1243888Y-209867D01*
X1245555Y-210177D01*
X1247013Y-209867D01*
X1248471Y-209092D01*
X1249305Y-208162D01*
X1249513Y-207077D01*
X1249097Y-205837D01*
X1248055Y-204907D01*
X1246180Y-203977D01*
G01X1249154Y1676732D02*
G03I-2500J0D01*
G01X1241280Y1672795D02*
G03I-2500J0D01*
G01X1249154Y1690905D02*
G03I-2500J0D01*
G01X1241280Y1686968D02*
G03I-2500J0D01*
G01X1249154Y1705078D02*
G03I-2500J0D01*
G01X1241280Y1701141D02*
G03I-2500J0D01*
G01Y1715314D02*
G03I-2500J0D01*
G01X1249154Y1719251D02*
G03I-2500J0D01*
G01X1241280Y1729488D02*
G03I-2500J0D01*
G01X1249154Y1733425D02*
G03I-2500J0D01*
G01X1269770Y-377922D02*
X1257270D01*
X1259770Y-379782D01*
G01X1269770D02*
Y-376062D01*
G01X1259353Y-368467D02*
X1258104Y-367537D01*
X1257478Y-366452D01*
X1257270Y-365212D01*
X1257687Y-363662D01*
X1258728Y-362577D01*
X1259978Y-362267D01*
X1261229Y-362422D01*
X1262270Y-363042D01*
X1264353Y-366142D01*
X1265812Y-367537D01*
X1267895Y-368467D01*
X1269770Y-368777D01*
Y-362267D01*
G01Y-353432D02*
X1267062Y-353122D01*
X1264770Y-352657D01*
X1262687Y-352037D01*
X1260395Y-351262D01*
X1257270Y-350022D01*
Y-356222D01*
G01X1269770Y-340722D02*
X1257270D01*
X1259770Y-342582D01*
G01X1269770D02*
Y-338862D01*
G01X1259353Y-331267D02*
X1258104Y-330337D01*
X1257478Y-329252D01*
X1257270Y-328012D01*
X1257687Y-326462D01*
X1258728Y-325377D01*
X1259978Y-325067D01*
X1261229Y-325222D01*
X1262270Y-325842D01*
X1264353Y-328942D01*
X1265812Y-330337D01*
X1267895Y-331267D01*
X1269770Y-331577D01*
Y-325067D01*
G01X1270187Y-315922D02*
X1269978Y-316232D01*
X1269562D01*
X1269353Y-315922D01*
X1269562Y-315612D01*
X1269978D01*
X1270187Y-315922D01*
G01X1264562Y-306467D02*
X1263103Y-305382D01*
X1262270Y-304452D01*
X1261853Y-303212D01*
X1262270Y-302127D01*
X1263103Y-301352D01*
X1264353Y-300732D01*
X1265812Y-300577D01*
X1267062Y-300732D01*
X1268312Y-301352D01*
X1269353Y-302282D01*
X1269770Y-303367D01*
X1269353Y-304607D01*
X1268104Y-305692D01*
X1266228Y-306312D01*
X1264145Y-306467D01*
X1261437Y-306157D01*
X1259978Y-305692D01*
X1258520Y-304917D01*
X1257478Y-303832D01*
X1257270Y-302747D01*
X1257687Y-301662D01*
X1258728Y-300887D01*
G01X1257270Y-291122D02*
X1257687Y-292362D01*
X1258728Y-293292D01*
X1259978Y-293912D01*
X1261645Y-294377D01*
X1263520Y-294532D01*
X1265395Y-294377D01*
X1267062Y-293912D01*
X1268312Y-293292D01*
X1269353Y-292362D01*
X1269770Y-291122D01*
X1269353Y-289882D01*
X1268312Y-288952D01*
X1267062Y-288332D01*
X1265395Y-287867D01*
X1263520Y-287712D01*
X1261645Y-287867D01*
X1259978Y-288332D01*
X1258728Y-288952D01*
X1257687Y-289882D01*
X1257270Y-291122D01*
G01X1267270Y-259932D02*
X1268729Y-259002D01*
X1269562Y-257762D01*
X1269770Y-256367D01*
X1269562Y-255127D01*
X1268520Y-253887D01*
X1267270Y-253112D01*
X1266020Y-252957D01*
X1264562Y-253267D01*
X1263520Y-254352D01*
X1263103Y-255437D01*
Y-256832D01*
G01Y-255437D02*
X1262478Y-254507D01*
X1261437Y-253732D01*
X1260187Y-253422D01*
X1258937Y-253732D01*
X1257895Y-254507D01*
X1257270Y-255902D01*
X1257478Y-257297D01*
X1258312Y-258692D01*
G01X1259353Y-247067D02*
X1258104Y-246137D01*
X1257478Y-245052D01*
X1257270Y-243812D01*
X1257687Y-242262D01*
X1258728Y-241177D01*
X1259978Y-240867D01*
X1261229Y-241022D01*
X1262270Y-241642D01*
X1264353Y-244742D01*
X1265812Y-246137D01*
X1267895Y-247067D01*
X1269770Y-247377D01*
Y-240867D01*
G01X1259353Y-234667D02*
X1258104Y-233737D01*
X1257478Y-232652D01*
X1257270Y-231412D01*
X1257687Y-229862D01*
X1258728Y-228777D01*
X1259978Y-228467D01*
X1261229Y-228622D01*
X1262270Y-229242D01*
X1264353Y-232342D01*
X1265812Y-233737D01*
X1267895Y-234667D01*
X1269770Y-234977D01*
Y-228467D01*
G01X1270187Y-219322D02*
X1269978Y-219632D01*
X1269562D01*
X1269353Y-219322D01*
X1269562Y-219012D01*
X1269978D01*
X1270187Y-219322D01*
G01X1268312Y-209557D02*
X1269353Y-208472D01*
X1269770Y-207232D01*
X1269353Y-205992D01*
X1268104Y-204907D01*
X1266228Y-204132D01*
X1264353Y-203822D01*
X1262062D01*
X1260187Y-204132D01*
X1258520Y-204907D01*
X1257687Y-205837D01*
X1257270Y-206922D01*
X1257687Y-208162D01*
X1258520Y-209092D01*
X1259770Y-209712D01*
X1261437Y-210022D01*
X1262895Y-209712D01*
X1264353Y-208937D01*
X1265187Y-208007D01*
X1265395Y-206922D01*
X1264979Y-205682D01*
X1263937Y-204752D01*
X1262062Y-203822D01*
G01X1264902Y1676732D02*
G03I-2500J0D01*
G01X1257028Y1672795D02*
G03I-2500J0D01*
G01X1264902Y1690905D02*
G03I-2500J0D01*
G01X1257028Y1686968D02*
G03I-2500J0D01*
G01X1264902Y1705078D02*
G03I-2500J0D01*
G01X1257028Y1701141D02*
G03I-2500J0D01*
G01Y1715314D02*
G03I-2500J0D01*
G01X1264902Y1719251D02*
G03I-2500J0D01*
G01X1257028Y1729488D02*
G03I-2500J0D01*
G01X1264902Y1733425D02*
G03I-2500J0D01*
G01X1289164Y-390296D02*
X1276664D01*
X1279164Y-392156D01*
G01X1289164D02*
Y-388436D01*
G01X1278747Y-380841D02*
X1277498Y-379911D01*
X1276872Y-378826D01*
X1276664Y-377586D01*
X1277081Y-376036D01*
X1278122Y-374951D01*
X1279372Y-374641D01*
X1280623Y-374796D01*
X1281664Y-375416D01*
X1283747Y-378516D01*
X1285206Y-379911D01*
X1287289Y-380841D01*
X1289164Y-381151D01*
Y-374641D01*
G01Y-365496D02*
X1288956Y-364411D01*
X1288331Y-363171D01*
X1287289Y-362396D01*
X1285831Y-362086D01*
X1284373Y-362396D01*
X1283122Y-363326D01*
X1282497Y-364721D01*
Y-366271D01*
X1282081Y-367201D01*
X1281039Y-367976D01*
X1279581Y-368286D01*
X1278122Y-367821D01*
X1277081Y-366736D01*
X1276664Y-365496D01*
X1277081Y-364256D01*
X1278122Y-363171D01*
X1279581Y-362706D01*
X1281039Y-363016D01*
X1282081Y-363791D01*
X1282497Y-364721D01*
Y-366271D01*
X1283122Y-367666D01*
X1284373Y-368596D01*
X1285831Y-368906D01*
X1287289Y-368596D01*
X1288331Y-367821D01*
X1288956Y-366581D01*
X1289164Y-365496D01*
G01X1278747Y-356041D02*
X1277498Y-355111D01*
X1276872Y-354026D01*
X1276664Y-352786D01*
X1277081Y-351236D01*
X1278122Y-350151D01*
X1279372Y-349841D01*
X1280623Y-349996D01*
X1281664Y-350616D01*
X1283747Y-353716D01*
X1285206Y-355111D01*
X1287289Y-356041D01*
X1289164Y-356351D01*
Y-349841D01*
G01X1287706Y-343331D02*
X1288747Y-342246D01*
X1289164Y-341006D01*
X1288747Y-339766D01*
X1287498Y-338681D01*
X1285622Y-337906D01*
X1283747Y-337596D01*
X1281456D01*
X1279581Y-337906D01*
X1277914Y-338681D01*
X1277081Y-339611D01*
X1276664Y-340696D01*
X1277081Y-341936D01*
X1277914Y-342866D01*
X1279164Y-343486D01*
X1280831Y-343796D01*
X1282289Y-343486D01*
X1283747Y-342711D01*
X1284581Y-341781D01*
X1284789Y-340696D01*
X1284373Y-339456D01*
X1283331Y-338526D01*
X1281456Y-337596D01*
G01X1289581Y-328296D02*
X1289372Y-328606D01*
X1288956D01*
X1288747Y-328296D01*
X1288956Y-327986D01*
X1289372D01*
X1289581Y-328296D01*
G01X1289164Y-315896D02*
X1276664D01*
X1279164Y-317756D01*
G01X1289164D02*
Y-314036D01*
G01Y-301636D02*
X1276664D01*
X1285622Y-307371D01*
Y-299621D01*
G01X1286664Y-272306D02*
X1288123Y-271376D01*
X1288956Y-270136D01*
X1289164Y-268741D01*
X1288956Y-267501D01*
X1287914Y-266261D01*
X1286664Y-265486D01*
X1285414Y-265331D01*
X1283956Y-265641D01*
X1282914Y-266726D01*
X1282497Y-267811D01*
Y-269206D01*
G01Y-267811D02*
X1281872Y-266881D01*
X1280831Y-266106D01*
X1279581Y-265796D01*
X1278331Y-266106D01*
X1277289Y-266881D01*
X1276664Y-268276D01*
X1276872Y-269671D01*
X1277706Y-271066D01*
G01X1278747Y-259441D02*
X1277498Y-258511D01*
X1276872Y-257426D01*
X1276664Y-256186D01*
X1277081Y-254636D01*
X1278122Y-253551D01*
X1279372Y-253241D01*
X1280623Y-253396D01*
X1281664Y-254016D01*
X1283747Y-257116D01*
X1285206Y-258511D01*
X1287289Y-259441D01*
X1289164Y-259751D01*
Y-253241D01*
G01X1287289Y-247506D02*
X1288331Y-246576D01*
X1288956Y-245491D01*
X1289164Y-244096D01*
X1288747Y-242701D01*
X1287914Y-241616D01*
X1286456Y-240841D01*
X1284789Y-240686D01*
X1283122Y-240996D01*
X1282081Y-241771D01*
X1281247Y-242856D01*
X1281039Y-243941D01*
X1281247Y-245026D01*
X1282081Y-246421D01*
X1276664Y-245956D01*
Y-241771D01*
G01X1289581Y-231696D02*
X1289372Y-232006D01*
X1288956D01*
X1288747Y-231696D01*
X1288956Y-231386D01*
X1289372D01*
X1289581Y-231696D01*
G01X1289164Y-219296D02*
X1288956Y-218211D01*
X1288331Y-216971D01*
X1287289Y-216196D01*
X1285831Y-215886D01*
X1284373Y-216196D01*
X1283122Y-217126D01*
X1282497Y-218521D01*
Y-220071D01*
X1282081Y-221001D01*
X1281039Y-221776D01*
X1279581Y-222086D01*
X1278122Y-221621D01*
X1277081Y-220536D01*
X1276664Y-219296D01*
X1277081Y-218056D01*
X1278122Y-216971D01*
X1279581Y-216506D01*
X1281039Y-216816D01*
X1282081Y-217591D01*
X1282497Y-218521D01*
Y-220071D01*
X1283122Y-221466D01*
X1284373Y-222396D01*
X1285831Y-222706D01*
X1287289Y-222396D01*
X1288331Y-221621D01*
X1288956Y-220381D01*
X1289164Y-219296D01*
G01X1283956Y-209841D02*
X1282497Y-208756D01*
X1281664Y-207826D01*
X1281247Y-206586D01*
X1281664Y-205501D01*
X1282497Y-204726D01*
X1283747Y-204106D01*
X1285206Y-203951D01*
X1286456Y-204106D01*
X1287706Y-204726D01*
X1288747Y-205656D01*
X1289164Y-206741D01*
X1288747Y-207981D01*
X1287498Y-209066D01*
X1285622Y-209686D01*
X1283539Y-209841D01*
X1280831Y-209531D01*
X1279372Y-209066D01*
X1277914Y-208291D01*
X1276872Y-207206D01*
X1276664Y-206121D01*
X1277081Y-205036D01*
X1278122Y-204261D01*
G01X1280650Y1676732D02*
G03I-2500J0D01*
G01X1272776Y1672795D02*
G03I-2500J0D01*
G01X1280650Y1690905D02*
G03I-2500J0D01*
G01X1272776Y1686968D02*
G03I-2500J0D01*
G01X1280650Y1705078D02*
G03I-2500J0D01*
G01X1272776Y1701141D02*
G03I-2500J0D01*
G01Y1715314D02*
G03I-2500J0D01*
G01X1280650Y1719251D02*
G03I-2500J0D01*
G01X1272776Y1729488D02*
G03I-2500J0D01*
G01X1280650Y1733425D02*
G03I-2500J0D01*
G01X1304892Y-390295D02*
X1292392D01*
X1294892Y-392155D01*
G01X1304892D02*
Y-388435D01*
G01X1294475Y-380840D02*
X1293226Y-379910D01*
X1292600Y-378825D01*
X1292392Y-377585D01*
X1292809Y-376035D01*
X1293850Y-374950D01*
X1295100Y-374640D01*
X1296351Y-374795D01*
X1297392Y-375415D01*
X1299475Y-378515D01*
X1300934Y-379910D01*
X1303017Y-380840D01*
X1304892Y-381150D01*
Y-374640D01*
G01X1303434Y-368130D02*
X1304475Y-367045D01*
X1304892Y-365805D01*
X1304475Y-364565D01*
X1303226Y-363480D01*
X1301350Y-362705D01*
X1299475Y-362395D01*
X1297184D01*
X1295309Y-362705D01*
X1293642Y-363480D01*
X1292809Y-364410D01*
X1292392Y-365495D01*
X1292809Y-366735D01*
X1293642Y-367665D01*
X1294892Y-368285D01*
X1296559Y-368595D01*
X1298017Y-368285D01*
X1299475Y-367510D01*
X1300309Y-366580D01*
X1300517Y-365495D01*
X1300101Y-364255D01*
X1299059Y-363325D01*
X1297184Y-362395D01*
G01X1304892Y-353095D02*
X1304684Y-352010D01*
X1304059Y-350770D01*
X1303017Y-349995D01*
X1301559Y-349685D01*
X1300101Y-349995D01*
X1298850Y-350925D01*
X1298225Y-352320D01*
Y-353870D01*
X1297809Y-354800D01*
X1296767Y-355575D01*
X1295309Y-355885D01*
X1293850Y-355420D01*
X1292809Y-354335D01*
X1292392Y-353095D01*
X1292809Y-351855D01*
X1293850Y-350770D01*
X1295309Y-350305D01*
X1296767Y-350615D01*
X1297809Y-351390D01*
X1298225Y-352320D01*
Y-353870D01*
X1298850Y-355265D01*
X1300101Y-356195D01*
X1301559Y-356505D01*
X1303017Y-356195D01*
X1304059Y-355420D01*
X1304684Y-354180D01*
X1304892Y-353095D01*
G01X1299684Y-343640D02*
X1298225Y-342555D01*
X1297392Y-341625D01*
X1296975Y-340385D01*
X1297392Y-339300D01*
X1298225Y-338525D01*
X1299475Y-337905D01*
X1300934Y-337750D01*
X1302184Y-337905D01*
X1303434Y-338525D01*
X1304475Y-339455D01*
X1304892Y-340540D01*
X1304475Y-341780D01*
X1303226Y-342865D01*
X1301350Y-343485D01*
X1299267Y-343640D01*
X1296559Y-343330D01*
X1295100Y-342865D01*
X1293642Y-342090D01*
X1292600Y-341005D01*
X1292392Y-339920D01*
X1292809Y-338835D01*
X1293850Y-338060D01*
G01X1305309Y-328295D02*
X1305100Y-328605D01*
X1304684D01*
X1304475Y-328295D01*
X1304684Y-327985D01*
X1305100D01*
X1305309Y-328295D01*
G01X1304892Y-314035D02*
X1292392D01*
X1301350Y-319770D01*
Y-312020D01*
G01X1294475Y-306440D02*
X1293226Y-305510D01*
X1292600Y-304425D01*
X1292392Y-303185D01*
X1292809Y-301635D01*
X1293850Y-300550D01*
X1295100Y-300240D01*
X1296351Y-300395D01*
X1297392Y-301015D01*
X1299475Y-304115D01*
X1300934Y-305510D01*
X1303017Y-306440D01*
X1304892Y-306750D01*
Y-300240D01*
G01X1302392Y-272305D02*
X1303851Y-271375D01*
X1304684Y-270135D01*
X1304892Y-268740D01*
X1304684Y-267500D01*
X1303642Y-266260D01*
X1302392Y-265485D01*
X1301142Y-265330D01*
X1299684Y-265640D01*
X1298642Y-266725D01*
X1298225Y-267810D01*
Y-269205D01*
G01Y-267810D02*
X1297600Y-266880D01*
X1296559Y-266105D01*
X1295309Y-265795D01*
X1294059Y-266105D01*
X1293017Y-266880D01*
X1292392Y-268275D01*
X1292600Y-269670D01*
X1293434Y-271065D01*
G01X1294475Y-259440D02*
X1293226Y-258510D01*
X1292600Y-257425D01*
X1292392Y-256185D01*
X1292809Y-254635D01*
X1293850Y-253550D01*
X1295100Y-253240D01*
X1296351Y-253395D01*
X1297392Y-254015D01*
X1299475Y-257115D01*
X1300934Y-258510D01*
X1303017Y-259440D01*
X1304892Y-259750D01*
Y-253240D01*
G01X1303434Y-246730D02*
X1304475Y-245645D01*
X1304892Y-244405D01*
X1304475Y-243165D01*
X1303226Y-242080D01*
X1301350Y-241305D01*
X1299475Y-240995D01*
X1297184D01*
X1295309Y-241305D01*
X1293642Y-242080D01*
X1292809Y-243010D01*
X1292392Y-244095D01*
X1292809Y-245335D01*
X1293642Y-246265D01*
X1294892Y-246885D01*
X1296559Y-247195D01*
X1298017Y-246885D01*
X1299475Y-246110D01*
X1300309Y-245180D01*
X1300517Y-244095D01*
X1300101Y-242855D01*
X1299059Y-241925D01*
X1297184Y-240995D01*
G01X1305309Y-231695D02*
X1305100Y-232005D01*
X1304684D01*
X1304475Y-231695D01*
X1304684Y-231385D01*
X1305100D01*
X1305309Y-231695D01*
G01X1304892Y-219295D02*
X1304684Y-218210D01*
X1304059Y-216970D01*
X1303017Y-216195D01*
X1301559Y-215885D01*
X1300101Y-216195D01*
X1298850Y-217125D01*
X1298225Y-218520D01*
Y-220070D01*
X1297809Y-221000D01*
X1296767Y-221775D01*
X1295309Y-222085D01*
X1293850Y-221620D01*
X1292809Y-220535D01*
X1292392Y-219295D01*
X1292809Y-218055D01*
X1293850Y-216970D01*
X1295309Y-216505D01*
X1296767Y-216815D01*
X1297809Y-217590D01*
X1298225Y-218520D01*
Y-220070D01*
X1298850Y-221465D01*
X1300101Y-222395D01*
X1301559Y-222705D01*
X1303017Y-222395D01*
X1304059Y-221620D01*
X1304684Y-220380D01*
X1304892Y-219295D01*
G01X1299684Y-209840D02*
X1298225Y-208755D01*
X1297392Y-207825D01*
X1296975Y-206585D01*
X1297392Y-205500D01*
X1298225Y-204725D01*
X1299475Y-204105D01*
X1300934Y-203950D01*
X1302184Y-204105D01*
X1303434Y-204725D01*
X1304475Y-205655D01*
X1304892Y-206740D01*
X1304475Y-207980D01*
X1303226Y-209065D01*
X1301350Y-209685D01*
X1299267Y-209840D01*
X1296559Y-209530D01*
X1295100Y-209065D01*
X1293642Y-208290D01*
X1292600Y-207205D01*
X1292392Y-206120D01*
X1292809Y-205035D01*
X1293850Y-204260D01*
G01X1283200Y1007778D02*
Y1015278D01*
X1287494Y1007778D01*
Y1015278D01*
G01X1290980Y1007778D02*
Y1015278D01*
X1293220D01*
X1293967Y1014903D01*
X1294527Y1014028D01*
X1294714Y1013028D01*
X1294527Y1012028D01*
X1294060Y1011278D01*
X1293220Y1010903D01*
X1290980D01*
G01X1300347Y1015278D02*
Y1007778D01*
G01X1298200Y1015278D02*
X1302494D01*
G01X1305887Y1007778D02*
Y1015278D01*
G01X1309807D02*
Y1007778D01*
G01Y1011528D02*
X1305887D01*
G01X1296398Y1676732D02*
G03I-2500J0D01*
G01X1288524Y1672795D02*
G03I-2500J0D01*
G01X1296398Y1690905D02*
G03I-2500J0D01*
G01X1288524Y1686968D02*
G03I-2500J0D01*
G01X1296398Y1705078D02*
G03I-2500J0D01*
G01X1288524Y1701141D02*
G03I-2500J0D01*
G01Y1715314D02*
G03I-2500J0D01*
G01X1296398Y1719251D02*
G03I-2500J0D01*
G01X1288524Y1729488D02*
G03I-2500J0D01*
G01X1296398Y1733425D02*
G03I-2500J0D01*
G01X1321674Y-390296D02*
X1309174D01*
X1311674Y-392156D01*
G01X1321674D02*
Y-388436D01*
G01X1319174Y-381306D02*
X1320633Y-380376D01*
X1321466Y-379136D01*
X1321674Y-377741D01*
X1321466Y-376501D01*
X1320424Y-375261D01*
X1319174Y-374486D01*
X1317924Y-374331D01*
X1316466Y-374641D01*
X1315424Y-375726D01*
X1315007Y-376811D01*
Y-378206D01*
G01Y-376811D02*
X1314382Y-375881D01*
X1313341Y-375106D01*
X1312091Y-374796D01*
X1310841Y-375106D01*
X1309799Y-375881D01*
X1309174Y-377276D01*
X1309382Y-378671D01*
X1310216Y-380066D01*
G01X1311257Y-368441D02*
X1310008Y-367511D01*
X1309382Y-366426D01*
X1309174Y-365186D01*
X1309591Y-363636D01*
X1310632Y-362551D01*
X1311882Y-362241D01*
X1313133Y-362396D01*
X1314174Y-363016D01*
X1316257Y-366116D01*
X1317716Y-367511D01*
X1319799Y-368441D01*
X1321674Y-368751D01*
Y-362241D01*
G01X1316466Y-356041D02*
X1315007Y-354956D01*
X1314174Y-354026D01*
X1313757Y-352786D01*
X1314174Y-351701D01*
X1315007Y-350926D01*
X1316257Y-350306D01*
X1317716Y-350151D01*
X1318966Y-350306D01*
X1320216Y-350926D01*
X1321257Y-351856D01*
X1321674Y-352941D01*
X1321257Y-354181D01*
X1320008Y-355266D01*
X1318132Y-355886D01*
X1316049Y-356041D01*
X1313341Y-355731D01*
X1311882Y-355266D01*
X1310424Y-354491D01*
X1309382Y-353406D01*
X1309174Y-352321D01*
X1309591Y-351236D01*
X1310632Y-350461D01*
G01X1311257Y-343641D02*
X1310008Y-342711D01*
X1309382Y-341626D01*
X1309174Y-340386D01*
X1309591Y-338836D01*
X1310632Y-337751D01*
X1311882Y-337441D01*
X1313133Y-337596D01*
X1314174Y-338216D01*
X1316257Y-341316D01*
X1317716Y-342711D01*
X1319799Y-343641D01*
X1321674Y-343951D01*
Y-337441D01*
G01X1322091Y-328296D02*
X1321882Y-328606D01*
X1321466D01*
X1321257Y-328296D01*
X1321466Y-327986D01*
X1321882D01*
X1322091Y-328296D01*
G01X1321674Y-314036D02*
X1309174D01*
X1318132Y-319771D01*
Y-312021D01*
G01X1309174Y-303496D02*
X1309591Y-304736D01*
X1310632Y-305666D01*
X1311882Y-306286D01*
X1313549Y-306751D01*
X1315424Y-306906D01*
X1317299Y-306751D01*
X1318966Y-306286D01*
X1320216Y-305666D01*
X1321257Y-304736D01*
X1321674Y-303496D01*
X1321257Y-302256D01*
X1320216Y-301326D01*
X1318966Y-300706D01*
X1317299Y-300241D01*
X1315424Y-300086D01*
X1313549Y-300241D01*
X1311882Y-300706D01*
X1310632Y-301326D01*
X1309591Y-302256D01*
X1309174Y-303496D01*
G01X1319174Y-272306D02*
X1320633Y-271376D01*
X1321466Y-270136D01*
X1321674Y-268741D01*
X1321466Y-267501D01*
X1320424Y-266261D01*
X1319174Y-265486D01*
X1317924Y-265331D01*
X1316466Y-265641D01*
X1315424Y-266726D01*
X1315007Y-267811D01*
Y-269206D01*
G01Y-267811D02*
X1314382Y-266881D01*
X1313341Y-266106D01*
X1312091Y-265796D01*
X1310841Y-266106D01*
X1309799Y-266881D01*
X1309174Y-268276D01*
X1309382Y-269671D01*
X1310216Y-271066D01*
G01X1319174Y-259906D02*
X1320633Y-258976D01*
X1321466Y-257736D01*
X1321674Y-256341D01*
X1321466Y-255101D01*
X1320424Y-253861D01*
X1319174Y-253086D01*
X1317924Y-252931D01*
X1316466Y-253241D01*
X1315424Y-254326D01*
X1315007Y-255411D01*
Y-256806D01*
G01Y-255411D02*
X1314382Y-254481D01*
X1313341Y-253706D01*
X1312091Y-253396D01*
X1310841Y-253706D01*
X1309799Y-254481D01*
X1309174Y-255876D01*
X1309382Y-257271D01*
X1310216Y-258666D01*
G01X1316466Y-247041D02*
X1315007Y-245956D01*
X1314174Y-245026D01*
X1313757Y-243786D01*
X1314174Y-242701D01*
X1315007Y-241926D01*
X1316257Y-241306D01*
X1317716Y-241151D01*
X1318966Y-241306D01*
X1320216Y-241926D01*
X1321257Y-242856D01*
X1321674Y-243941D01*
X1321257Y-245181D01*
X1320008Y-246266D01*
X1318132Y-246886D01*
X1316049Y-247041D01*
X1313341Y-246731D01*
X1311882Y-246266D01*
X1310424Y-245491D01*
X1309382Y-244406D01*
X1309174Y-243321D01*
X1309591Y-242236D01*
X1310632Y-241461D01*
G01X1322091Y-231696D02*
X1321882Y-232006D01*
X1321466D01*
X1321257Y-231696D01*
X1321466Y-231386D01*
X1321882D01*
X1322091Y-231696D01*
G01X1321674Y-219296D02*
X1321466Y-218211D01*
X1320841Y-216971D01*
X1319799Y-216196D01*
X1318341Y-215886D01*
X1316883Y-216196D01*
X1315632Y-217126D01*
X1315007Y-218521D01*
Y-220071D01*
X1314591Y-221001D01*
X1313549Y-221776D01*
X1312091Y-222086D01*
X1310632Y-221621D01*
X1309591Y-220536D01*
X1309174Y-219296D01*
X1309591Y-218056D01*
X1310632Y-216971D01*
X1312091Y-216506D01*
X1313549Y-216816D01*
X1314591Y-217591D01*
X1315007Y-218521D01*
Y-220071D01*
X1315632Y-221466D01*
X1316883Y-222396D01*
X1318341Y-222706D01*
X1319799Y-222396D01*
X1320841Y-221621D01*
X1321466Y-220381D01*
X1321674Y-219296D01*
G01X1316466Y-209841D02*
X1315007Y-208756D01*
X1314174Y-207826D01*
X1313757Y-206586D01*
X1314174Y-205501D01*
X1315007Y-204726D01*
X1316257Y-204106D01*
X1317716Y-203951D01*
X1318966Y-204106D01*
X1320216Y-204726D01*
X1321257Y-205656D01*
X1321674Y-206741D01*
X1321257Y-207981D01*
X1320008Y-209066D01*
X1318132Y-209686D01*
X1316049Y-209841D01*
X1313341Y-209531D01*
X1311882Y-209066D01*
X1310424Y-208291D01*
X1309382Y-207206D01*
X1309174Y-206121D01*
X1309591Y-205036D01*
X1310632Y-204261D01*
G01X1316083Y1676732D02*
G03I-2500J0D01*
G01X1308209Y1672795D02*
G03I-2500J0D01*
G01X1316083Y1690905D02*
G03I-2500J0D01*
G01X1308209Y1686968D02*
G03I-2500J0D01*
G01X1316083Y1705078D02*
G03I-2500J0D01*
G01X1308209Y1701141D02*
G03I-2500J0D01*
G01Y1715314D02*
G03I-2500J0D01*
G01X1316083Y1719251D02*
G03I-2500J0D01*
G01X1308209Y1729488D02*
G03I-2500J0D01*
G01X1316083Y1733425D02*
G03I-2500J0D01*
G01X1338455Y-390267D02*
X1325955D01*
X1328455Y-392127D01*
G01X1338455D02*
Y-388407D01*
G01X1335955Y-381277D02*
X1337414Y-380347D01*
X1338247Y-379107D01*
X1338455Y-377712D01*
X1338247Y-376472D01*
X1337205Y-375232D01*
X1335955Y-374457D01*
X1334705Y-374302D01*
X1333247Y-374612D01*
X1332205Y-375697D01*
X1331788Y-376782D01*
Y-378177D01*
G01Y-376782D02*
X1331163Y-375852D01*
X1330122Y-375077D01*
X1328872Y-374767D01*
X1327622Y-375077D01*
X1326580Y-375852D01*
X1325955Y-377247D01*
X1326163Y-378642D01*
X1326997Y-380037D01*
G01X1335955Y-368877D02*
X1337414Y-367947D01*
X1338247Y-366707D01*
X1338455Y-365312D01*
X1338247Y-364072D01*
X1337205Y-362832D01*
X1335955Y-362057D01*
X1334705Y-361902D01*
X1333247Y-362212D01*
X1332205Y-363297D01*
X1331788Y-364382D01*
Y-365777D01*
G01Y-364382D02*
X1331163Y-363452D01*
X1330122Y-362677D01*
X1328872Y-362367D01*
X1327622Y-362677D01*
X1326580Y-363452D01*
X1325955Y-364847D01*
X1326163Y-366242D01*
X1326997Y-367637D01*
G01X1328038Y-356012D02*
X1326789Y-355082D01*
X1326163Y-353997D01*
X1325955Y-352757D01*
X1326372Y-351207D01*
X1327413Y-350122D01*
X1328663Y-349812D01*
X1329914Y-349967D01*
X1330955Y-350587D01*
X1333038Y-353687D01*
X1334497Y-355082D01*
X1336580Y-356012D01*
X1338455Y-356322D01*
Y-349812D01*
G01X1328038Y-343612D02*
X1326789Y-342682D01*
X1326163Y-341597D01*
X1325955Y-340357D01*
X1326372Y-338807D01*
X1327413Y-337722D01*
X1328663Y-337412D01*
X1329914Y-337567D01*
X1330955Y-338187D01*
X1333038Y-341287D01*
X1334497Y-342682D01*
X1336580Y-343612D01*
X1338455Y-343922D01*
Y-337412D01*
G01X1338872Y-328267D02*
X1338663Y-328577D01*
X1338247D01*
X1338038Y-328267D01*
X1338247Y-327957D01*
X1338663D01*
X1338872Y-328267D01*
G01X1325955Y-315867D02*
X1326372Y-317107D01*
X1327413Y-318037D01*
X1328663Y-318657D01*
X1330330Y-319122D01*
X1332205Y-319277D01*
X1334080Y-319122D01*
X1335747Y-318657D01*
X1336997Y-318037D01*
X1338038Y-317107D01*
X1338455Y-315867D01*
X1338038Y-314627D01*
X1336997Y-313697D01*
X1335747Y-313077D01*
X1334080Y-312612D01*
X1332205Y-312457D01*
X1330330Y-312612D01*
X1328663Y-313077D01*
X1327413Y-313697D01*
X1326372Y-314627D01*
X1325955Y-315867D01*
G01X1336580Y-306877D02*
X1337622Y-305947D01*
X1338247Y-304862D01*
X1338455Y-303467D01*
X1338038Y-302072D01*
X1337205Y-300987D01*
X1335747Y-300212D01*
X1334080Y-300057D01*
X1332413Y-300367D01*
X1331372Y-301142D01*
X1330538Y-302227D01*
X1330330Y-303312D01*
X1330538Y-304397D01*
X1331372Y-305792D01*
X1325955Y-305327D01*
Y-301142D01*
G01X1335955Y-272277D02*
X1337414Y-271347D01*
X1338247Y-270107D01*
X1338455Y-268712D01*
X1338247Y-267472D01*
X1337205Y-266232D01*
X1335955Y-265457D01*
X1334705Y-265302D01*
X1333247Y-265612D01*
X1332205Y-266697D01*
X1331788Y-267782D01*
Y-269177D01*
G01Y-267782D02*
X1331163Y-266852D01*
X1330122Y-266077D01*
X1328872Y-265767D01*
X1327622Y-266077D01*
X1326580Y-266852D01*
X1325955Y-268247D01*
X1326163Y-269642D01*
X1326997Y-271037D01*
G01X1335955Y-259877D02*
X1337414Y-258947D01*
X1338247Y-257707D01*
X1338455Y-256312D01*
X1338247Y-255072D01*
X1337205Y-253832D01*
X1335955Y-253057D01*
X1334705Y-252902D01*
X1333247Y-253212D01*
X1332205Y-254297D01*
X1331788Y-255382D01*
Y-256777D01*
G01Y-255382D02*
X1331163Y-254452D01*
X1330122Y-253677D01*
X1328872Y-253367D01*
X1327622Y-253677D01*
X1326580Y-254452D01*
X1325955Y-255847D01*
X1326163Y-257242D01*
X1326997Y-258637D01*
G01X1338455Y-244067D02*
X1338247Y-242982D01*
X1337622Y-241742D01*
X1336580Y-240967D01*
X1335122Y-240657D01*
X1333664Y-240967D01*
X1332413Y-241897D01*
X1331788Y-243292D01*
Y-244842D01*
X1331372Y-245772D01*
X1330330Y-246547D01*
X1328872Y-246857D01*
X1327413Y-246392D01*
X1326372Y-245307D01*
X1325955Y-244067D01*
X1326372Y-242827D01*
X1327413Y-241742D01*
X1328872Y-241277D01*
X1330330Y-241587D01*
X1331372Y-242362D01*
X1331788Y-243292D01*
Y-244842D01*
X1332413Y-246237D01*
X1333664Y-247167D01*
X1335122Y-247477D01*
X1336580Y-247167D01*
X1337622Y-246392D01*
X1338247Y-245152D01*
X1338455Y-244067D01*
G01X1338872Y-231667D02*
X1338663Y-231977D01*
X1338247D01*
X1338038Y-231667D01*
X1338247Y-231357D01*
X1338663D01*
X1338872Y-231667D01*
G01X1335955Y-222677D02*
X1337414Y-221747D01*
X1338247Y-220507D01*
X1338455Y-219112D01*
X1338247Y-217872D01*
X1337205Y-216632D01*
X1335955Y-215857D01*
X1334705Y-215702D01*
X1333247Y-216012D01*
X1332205Y-217097D01*
X1331788Y-218182D01*
Y-219577D01*
G01Y-218182D02*
X1331163Y-217252D01*
X1330122Y-216477D01*
X1328872Y-216167D01*
X1327622Y-216477D01*
X1326580Y-217252D01*
X1325955Y-218647D01*
X1326163Y-220042D01*
X1326997Y-221437D01*
G01X1338455Y-206867D02*
X1338247Y-205782D01*
X1337622Y-204542D01*
X1336580Y-203767D01*
X1335122Y-203457D01*
X1333664Y-203767D01*
X1332413Y-204697D01*
X1331788Y-206092D01*
Y-207642D01*
X1331372Y-208572D01*
X1330330Y-209347D01*
X1328872Y-209657D01*
X1327413Y-209192D01*
X1326372Y-208107D01*
X1325955Y-206867D01*
X1326372Y-205627D01*
X1327413Y-204542D01*
X1328872Y-204077D01*
X1330330Y-204387D01*
X1331372Y-205162D01*
X1331788Y-206092D01*
Y-207642D01*
X1332413Y-209037D01*
X1333664Y-209967D01*
X1335122Y-210277D01*
X1336580Y-209967D01*
X1337622Y-209192D01*
X1338247Y-207952D01*
X1338455Y-206867D01*
G01X1331046Y823886D02*
Y831386D01*
X1335340Y823886D01*
Y831386D01*
G01X1338826Y823886D02*
Y831386D01*
X1341066D01*
X1341813Y831011D01*
X1342373Y830136D01*
X1342560Y829136D01*
X1342373Y828136D01*
X1341906Y827386D01*
X1341066Y827011D01*
X1338826D01*
G01X1348193Y831386D02*
Y823886D01*
G01X1346046Y831386D02*
X1350340D01*
G01X1353733Y823886D02*
Y831386D01*
G01X1357653D02*
Y823886D01*
G01Y827636D02*
X1353733D01*
G01X1331831Y1676732D02*
G03I-2500J0D01*
G01X1323957Y1672795D02*
G03I-2500J0D01*
G01X1331831Y1690905D02*
G03I-2500J0D01*
G01X1323957Y1686968D02*
G03I-2500J0D01*
G01X1331831Y1705078D02*
G03I-2500J0D01*
G01X1323957Y1701141D02*
G03I-2500J0D01*
G01Y1715314D02*
G03I-2500J0D01*
G01X1331831Y1719251D02*
G03I-2500J0D01*
G01X1323957Y1729488D02*
G03I-2500J0D01*
G01X1331831Y1733425D02*
G03I-2500J0D01*
G01X1334103Y1187849D02*
Y1195349D01*
X1338397Y1187849D01*
Y1195349D01*
G01X1341883Y1187849D02*
Y1195349D01*
X1344123D01*
X1344870Y1194974D01*
X1345430Y1194099D01*
X1345617Y1193099D01*
X1345430Y1192099D01*
X1344963Y1191349D01*
X1344123Y1190974D01*
X1341883D01*
G01X1351250Y1195349D02*
Y1187849D01*
G01X1349103Y1195349D02*
X1353397D01*
G01X1356790Y1187849D02*
Y1195349D01*
G01X1360710D02*
Y1187849D01*
G01Y1191599D02*
X1356790D01*
G01X1347579Y1676732D02*
G03I-2500J0D01*
G01X1339705Y1672795D02*
G03I-2500J0D01*
G01X1347579Y1690905D02*
G03I-2500J0D01*
G01X1339705Y1686968D02*
G03I-2500J0D01*
G01X1347579Y1705078D02*
G03I-2500J0D01*
G01X1339705Y1701141D02*
G03I-2500J0D01*
G01Y1715314D02*
G03I-2500J0D01*
G01X1347579Y1719251D02*
G03I-2500J0D01*
G01X1339705Y1729488D02*
G03I-2500J0D01*
G01X1347579Y1733425D02*
G03I-2500J0D01*
G01X1363327Y1676732D02*
G03I-2500J0D01*
G01X1355453Y1672795D02*
G03I-2500J0D01*
G01X1363327Y1690905D02*
G03I-2500J0D01*
G01X1355453Y1686968D02*
G03I-2500J0D01*
G01X1363327Y1705078D02*
G03I-2500J0D01*
G01X1355453Y1701141D02*
G03I-2500J0D01*
G01Y1715314D02*
G03I-2500J0D01*
G01X1363327Y1719251D02*
G03I-2500J0D01*
G01X1355453Y1729488D02*
G03I-2500J0D01*
G01X1363327Y1733425D02*
G03I-2500J0D01*
G01X1377669Y125231D02*
Y132731D01*
X1381963Y125231D01*
Y132731D01*
G01X1385449Y125231D02*
Y132731D01*
X1387689D01*
X1388436Y132356D01*
X1388996Y131481D01*
X1389183Y130481D01*
X1388996Y129481D01*
X1388529Y128731D01*
X1387689Y128356D01*
X1385449D01*
G01X1394816Y132731D02*
Y125231D01*
G01X1392669Y132731D02*
X1396963D01*
G01X1400356Y125231D02*
Y132731D01*
G01X1404276D02*
Y125231D01*
G01Y128981D02*
X1400356D01*
G01X1400818Y-378383D02*
X1388318D01*
X1390818Y-380243D01*
G01X1400818D02*
Y-376523D01*
G01Y-364123D02*
X1388318D01*
X1397276Y-369858D01*
Y-362108D01*
G01X1388318Y-353583D02*
X1388735Y-354823D01*
X1389776Y-355753D01*
X1391026Y-356373D01*
X1392693Y-356838D01*
X1394568Y-356993D01*
X1396443Y-356838D01*
X1398110Y-356373D01*
X1399360Y-355753D01*
X1400401Y-354823D01*
X1400818Y-353583D01*
X1400401Y-352343D01*
X1399360Y-351413D01*
X1398110Y-350793D01*
X1396443Y-350328D01*
X1394568Y-350173D01*
X1392693Y-350328D01*
X1391026Y-350793D01*
X1389776Y-351413D01*
X1388735Y-352343D01*
X1388318Y-353583D01*
G01X1398943Y-344593D02*
X1399985Y-343663D01*
X1400610Y-342578D01*
X1400818Y-341183D01*
X1400401Y-339788D01*
X1399568Y-338703D01*
X1398110Y-337928D01*
X1396443Y-337773D01*
X1394776Y-338083D01*
X1393735Y-338858D01*
X1392901Y-339943D01*
X1392693Y-341028D01*
X1392901Y-342113D01*
X1393735Y-343508D01*
X1388318Y-343043D01*
Y-338858D01*
G01X1400818Y-328783D02*
X1388318D01*
X1390818Y-330643D01*
G01X1400818D02*
Y-326923D01*
G01X1401235Y-316383D02*
X1401026Y-316693D01*
X1400610D01*
X1400401Y-316383D01*
X1400610Y-316073D01*
X1401026D01*
X1401235Y-316383D01*
G01X1400818Y-303983D02*
X1388318D01*
X1390818Y-305843D01*
G01X1400818D02*
Y-302123D01*
G01Y-291583D02*
X1400610Y-290498D01*
X1399985Y-289258D01*
X1398943Y-288483D01*
X1397485Y-288173D01*
X1396027Y-288483D01*
X1394776Y-289413D01*
X1394151Y-290808D01*
Y-292358D01*
X1393735Y-293288D01*
X1392693Y-294063D01*
X1391235Y-294373D01*
X1389776Y-293908D01*
X1388735Y-292823D01*
X1388318Y-291583D01*
X1388735Y-290343D01*
X1389776Y-289258D01*
X1391235Y-288793D01*
X1392693Y-289103D01*
X1393735Y-289878D01*
X1394151Y-290808D01*
Y-292358D01*
X1394776Y-293753D01*
X1396027Y-294683D01*
X1397485Y-294993D01*
X1398943Y-294683D01*
X1399985Y-293908D01*
X1400610Y-292668D01*
X1400818Y-291583D01*
G01X1398318Y-260393D02*
X1399777Y-259463D01*
X1400610Y-258223D01*
X1400818Y-256828D01*
X1400610Y-255588D01*
X1399568Y-254348D01*
X1398318Y-253573D01*
X1397068Y-253418D01*
X1395610Y-253728D01*
X1394568Y-254813D01*
X1394151Y-255898D01*
Y-257293D01*
G01Y-255898D02*
X1393526Y-254968D01*
X1392485Y-254193D01*
X1391235Y-253883D01*
X1389985Y-254193D01*
X1388943Y-254968D01*
X1388318Y-256363D01*
X1388526Y-257758D01*
X1389360Y-259153D01*
G01X1398943Y-247993D02*
X1399985Y-247063D01*
X1400610Y-245978D01*
X1400818Y-244583D01*
X1400401Y-243188D01*
X1399568Y-242103D01*
X1398110Y-241328D01*
X1396443Y-241173D01*
X1394776Y-241483D01*
X1393735Y-242258D01*
X1392901Y-243343D01*
X1392693Y-244428D01*
X1392901Y-245513D01*
X1393735Y-246908D01*
X1388318Y-246443D01*
Y-242258D01*
G01X1395610Y-235128D02*
X1394151Y-234043D01*
X1393318Y-233113D01*
X1392901Y-231873D01*
X1393318Y-230788D01*
X1394151Y-230013D01*
X1395401Y-229393D01*
X1396860Y-229238D01*
X1398110Y-229393D01*
X1399360Y-230013D01*
X1400401Y-230943D01*
X1400818Y-232028D01*
X1400401Y-233268D01*
X1399152Y-234353D01*
X1397276Y-234973D01*
X1395193Y-235128D01*
X1392485Y-234818D01*
X1391026Y-234353D01*
X1389568Y-233578D01*
X1388526Y-232493D01*
X1388318Y-231408D01*
X1388735Y-230323D01*
X1389776Y-229548D01*
G01X1401235Y-219783D02*
X1401026Y-220093D01*
X1400610D01*
X1400401Y-219783D01*
X1400610Y-219473D01*
X1401026D01*
X1401235Y-219783D01*
G01X1399360Y-210018D02*
X1400401Y-208933D01*
X1400818Y-207693D01*
X1400401Y-206453D01*
X1399152Y-205368D01*
X1397276Y-204593D01*
X1395401Y-204283D01*
X1393110D01*
X1391235Y-204593D01*
X1389568Y-205368D01*
X1388735Y-206298D01*
X1388318Y-207383D01*
X1388735Y-208623D01*
X1389568Y-209553D01*
X1390818Y-210173D01*
X1392485Y-210483D01*
X1393943Y-210173D01*
X1395401Y-209398D01*
X1396235Y-208468D01*
X1396443Y-207383D01*
X1396027Y-206143D01*
X1394985Y-205213D01*
X1393110Y-204283D01*
G01X1394209Y2023975D02*
X1386709D01*
X1394209Y2028269D01*
X1386709D01*
G01X1394209Y2033622D02*
X1394084Y2032875D01*
X1393584Y2032222D01*
X1392834Y2031662D01*
X1391959Y2031289D01*
X1390959Y2031102D01*
X1389959D01*
X1388959Y2031289D01*
X1388084Y2031662D01*
X1387334Y2032222D01*
X1386834Y2032875D01*
X1386709Y2033622D01*
X1386834Y2034369D01*
X1387334Y2035022D01*
X1388084Y2035582D01*
X1388959Y2035955D01*
X1389959Y2036142D01*
X1390959D01*
X1391959Y2035955D01*
X1392834Y2035582D01*
X1393584Y2035022D01*
X1394084Y2034369D01*
X1394209Y2033622D01*
G01Y2038975D02*
X1386709D01*
X1394209Y2043269D01*
X1386709D01*
G01X1391709Y2047409D02*
Y2049835D01*
G01X1394209Y2053695D02*
X1386709D01*
X1392959Y2056122D01*
X1386709Y2058549D01*
X1394209D01*
G01Y2061289D02*
X1386709Y2063622D01*
X1394209Y2065955D01*
G01X1391584Y2065115D02*
Y2062129D01*
G01X1394209Y2069255D02*
X1386709D01*
Y2071589D01*
X1387084Y2072335D01*
X1387584Y2072802D01*
X1388584Y2072989D01*
X1389584Y2072802D01*
X1390209Y2072242D01*
X1390584Y2071589D01*
Y2069255D01*
G01Y2071589D02*
X1394209Y2072989D01*
G01Y2076569D02*
X1386709D01*
G01Y2080115D02*
X1391334Y2076569D01*
G01X1394209Y2080675D02*
X1389209Y2078155D01*
G01X1394459Y2086122D02*
X1394334Y2085935D01*
X1394084D01*
X1393959Y2086122D01*
X1394084Y2086309D01*
X1394334D01*
X1394459Y2086122D01*
G01X1391084D02*
X1390959Y2085935D01*
X1390709D01*
X1390584Y2086122D01*
X1390709Y2086309D01*
X1390959D01*
X1391084Y2086122D01*
G01X1386709Y2093622D02*
X1394209D01*
G01X1386709Y2091475D02*
Y2095769D01*
G01Y2100002D02*
Y2102242D01*
G01Y2101122D02*
X1394209D01*
G01Y2100002D02*
Y2102242D01*
G01Y2106475D02*
X1386709D01*
X1394209Y2110769D01*
X1386709D01*
G01Y2121755D02*
X1394209D01*
Y2125489D01*
G01Y2132989D02*
Y2129255D01*
X1386709D01*
Y2132989D01*
G01X1390334Y2131495D02*
Y2129255D01*
G01X1394209Y2136289D02*
X1386709Y2138622D01*
X1394209Y2140955D01*
G01X1391584Y2140115D02*
Y2137129D01*
G01X1394209Y2144069D02*
X1386709D01*
Y2145935D01*
X1387084Y2146682D01*
X1387584Y2147242D01*
X1388334Y2147709D01*
X1389209Y2148082D01*
X1390459Y2148175D01*
X1391709Y2148082D01*
X1392584Y2147709D01*
X1393334Y2147242D01*
X1393834Y2146682D01*
X1394209Y2145935D01*
Y2144069D01*
G01X1394459Y2153622D02*
X1394334Y2153435D01*
X1394084D01*
X1393959Y2153622D01*
X1394084Y2153809D01*
X1394334D01*
X1394459Y2153622D01*
G01X1391084D02*
X1390959Y2153435D01*
X1390709D01*
X1390584Y2153622D01*
X1390709Y2153809D01*
X1390959D01*
X1391084Y2153622D01*
G01X1394209Y2159255D02*
X1386709D01*
Y2161589D01*
X1387084Y2162335D01*
X1387584Y2162802D01*
X1388584Y2162989D01*
X1389584Y2162802D01*
X1390209Y2162242D01*
X1390584Y2161589D01*
Y2159255D01*
G01Y2161589D02*
X1394209Y2162989D01*
G01Y2170489D02*
Y2166755D01*
X1386709D01*
Y2170489D01*
G01X1390334Y2168995D02*
Y2166755D01*
G01X1387334Y2178175D02*
X1386959Y2177615D01*
X1386709Y2176962D01*
Y2176215D01*
X1387084Y2175375D01*
X1387709Y2174722D01*
X1388459Y2174255D01*
X1389709Y2173882D01*
X1390834Y2173789D01*
X1391959Y2173975D01*
X1392709Y2174255D01*
X1393459Y2174815D01*
X1393959Y2175469D01*
X1394209Y2176122D01*
Y2176775D01*
X1393959Y2177429D01*
X1393584Y2177989D01*
X1393084Y2178455D01*
G01X1394209Y2183622D02*
X1394084Y2182875D01*
X1393584Y2182222D01*
X1392834Y2181662D01*
X1391959Y2181289D01*
X1390959Y2181102D01*
X1389959D01*
X1388959Y2181289D01*
X1388084Y2181662D01*
X1387334Y2182222D01*
X1386834Y2182875D01*
X1386709Y2183622D01*
X1386834Y2184369D01*
X1387334Y2185022D01*
X1388084Y2185582D01*
X1388959Y2185955D01*
X1389959Y2186142D01*
X1390959D01*
X1391959Y2185955D01*
X1392834Y2185582D01*
X1393584Y2185022D01*
X1394084Y2184369D01*
X1394209Y2183622D01*
G01Y2188695D02*
X1386709D01*
X1392959Y2191122D01*
X1386709Y2193549D01*
X1394209D01*
G01Y2196195D02*
X1386709D01*
X1392959Y2198622D01*
X1386709Y2201049D01*
X1394209D01*
G01Y2207989D02*
Y2204255D01*
X1386709D01*
Y2207989D01*
G01X1390334Y2206495D02*
Y2204255D01*
G01X1394209Y2211475D02*
X1386709D01*
X1394209Y2215769D01*
X1386709D01*
G01X1394209Y2219069D02*
X1386709D01*
Y2220935D01*
X1387084Y2221682D01*
X1387584Y2222242D01*
X1388334Y2222709D01*
X1389209Y2223082D01*
X1390459Y2223175D01*
X1391709Y2223082D01*
X1392584Y2222709D01*
X1393334Y2222242D01*
X1393834Y2221682D01*
X1394209Y2220935D01*
Y2219069D01*
G01Y2230489D02*
Y2226755D01*
X1386709D01*
Y2230489D01*
G01X1390334Y2228995D02*
Y2226755D01*
G01X1394209Y2234069D02*
X1386709D01*
Y2235935D01*
X1387084Y2236682D01*
X1387584Y2237242D01*
X1388334Y2237709D01*
X1389209Y2238082D01*
X1390459Y2238175D01*
X1391709Y2238082D01*
X1392584Y2237709D01*
X1393334Y2237242D01*
X1393834Y2236682D01*
X1394209Y2235935D01*
Y2234069D01*
G01Y2249069D02*
X1386709D01*
Y2250935D01*
X1387084Y2251682D01*
X1387584Y2252242D01*
X1388334Y2252709D01*
X1389209Y2253082D01*
X1390459Y2253175D01*
X1391709Y2253082D01*
X1392584Y2252709D01*
X1393334Y2252242D01*
X1393834Y2251682D01*
X1394209Y2250935D01*
Y2249069D01*
G01Y2256755D02*
X1386709D01*
Y2259089D01*
X1387084Y2259835D01*
X1387584Y2260302D01*
X1388584Y2260489D01*
X1389584Y2260302D01*
X1390209Y2259742D01*
X1390584Y2259089D01*
Y2256755D01*
G01Y2259089D02*
X1394209Y2260489D01*
G01X1386709Y2265002D02*
Y2267242D01*
G01Y2266122D02*
X1394209D01*
G01Y2265002D02*
Y2267242D01*
G01X1386709Y2271755D02*
X1394209D01*
Y2275489D01*
G01X1386709Y2279255D02*
X1394209D01*
Y2282989D01*
G01X1393209Y2294162D02*
X1393834Y2294909D01*
X1394209Y2295749D01*
Y2296495D01*
X1393834Y2297242D01*
X1393209Y2297802D01*
X1392334Y2298082D01*
X1391459Y2297895D01*
X1390709Y2297429D01*
X1390209Y2296589D01*
X1389959Y2295469D01*
X1389459Y2294815D01*
X1388584Y2294535D01*
X1387709Y2294722D01*
X1387084Y2295189D01*
X1386709Y2295842D01*
Y2296495D01*
X1386959Y2297149D01*
X1387584Y2297709D01*
G01X1386709Y2302502D02*
Y2304742D01*
G01Y2303622D02*
X1394209D01*
G01Y2302502D02*
Y2304742D01*
G01X1386709Y2309349D02*
Y2312895D01*
X1394209Y2309349D01*
Y2312895D01*
G01Y2320489D02*
Y2316755D01*
X1386709D01*
Y2320489D01*
G01X1390334Y2318995D02*
Y2316755D01*
G01X1394209Y2331849D02*
X1386709D01*
Y2335395D01*
G01X1390334Y2334089D02*
Y2331849D01*
G01X1394209Y2341122D02*
X1394084Y2340375D01*
X1393584Y2339722D01*
X1392834Y2339162D01*
X1391959Y2338789D01*
X1390959Y2338602D01*
X1389959D01*
X1388959Y2338789D01*
X1388084Y2339162D01*
X1387334Y2339722D01*
X1386834Y2340375D01*
X1386709Y2341122D01*
X1386834Y2341869D01*
X1387334Y2342522D01*
X1388084Y2343082D01*
X1388959Y2343455D01*
X1389959Y2343642D01*
X1390959D01*
X1391959Y2343455D01*
X1392834Y2343082D01*
X1393584Y2342522D01*
X1394084Y2341869D01*
X1394209Y2341122D01*
G01Y2346755D02*
X1386709D01*
Y2349089D01*
X1387084Y2349835D01*
X1387584Y2350302D01*
X1388584Y2350489D01*
X1389584Y2350302D01*
X1390209Y2349742D01*
X1390584Y2349089D01*
Y2346755D01*
G01Y2349089D02*
X1394209Y2350489D01*
G01X1386709Y2363622D02*
X1386959Y2362875D01*
X1387584Y2362315D01*
X1388334Y2361942D01*
X1389334Y2361662D01*
X1390459Y2361569D01*
X1391584Y2361662D01*
X1392584Y2361942D01*
X1393334Y2362315D01*
X1393959Y2362875D01*
X1394209Y2363622D01*
X1393959Y2364369D01*
X1393334Y2364929D01*
X1392584Y2365302D01*
X1391584Y2365582D01*
X1390459Y2365675D01*
X1389334Y2365582D01*
X1388334Y2365302D01*
X1387584Y2364929D01*
X1386959Y2364369D01*
X1386709Y2363622D01*
G01X1394459Y2371122D02*
X1394334Y2370935D01*
X1394084D01*
X1393959Y2371122D01*
X1394084Y2371309D01*
X1394334D01*
X1394459Y2371122D01*
G01X1392709Y2376569D02*
X1393584Y2377129D01*
X1394084Y2377875D01*
X1394209Y2378715D01*
X1394084Y2379462D01*
X1393459Y2380209D01*
X1392709Y2380675D01*
X1391959Y2380769D01*
X1391084Y2380582D01*
X1390459Y2379929D01*
X1390209Y2379275D01*
Y2378435D01*
G01Y2379275D02*
X1389834Y2379835D01*
X1389209Y2380302D01*
X1388459Y2380489D01*
X1387709Y2380302D01*
X1387084Y2379835D01*
X1386709Y2378995D01*
X1386834Y2378155D01*
X1387334Y2377315D01*
G01X1391084Y2384349D02*
X1390209Y2385002D01*
X1389709Y2385562D01*
X1389459Y2386309D01*
X1389709Y2386962D01*
X1390209Y2387429D01*
X1390959Y2387802D01*
X1391834Y2387895D01*
X1392584Y2387802D01*
X1393334Y2387429D01*
X1393959Y2386869D01*
X1394209Y2386215D01*
X1393959Y2385469D01*
X1393209Y2384815D01*
X1392084Y2384442D01*
X1390834Y2384349D01*
X1389209Y2384535D01*
X1388334Y2384815D01*
X1387459Y2385282D01*
X1386834Y2385935D01*
X1386709Y2386589D01*
X1386959Y2387242D01*
X1387584Y2387709D01*
G01X1394209Y2391195D02*
X1386709D01*
X1392959Y2393622D01*
X1386709Y2396049D01*
X1394209D01*
G01Y2398695D02*
X1386709D01*
X1392959Y2401122D01*
X1386709Y2403549D01*
X1394209D01*
G01Y2414349D02*
X1386709D01*
Y2417895D01*
G01X1390334Y2416589D02*
Y2414349D01*
G01X1386709Y2422502D02*
Y2424742D01*
G01Y2423622D02*
X1394209D01*
G01Y2422502D02*
Y2424742D01*
G01Y2428975D02*
X1386709D01*
X1394209Y2433269D01*
X1386709D01*
G01Y2437502D02*
Y2439742D01*
G01Y2438622D02*
X1394209D01*
G01Y2437502D02*
Y2439742D01*
G01X1393209Y2444162D02*
X1393834Y2444909D01*
X1394209Y2445749D01*
Y2446495D01*
X1393834Y2447242D01*
X1393209Y2447802D01*
X1392334Y2448082D01*
X1391459Y2447895D01*
X1390709Y2447429D01*
X1390209Y2446589D01*
X1389959Y2445469D01*
X1389459Y2444815D01*
X1388584Y2444535D01*
X1387709Y2444722D01*
X1387084Y2445189D01*
X1386709Y2445842D01*
Y2446495D01*
X1386959Y2447149D01*
X1387584Y2447709D01*
G01X1394209Y2451662D02*
X1386709D01*
G01Y2455582D02*
X1394209D01*
G01X1390459D02*
Y2451662D01*
G01X1394209Y2462989D02*
Y2459255D01*
X1386709D01*
Y2462989D01*
G01X1390334Y2461495D02*
Y2459255D01*
G01X1394209Y2466569D02*
X1386709D01*
Y2468435D01*
X1387084Y2469182D01*
X1387584Y2469742D01*
X1388334Y2470209D01*
X1389209Y2470582D01*
X1390459Y2470675D01*
X1391709Y2470582D01*
X1392584Y2470209D01*
X1393334Y2469742D01*
X1393834Y2469182D01*
X1394209Y2468435D01*
Y2466569D01*
G01Y2481755D02*
X1386709D01*
Y2483995D01*
X1387084Y2484742D01*
X1387959Y2485302D01*
X1388959Y2485489D01*
X1389959Y2485302D01*
X1390709Y2484835D01*
X1391084Y2483995D01*
Y2481755D01*
G01X1386709Y2491122D02*
X1394209D01*
G01X1386709Y2488975D02*
Y2493269D01*
G01X1394209Y2496662D02*
X1386709D01*
G01Y2500582D02*
X1394209D01*
G01X1390459D02*
Y2496662D01*
G01X1386709Y2512502D02*
Y2514742D01*
G01Y2513622D02*
X1394209D01*
G01Y2512502D02*
Y2514742D01*
G01X1393209Y2519162D02*
X1393834Y2519909D01*
X1394209Y2520749D01*
Y2521495D01*
X1393834Y2522242D01*
X1393209Y2522802D01*
X1392334Y2523082D01*
X1391459Y2522895D01*
X1390709Y2522429D01*
X1390209Y2521589D01*
X1389959Y2520469D01*
X1389459Y2519815D01*
X1388584Y2519535D01*
X1387709Y2519722D01*
X1387084Y2520189D01*
X1386709Y2520842D01*
Y2521495D01*
X1386959Y2522149D01*
X1387584Y2522709D01*
G01X1386709Y2536122D02*
X1386959Y2535375D01*
X1387584Y2534815D01*
X1388334Y2534442D01*
X1389334Y2534162D01*
X1390459Y2534069D01*
X1391584Y2534162D01*
X1392584Y2534442D01*
X1393334Y2534815D01*
X1393959Y2535375D01*
X1394209Y2536122D01*
X1393959Y2536869D01*
X1393334Y2537429D01*
X1392584Y2537802D01*
X1391584Y2538082D01*
X1390459Y2538175D01*
X1389334Y2538082D01*
X1388334Y2537802D01*
X1387584Y2537429D01*
X1386959Y2536869D01*
X1386709Y2536122D01*
G01X1394459Y2543622D02*
X1394334Y2543435D01*
X1394084D01*
X1393959Y2543622D01*
X1394084Y2543809D01*
X1394334D01*
X1394459Y2543622D01*
G01X1394209Y2552242D02*
X1386709D01*
X1392084Y2548789D01*
Y2553455D01*
G01X1393084Y2556569D02*
X1393709Y2557129D01*
X1394084Y2557782D01*
X1394209Y2558622D01*
X1393959Y2559462D01*
X1393459Y2560115D01*
X1392584Y2560582D01*
X1391584Y2560675D01*
X1390584Y2560489D01*
X1389959Y2560022D01*
X1389459Y2559369D01*
X1389334Y2558715D01*
X1389459Y2558062D01*
X1389959Y2557222D01*
X1386709Y2557502D01*
Y2560022D01*
G01X1394209Y2563695D02*
X1386709D01*
X1392959Y2566122D01*
X1386709Y2568549D01*
X1394209D01*
G01Y2571195D02*
X1386709D01*
X1392959Y2573622D01*
X1386709Y2576049D01*
X1394209D01*
G01Y2586195D02*
X1386709D01*
X1392959Y2588622D01*
X1386709Y2591049D01*
X1394209D01*
G01Y2597989D02*
Y2594255D01*
X1386709D01*
Y2597989D01*
G01X1390334Y2596495D02*
Y2594255D01*
G01X1386709Y2603622D02*
X1394209D01*
G01X1386709Y2601475D02*
Y2605769D01*
G01X1394209Y2609255D02*
X1386709D01*
Y2611589D01*
X1387084Y2612335D01*
X1387584Y2612802D01*
X1388584Y2612989D01*
X1389584Y2612802D01*
X1390209Y2612242D01*
X1390584Y2611589D01*
Y2609255D01*
G01Y2611589D02*
X1394209Y2612989D01*
G01X1386709Y2617502D02*
Y2619742D01*
G01Y2618622D02*
X1394209D01*
G01Y2617502D02*
Y2619742D01*
G01X1387334Y2628175D02*
X1386959Y2627615D01*
X1386709Y2626962D01*
Y2626215D01*
X1387084Y2625375D01*
X1387709Y2624722D01*
X1388459Y2624255D01*
X1389709Y2623882D01*
X1390834Y2623789D01*
X1391959Y2623975D01*
X1392709Y2624255D01*
X1393459Y2624815D01*
X1393959Y2625469D01*
X1394209Y2626122D01*
Y2626775D01*
X1393959Y2627429D01*
X1393584Y2627989D01*
X1393084Y2628455D01*
G01X1394209Y2639069D02*
X1386709D01*
Y2640935D01*
X1387084Y2641682D01*
X1387584Y2642242D01*
X1388334Y2642709D01*
X1389209Y2643082D01*
X1390459Y2643175D01*
X1391709Y2643082D01*
X1392584Y2642709D01*
X1393334Y2642242D01*
X1393834Y2641682D01*
X1394209Y2640935D01*
Y2639069D01*
G01Y2646755D02*
X1386709D01*
Y2649089D01*
X1387084Y2649835D01*
X1387584Y2650302D01*
X1388584Y2650489D01*
X1389584Y2650302D01*
X1390209Y2649742D01*
X1390584Y2649089D01*
Y2646755D01*
G01Y2649089D02*
X1394209Y2650489D01*
G01X1386709Y2655002D02*
Y2657242D01*
G01Y2656122D02*
X1394209D01*
G01Y2655002D02*
Y2657242D01*
G01X1386709Y2661755D02*
X1394209D01*
Y2665489D01*
G01X1386709Y2669255D02*
X1394209D01*
Y2672989D01*
G01X1396709Y2678155D02*
X1395459Y2677222D01*
X1394209Y2676755D01*
X1389209D01*
X1387959Y2677222D01*
X1386709Y2678155D01*
G01Y2686122D02*
X1386959Y2685375D01*
X1387584Y2684815D01*
X1388334Y2684442D01*
X1389334Y2684162D01*
X1390459Y2684069D01*
X1391584Y2684162D01*
X1392584Y2684442D01*
X1393334Y2684815D01*
X1393959Y2685375D01*
X1394209Y2686122D01*
X1393959Y2686869D01*
X1393334Y2687429D01*
X1392584Y2687802D01*
X1391584Y2688082D01*
X1390459Y2688175D01*
X1389334Y2688082D01*
X1388334Y2687802D01*
X1387584Y2687429D01*
X1386959Y2686869D01*
X1386709Y2686122D01*
G01X1394459Y2693622D02*
X1394334Y2693435D01*
X1394084D01*
X1393959Y2693622D01*
X1394084Y2693809D01*
X1394334D01*
X1394459Y2693622D01*
G01X1386709Y2701122D02*
X1386959Y2700375D01*
X1387584Y2699815D01*
X1388334Y2699442D01*
X1389334Y2699162D01*
X1390459Y2699069D01*
X1391584Y2699162D01*
X1392584Y2699442D01*
X1393334Y2699815D01*
X1393959Y2700375D01*
X1394209Y2701122D01*
X1393959Y2701869D01*
X1393334Y2702429D01*
X1392584Y2702802D01*
X1391584Y2703082D01*
X1390459Y2703175D01*
X1389334Y2703082D01*
X1388334Y2702802D01*
X1387584Y2702429D01*
X1386959Y2701869D01*
X1386709Y2701122D01*
G01X1394209Y2708622D02*
X1386709D01*
X1388209Y2707502D01*
G01X1394209D02*
Y2709742D01*
G01Y2715935D02*
X1392584Y2716122D01*
X1391209Y2716402D01*
X1389959Y2716775D01*
X1388584Y2717242D01*
X1386709Y2717989D01*
Y2714255D01*
G01X1394209Y2723435D02*
X1392584Y2723622D01*
X1391209Y2723902D01*
X1389959Y2724275D01*
X1388584Y2724742D01*
X1386709Y2725489D01*
Y2721755D01*
G01X1388334Y2730282D02*
X1386709Y2730749D01*
G01Y2731962D02*
X1388334Y2731495D01*
G01X1396709Y2739089D02*
X1395459Y2740022D01*
X1394209Y2740489D01*
X1389209D01*
X1387959Y2740022D01*
X1386709Y2739089D01*
G01X1394459Y2746122D02*
X1394334Y2745935D01*
X1394084D01*
X1393959Y2746122D01*
X1394084Y2746309D01*
X1394334D01*
X1394459Y2746122D01*
G01X1422686Y-390297D02*
X1410186D01*
X1412686Y-392157D01*
G01X1422686D02*
Y-388437D01*
G01Y-376037D02*
X1410186D01*
X1419144Y-381772D01*
Y-374022D01*
G01X1422686Y-365497D02*
X1410186D01*
X1412686Y-367357D01*
G01X1422686D02*
Y-363637D01*
G01X1417478Y-356042D02*
X1416019Y-354957D01*
X1415186Y-354027D01*
X1414769Y-352787D01*
X1415186Y-351702D01*
X1416019Y-350927D01*
X1417269Y-350307D01*
X1418728Y-350152D01*
X1419978Y-350307D01*
X1421228Y-350927D01*
X1422269Y-351857D01*
X1422686Y-352942D01*
X1422269Y-354182D01*
X1421020Y-355267D01*
X1419144Y-355887D01*
X1417061Y-356042D01*
X1414353Y-355732D01*
X1412894Y-355267D01*
X1411436Y-354492D01*
X1410394Y-353407D01*
X1410186Y-352322D01*
X1410603Y-351237D01*
X1411644Y-350462D01*
G01X1422686Y-338837D02*
X1410186D01*
X1419144Y-344572D01*
Y-336822D01*
G01X1423103Y-328297D02*
X1422894Y-328607D01*
X1422478D01*
X1422269Y-328297D01*
X1422478Y-327987D01*
X1422894D01*
X1423103Y-328297D01*
G01X1420186Y-319307D02*
X1421645Y-318377D01*
X1422478Y-317137D01*
X1422686Y-315742D01*
X1422478Y-314502D01*
X1421436Y-313262D01*
X1420186Y-312487D01*
X1418936Y-312332D01*
X1417478Y-312642D01*
X1416436Y-313727D01*
X1416019Y-314812D01*
Y-316207D01*
G01Y-314812D02*
X1415394Y-313882D01*
X1414353Y-313107D01*
X1413103Y-312797D01*
X1411853Y-313107D01*
X1410811Y-313882D01*
X1410186Y-315277D01*
X1410394Y-316672D01*
X1411228Y-318067D01*
G01X1417478Y-306442D02*
X1416019Y-305357D01*
X1415186Y-304427D01*
X1414769Y-303187D01*
X1415186Y-302102D01*
X1416019Y-301327D01*
X1417269Y-300707D01*
X1418728Y-300552D01*
X1419978Y-300707D01*
X1421228Y-301327D01*
X1422269Y-302257D01*
X1422686Y-303342D01*
X1422269Y-304582D01*
X1421020Y-305667D01*
X1419144Y-306287D01*
X1417061Y-306442D01*
X1414353Y-306132D01*
X1412894Y-305667D01*
X1411436Y-304892D01*
X1410394Y-303807D01*
X1410186Y-302722D01*
X1410603Y-301637D01*
X1411644Y-300862D01*
G01X1420186Y-272307D02*
X1421645Y-271377D01*
X1422478Y-270137D01*
X1422686Y-268742D01*
X1422478Y-267502D01*
X1421436Y-266262D01*
X1420186Y-265487D01*
X1418936Y-265332D01*
X1417478Y-265642D01*
X1416436Y-266727D01*
X1416019Y-267812D01*
Y-269207D01*
G01Y-267812D02*
X1415394Y-266882D01*
X1414353Y-266107D01*
X1413103Y-265797D01*
X1411853Y-266107D01*
X1410811Y-266882D01*
X1410186Y-268277D01*
X1410394Y-269672D01*
X1411228Y-271067D01*
G01X1420811Y-259907D02*
X1421853Y-258977D01*
X1422478Y-257892D01*
X1422686Y-256497D01*
X1422269Y-255102D01*
X1421436Y-254017D01*
X1419978Y-253242D01*
X1418311Y-253087D01*
X1416644Y-253397D01*
X1415603Y-254172D01*
X1414769Y-255257D01*
X1414561Y-256342D01*
X1414769Y-257427D01*
X1415603Y-258822D01*
X1410186Y-258357D01*
Y-254172D01*
G01X1421228Y-246732D02*
X1422269Y-245647D01*
X1422686Y-244407D01*
X1422269Y-243167D01*
X1421020Y-242082D01*
X1419144Y-241307D01*
X1417269Y-240997D01*
X1414978D01*
X1413103Y-241307D01*
X1411436Y-242082D01*
X1410603Y-243012D01*
X1410186Y-244097D01*
X1410603Y-245337D01*
X1411436Y-246267D01*
X1412686Y-246887D01*
X1414353Y-247197D01*
X1415811Y-246887D01*
X1417269Y-246112D01*
X1418103Y-245182D01*
X1418311Y-244097D01*
X1417895Y-242857D01*
X1416853Y-241927D01*
X1414978Y-240997D01*
G01X1423103Y-231697D02*
X1422894Y-232007D01*
X1422478D01*
X1422269Y-231697D01*
X1422478Y-231387D01*
X1422894D01*
X1423103Y-231697D01*
G01X1422686Y-219607D02*
X1419978Y-219297D01*
X1417686Y-218832D01*
X1415603Y-218212D01*
X1413311Y-217437D01*
X1410186Y-216197D01*
Y-222397D01*
G01X1422686Y-207207D02*
X1419978Y-206897D01*
X1417686Y-206432D01*
X1415603Y-205812D01*
X1413311Y-205037D01*
X1410186Y-203797D01*
Y-209997D01*
G01X1401134Y2057925D02*
X1400759Y2057365D01*
X1400509Y2056712D01*
Y2055965D01*
X1400884Y2055125D01*
X1401509Y2054472D01*
X1402259Y2054005D01*
X1403509Y2053632D01*
X1404634Y2053539D01*
X1405759Y2053725D01*
X1406509Y2054005D01*
X1407259Y2054565D01*
X1407759Y2055219D01*
X1408009Y2055872D01*
Y2056525D01*
X1407759Y2057179D01*
X1407384Y2057739D01*
X1406884Y2058205D01*
G01X1408009Y2063372D02*
X1407884Y2062625D01*
X1407384Y2061972D01*
X1406634Y2061412D01*
X1405759Y2061039D01*
X1404759Y2060852D01*
X1403759D01*
X1402759Y2061039D01*
X1401884Y2061412D01*
X1401134Y2061972D01*
X1400634Y2062625D01*
X1400509Y2063372D01*
X1400634Y2064119D01*
X1401134Y2064772D01*
X1401884Y2065332D01*
X1402759Y2065705D01*
X1403759Y2065892D01*
X1404759D01*
X1405759Y2065705D01*
X1406634Y2065332D01*
X1407384Y2064772D01*
X1407884Y2064119D01*
X1408009Y2063372D01*
G01Y2069005D02*
X1400509D01*
Y2071245D01*
X1400884Y2071992D01*
X1401759Y2072552D01*
X1402759Y2072739D01*
X1403759Y2072552D01*
X1404509Y2072085D01*
X1404884Y2071245D01*
Y2069005D01*
G01X1408009Y2076505D02*
X1400509D01*
Y2078745D01*
X1400884Y2079492D01*
X1401759Y2080052D01*
X1402759Y2080239D01*
X1403759Y2080052D01*
X1404509Y2079585D01*
X1404884Y2078745D01*
Y2076505D01*
G01X1408009Y2087739D02*
Y2084005D01*
X1400509D01*
Y2087739D01*
G01X1404134Y2086245D02*
Y2084005D01*
G01X1408009Y2091505D02*
X1400509D01*
Y2093839D01*
X1400884Y2094585D01*
X1401384Y2095052D01*
X1402384Y2095239D01*
X1403384Y2095052D01*
X1404009Y2094492D01*
X1404384Y2093839D01*
Y2091505D01*
G01Y2093839D02*
X1408009Y2095239D01*
G01Y2108372D02*
X1407884Y2107625D01*
X1407384Y2106972D01*
X1406634Y2106412D01*
X1405759Y2106039D01*
X1404759Y2105852D01*
X1403759D01*
X1402759Y2106039D01*
X1401884Y2106412D01*
X1401134Y2106972D01*
X1400634Y2107625D01*
X1400509Y2108372D01*
X1400634Y2109119D01*
X1401134Y2109772D01*
X1401884Y2110332D01*
X1402759Y2110705D01*
X1403759Y2110892D01*
X1404759D01*
X1405759Y2110705D01*
X1406634Y2110332D01*
X1407384Y2109772D01*
X1407884Y2109119D01*
X1408009Y2108372D01*
G01X1407009Y2113912D02*
X1407634Y2114659D01*
X1408009Y2115499D01*
Y2116245D01*
X1407634Y2116992D01*
X1407009Y2117552D01*
X1406134Y2117832D01*
X1405259Y2117645D01*
X1404509Y2117179D01*
X1404009Y2116339D01*
X1403759Y2115219D01*
X1403259Y2114565D01*
X1402384Y2114285D01*
X1401509Y2114472D01*
X1400884Y2114939D01*
X1400509Y2115592D01*
Y2116245D01*
X1400759Y2116899D01*
X1401384Y2117459D01*
G01X1408009Y2121505D02*
X1400509D01*
Y2123745D01*
X1400884Y2124492D01*
X1401759Y2125052D01*
X1402759Y2125239D01*
X1403759Y2125052D01*
X1404509Y2124585D01*
X1404884Y2123745D01*
Y2121505D01*
G01X1408259Y2129192D02*
X1400509Y2132552D01*
G01Y2138372D02*
X1408009D01*
G01X1400509Y2136225D02*
Y2140519D01*
G01Y2144752D02*
Y2146992D01*
G01Y2145872D02*
X1408009D01*
G01Y2144752D02*
Y2146992D01*
G01Y2151225D02*
X1400509D01*
X1408009Y2155519D01*
X1400509D01*
G01X1410509Y2160405D02*
X1409259Y2159472D01*
X1408009Y2159005D01*
X1403009D01*
X1401759Y2159472D01*
X1400509Y2160405D01*
G01Y2167252D02*
Y2169492D01*
G01Y2168372D02*
X1408009D01*
G01Y2167252D02*
Y2169492D01*
G01Y2173445D02*
X1400509D01*
X1406759Y2175872D01*
X1400509Y2178299D01*
X1408009D01*
G01Y2180945D02*
X1400509D01*
X1406759Y2183372D01*
X1400509Y2185799D01*
X1408009D01*
G01Y2192739D02*
Y2189005D01*
X1400509D01*
Y2192739D01*
G01X1404134Y2191245D02*
Y2189005D01*
G01X1408009Y2196505D02*
X1400509D01*
Y2198839D01*
X1400884Y2199585D01*
X1401384Y2200052D01*
X1402384Y2200239D01*
X1403384Y2200052D01*
X1404009Y2199492D01*
X1404384Y2198839D01*
Y2196505D01*
G01Y2198839D02*
X1408009Y2200239D01*
G01X1407009Y2203912D02*
X1407634Y2204659D01*
X1408009Y2205499D01*
Y2206245D01*
X1407634Y2206992D01*
X1407009Y2207552D01*
X1406134Y2207832D01*
X1405259Y2207645D01*
X1404509Y2207179D01*
X1404009Y2206339D01*
X1403759Y2205219D01*
X1403259Y2204565D01*
X1402384Y2204285D01*
X1401509Y2204472D01*
X1400884Y2204939D01*
X1400509Y2205592D01*
Y2206245D01*
X1400759Y2206899D01*
X1401384Y2207459D01*
G01X1400509Y2212252D02*
Y2214492D01*
G01Y2213372D02*
X1408009D01*
G01Y2212252D02*
Y2214492D01*
G01Y2220872D02*
X1407884Y2220125D01*
X1407384Y2219472D01*
X1406634Y2218912D01*
X1405759Y2218539D01*
X1404759Y2218352D01*
X1403759D01*
X1402759Y2218539D01*
X1401884Y2218912D01*
X1401134Y2219472D01*
X1400634Y2220125D01*
X1400509Y2220872D01*
X1400634Y2221619D01*
X1401134Y2222272D01*
X1401884Y2222832D01*
X1402759Y2223205D01*
X1403759Y2223392D01*
X1404759D01*
X1405759Y2223205D01*
X1406634Y2222832D01*
X1407384Y2222272D01*
X1407884Y2221619D01*
X1408009Y2220872D01*
G01Y2226225D02*
X1400509D01*
X1408009Y2230519D01*
X1400509D01*
G01X1410509Y2236339D02*
X1409259Y2237272D01*
X1408009Y2237739D01*
X1403009D01*
X1401759Y2237272D01*
X1400509Y2236339D01*
G01X1408259Y2243372D02*
X1408134Y2243185D01*
X1407884D01*
X1407759Y2243372D01*
X1407884Y2243559D01*
X1408134D01*
X1408259Y2243372D01*
G01X1404884D02*
X1404759Y2243185D01*
X1404509D01*
X1404384Y2243372D01*
X1404509Y2243559D01*
X1404759D01*
X1404884Y2243372D01*
G01X1408009Y2249005D02*
X1400509D01*
Y2251339D01*
X1400884Y2252085D01*
X1401384Y2252552D01*
X1402384Y2252739D01*
X1403384Y2252552D01*
X1404009Y2251992D01*
X1404384Y2251339D01*
Y2249005D01*
G01Y2251339D02*
X1408009Y2252739D01*
G01Y2260239D02*
Y2256505D01*
X1400509D01*
Y2260239D01*
G01X1404134Y2258745D02*
Y2256505D01*
G01X1401134Y2267925D02*
X1400759Y2267365D01*
X1400509Y2266712D01*
Y2265965D01*
X1400884Y2265125D01*
X1401509Y2264472D01*
X1402259Y2264005D01*
X1403509Y2263632D01*
X1404634Y2263539D01*
X1405759Y2263725D01*
X1406509Y2264005D01*
X1407259Y2264565D01*
X1407759Y2265219D01*
X1408009Y2265872D01*
Y2266525D01*
X1407759Y2267179D01*
X1407384Y2267739D01*
X1406884Y2268205D01*
G01X1408009Y2273372D02*
X1407884Y2272625D01*
X1407384Y2271972D01*
X1406634Y2271412D01*
X1405759Y2271039D01*
X1404759Y2270852D01*
X1403759D01*
X1402759Y2271039D01*
X1401884Y2271412D01*
X1401134Y2271972D01*
X1400634Y2272625D01*
X1400509Y2273372D01*
X1400634Y2274119D01*
X1401134Y2274772D01*
X1401884Y2275332D01*
X1402759Y2275705D01*
X1403759Y2275892D01*
X1404759D01*
X1405759Y2275705D01*
X1406634Y2275332D01*
X1407384Y2274772D01*
X1407884Y2274119D01*
X1408009Y2273372D01*
G01Y2278445D02*
X1400509D01*
X1406759Y2280872D01*
X1400509Y2283299D01*
X1408009D01*
G01Y2285945D02*
X1400509D01*
X1406759Y2288372D01*
X1400509Y2290799D01*
X1408009D01*
G01Y2297739D02*
Y2294005D01*
X1400509D01*
Y2297739D01*
G01X1404134Y2296245D02*
Y2294005D01*
G01X1408009Y2301225D02*
X1400509D01*
X1408009Y2305519D01*
X1400509D01*
G01X1408009Y2308819D02*
X1400509D01*
Y2310685D01*
X1400884Y2311432D01*
X1401384Y2311992D01*
X1402134Y2312459D01*
X1403009Y2312832D01*
X1404259Y2312925D01*
X1405509Y2312832D01*
X1406384Y2312459D01*
X1407134Y2311992D01*
X1407634Y2311432D01*
X1408009Y2310685D01*
Y2308819D01*
G01Y2320239D02*
Y2316505D01*
X1400509D01*
Y2320239D01*
G01X1404134Y2318745D02*
Y2316505D01*
G01X1408009Y2323819D02*
X1400509D01*
Y2325685D01*
X1400884Y2326432D01*
X1401384Y2326992D01*
X1402134Y2327459D01*
X1403009Y2327832D01*
X1404259Y2327925D01*
X1405509Y2327832D01*
X1406384Y2327459D01*
X1407134Y2326992D01*
X1407634Y2326432D01*
X1408009Y2325685D01*
Y2323819D01*
G01Y2338819D02*
X1400509D01*
Y2340685D01*
X1400884Y2341432D01*
X1401384Y2341992D01*
X1402134Y2342459D01*
X1403009Y2342832D01*
X1404259Y2342925D01*
X1405509Y2342832D01*
X1406384Y2342459D01*
X1407134Y2341992D01*
X1407634Y2341432D01*
X1408009Y2340685D01*
Y2338819D01*
G01Y2346505D02*
X1400509D01*
Y2348839D01*
X1400884Y2349585D01*
X1401384Y2350052D01*
X1402384Y2350239D01*
X1403384Y2350052D01*
X1404009Y2349492D01*
X1404384Y2348839D01*
Y2346505D01*
G01Y2348839D02*
X1408009Y2350239D01*
G01X1400509Y2354752D02*
Y2356992D01*
G01Y2355872D02*
X1408009D01*
G01Y2354752D02*
Y2356992D01*
G01X1400509Y2361505D02*
X1408009D01*
Y2365239D01*
G01X1400509Y2369005D02*
X1408009D01*
Y2372739D01*
G01X1407009Y2383912D02*
X1407634Y2384659D01*
X1408009Y2385499D01*
Y2386245D01*
X1407634Y2386992D01*
X1407009Y2387552D01*
X1406134Y2387832D01*
X1405259Y2387645D01*
X1404509Y2387179D01*
X1404009Y2386339D01*
X1403759Y2385219D01*
X1403259Y2384565D01*
X1402384Y2384285D01*
X1401509Y2384472D01*
X1400884Y2384939D01*
X1400509Y2385592D01*
Y2386245D01*
X1400759Y2386899D01*
X1401384Y2387459D01*
G01X1400509Y2392252D02*
Y2394492D01*
G01Y2393372D02*
X1408009D01*
G01Y2392252D02*
Y2394492D01*
G01X1400509Y2399099D02*
Y2402645D01*
X1408009Y2399099D01*
Y2402645D01*
G01Y2410239D02*
Y2406505D01*
X1400509D01*
Y2410239D01*
G01X1404134Y2408745D02*
Y2406505D01*
G01X1408009Y2421599D02*
X1400509D01*
Y2425145D01*
G01X1404134Y2423839D02*
Y2421599D01*
G01X1408009Y2430872D02*
X1407884Y2430125D01*
X1407384Y2429472D01*
X1406634Y2428912D01*
X1405759Y2428539D01*
X1404759Y2428352D01*
X1403759D01*
X1402759Y2428539D01*
X1401884Y2428912D01*
X1401134Y2429472D01*
X1400634Y2430125D01*
X1400509Y2430872D01*
X1400634Y2431619D01*
X1401134Y2432272D01*
X1401884Y2432832D01*
X1402759Y2433205D01*
X1403759Y2433392D01*
X1404759D01*
X1405759Y2433205D01*
X1406634Y2432832D01*
X1407384Y2432272D01*
X1407884Y2431619D01*
X1408009Y2430872D01*
G01Y2436505D02*
X1400509D01*
Y2438839D01*
X1400884Y2439585D01*
X1401384Y2440052D01*
X1402384Y2440239D01*
X1403384Y2440052D01*
X1404009Y2439492D01*
X1404384Y2438839D01*
Y2436505D01*
G01Y2438839D02*
X1408009Y2440239D01*
G01X1400509Y2453372D02*
X1400759Y2452625D01*
X1401384Y2452065D01*
X1402134Y2451692D01*
X1403134Y2451412D01*
X1404259Y2451319D01*
X1405384Y2451412D01*
X1406384Y2451692D01*
X1407134Y2452065D01*
X1407759Y2452625D01*
X1408009Y2453372D01*
X1407759Y2454119D01*
X1407134Y2454679D01*
X1406384Y2455052D01*
X1405384Y2455332D01*
X1404259Y2455425D01*
X1403134Y2455332D01*
X1402134Y2455052D01*
X1401384Y2454679D01*
X1400759Y2454119D01*
X1400509Y2453372D01*
G01X1408259Y2460872D02*
X1408134Y2460685D01*
X1407884D01*
X1407759Y2460872D01*
X1407884Y2461059D01*
X1408134D01*
X1408259Y2460872D01*
G01X1406509Y2466319D02*
X1407384Y2466879D01*
X1407884Y2467625D01*
X1408009Y2468465D01*
X1407884Y2469212D01*
X1407259Y2469959D01*
X1406509Y2470425D01*
X1405759Y2470519D01*
X1404884Y2470332D01*
X1404259Y2469679D01*
X1404009Y2469025D01*
Y2468185D01*
G01Y2469025D02*
X1403634Y2469585D01*
X1403009Y2470052D01*
X1402259Y2470239D01*
X1401509Y2470052D01*
X1400884Y2469585D01*
X1400509Y2468745D01*
X1400634Y2467905D01*
X1401134Y2467065D01*
G01X1404884Y2474099D02*
X1404009Y2474752D01*
X1403509Y2475312D01*
X1403259Y2476059D01*
X1403509Y2476712D01*
X1404009Y2477179D01*
X1404759Y2477552D01*
X1405634Y2477645D01*
X1406384Y2477552D01*
X1407134Y2477179D01*
X1407759Y2476619D01*
X1408009Y2475965D01*
X1407759Y2475219D01*
X1407009Y2474565D01*
X1405884Y2474192D01*
X1404634Y2474099D01*
X1403009Y2474285D01*
X1402134Y2474565D01*
X1401259Y2475032D01*
X1400634Y2475685D01*
X1400509Y2476339D01*
X1400759Y2476992D01*
X1401384Y2477459D01*
G01X1408009Y2480945D02*
X1400509D01*
X1406759Y2483372D01*
X1400509Y2485799D01*
X1408009D01*
G01Y2488445D02*
X1400509D01*
X1406759Y2490872D01*
X1400509Y2493299D01*
X1408009D01*
G01Y2504099D02*
X1400509D01*
Y2507645D01*
G01X1404134Y2506339D02*
Y2504099D01*
G01X1400509Y2512252D02*
Y2514492D01*
G01Y2513372D02*
X1408009D01*
G01Y2512252D02*
Y2514492D01*
G01Y2518725D02*
X1400509D01*
X1408009Y2523019D01*
X1400509D01*
G01Y2527252D02*
Y2529492D01*
G01Y2528372D02*
X1408009D01*
G01Y2527252D02*
Y2529492D01*
G01X1407009Y2533912D02*
X1407634Y2534659D01*
X1408009Y2535499D01*
Y2536245D01*
X1407634Y2536992D01*
X1407009Y2537552D01*
X1406134Y2537832D01*
X1405259Y2537645D01*
X1404509Y2537179D01*
X1404009Y2536339D01*
X1403759Y2535219D01*
X1403259Y2534565D01*
X1402384Y2534285D01*
X1401509Y2534472D01*
X1400884Y2534939D01*
X1400509Y2535592D01*
Y2536245D01*
X1400759Y2536899D01*
X1401384Y2537459D01*
G01X1408009Y2541412D02*
X1400509D01*
G01Y2545332D02*
X1408009D01*
G01X1404259D02*
Y2541412D01*
G01X1408009Y2552739D02*
Y2549005D01*
X1400509D01*
Y2552739D01*
G01X1404134Y2551245D02*
Y2549005D01*
G01X1408009Y2556319D02*
X1400509D01*
Y2558185D01*
X1400884Y2558932D01*
X1401384Y2559492D01*
X1402134Y2559959D01*
X1403009Y2560332D01*
X1404259Y2560425D01*
X1405509Y2560332D01*
X1406384Y2559959D01*
X1407134Y2559492D01*
X1407634Y2558932D01*
X1408009Y2558185D01*
Y2556319D01*
G01Y2571505D02*
X1400509D01*
Y2573745D01*
X1400884Y2574492D01*
X1401759Y2575052D01*
X1402759Y2575239D01*
X1403759Y2575052D01*
X1404509Y2574585D01*
X1404884Y2573745D01*
Y2571505D01*
G01X1400509Y2580872D02*
X1408009D01*
G01X1400509Y2578725D02*
Y2583019D01*
G01X1408009Y2586412D02*
X1400509D01*
G01Y2590332D02*
X1408009D01*
G01X1404259D02*
Y2586412D01*
G01X1400509Y2602252D02*
Y2604492D01*
G01Y2603372D02*
X1408009D01*
G01Y2602252D02*
Y2604492D01*
G01X1407009Y2608912D02*
X1407634Y2609659D01*
X1408009Y2610499D01*
Y2611245D01*
X1407634Y2611992D01*
X1407009Y2612552D01*
X1406134Y2612832D01*
X1405259Y2612645D01*
X1404509Y2612179D01*
X1404009Y2611339D01*
X1403759Y2610219D01*
X1403259Y2609565D01*
X1402384Y2609285D01*
X1401509Y2609472D01*
X1400884Y2609939D01*
X1400509Y2610592D01*
Y2611245D01*
X1400759Y2611899D01*
X1401384Y2612459D01*
G01X1400509Y2625872D02*
X1400759Y2625125D01*
X1401384Y2624565D01*
X1402134Y2624192D01*
X1403134Y2623912D01*
X1404259Y2623819D01*
X1405384Y2623912D01*
X1406384Y2624192D01*
X1407134Y2624565D01*
X1407759Y2625125D01*
X1408009Y2625872D01*
X1407759Y2626619D01*
X1407134Y2627179D01*
X1406384Y2627552D01*
X1405384Y2627832D01*
X1404259Y2627925D01*
X1403134Y2627832D01*
X1402134Y2627552D01*
X1401384Y2627179D01*
X1400759Y2626619D01*
X1400509Y2625872D01*
G01X1408259Y2633372D02*
X1408134Y2633185D01*
X1407884D01*
X1407759Y2633372D01*
X1407884Y2633559D01*
X1408134D01*
X1408259Y2633372D01*
G01X1408009Y2641992D02*
X1400509D01*
X1405884Y2638539D01*
Y2643205D01*
G01X1406884Y2646319D02*
X1407509Y2646879D01*
X1407884Y2647532D01*
X1408009Y2648372D01*
X1407759Y2649212D01*
X1407259Y2649865D01*
X1406384Y2650332D01*
X1405384Y2650425D01*
X1404384Y2650239D01*
X1403759Y2649772D01*
X1403259Y2649119D01*
X1403134Y2648465D01*
X1403259Y2647812D01*
X1403759Y2646972D01*
X1400509Y2647252D01*
Y2649772D01*
G01X1408009Y2653445D02*
X1400509D01*
X1406759Y2655872D01*
X1400509Y2658299D01*
X1408009D01*
G01Y2660945D02*
X1400509D01*
X1406759Y2663372D01*
X1400509Y2665799D01*
X1408009D01*
G01Y2675945D02*
X1400509D01*
X1406759Y2678372D01*
X1400509Y2680799D01*
X1408009D01*
G01Y2687739D02*
Y2684005D01*
X1400509D01*
Y2687739D01*
G01X1404134Y2686245D02*
Y2684005D01*
G01X1400509Y2693372D02*
X1408009D01*
G01X1400509Y2691225D02*
Y2695519D01*
G01X1408009Y2699005D02*
X1400509D01*
Y2701339D01*
X1400884Y2702085D01*
X1401384Y2702552D01*
X1402384Y2702739D01*
X1403384Y2702552D01*
X1404009Y2701992D01*
X1404384Y2701339D01*
Y2699005D01*
G01Y2701339D02*
X1408009Y2702739D01*
G01X1400509Y2707252D02*
Y2709492D01*
G01Y2708372D02*
X1408009D01*
G01Y2707252D02*
Y2709492D01*
G01X1401134Y2717925D02*
X1400759Y2717365D01*
X1400509Y2716712D01*
Y2715965D01*
X1400884Y2715125D01*
X1401509Y2714472D01*
X1402259Y2714005D01*
X1403509Y2713632D01*
X1404634Y2713539D01*
X1405759Y2713725D01*
X1406509Y2714005D01*
X1407259Y2714565D01*
X1407759Y2715219D01*
X1408009Y2715872D01*
Y2716525D01*
X1407759Y2717179D01*
X1407384Y2717739D01*
X1406884Y2718205D01*
G01X1408009Y2728819D02*
X1400509D01*
Y2730685D01*
X1400884Y2731432D01*
X1401384Y2731992D01*
X1402134Y2732459D01*
X1403009Y2732832D01*
X1404259Y2732925D01*
X1405509Y2732832D01*
X1406384Y2732459D01*
X1407134Y2731992D01*
X1407634Y2731432D01*
X1408009Y2730685D01*
Y2728819D01*
G01Y2736505D02*
X1400509D01*
Y2738839D01*
X1400884Y2739585D01*
X1401384Y2740052D01*
X1402384Y2740239D01*
X1403384Y2740052D01*
X1404009Y2739492D01*
X1404384Y2738839D01*
Y2736505D01*
G01Y2738839D02*
X1408009Y2740239D01*
G01X1400509Y2744752D02*
Y2746992D01*
G01Y2745872D02*
X1408009D01*
G01Y2744752D02*
Y2746992D01*
G01X1400509Y2751505D02*
X1408009D01*
Y2755239D01*
G01X1400509Y2759005D02*
X1408009D01*
Y2762739D01*
G01X1410509Y2767905D02*
X1409259Y2766972D01*
X1408009Y2766505D01*
X1403009D01*
X1401759Y2766972D01*
X1400509Y2767905D01*
G01Y2775872D02*
X1400759Y2775125D01*
X1401384Y2774565D01*
X1402134Y2774192D01*
X1403134Y2773912D01*
X1404259Y2773819D01*
X1405384Y2773912D01*
X1406384Y2774192D01*
X1407134Y2774565D01*
X1407759Y2775125D01*
X1408009Y2775872D01*
X1407759Y2776619D01*
X1407134Y2777179D01*
X1406384Y2777552D01*
X1405384Y2777832D01*
X1404259Y2777925D01*
X1403134Y2777832D01*
X1402134Y2777552D01*
X1401384Y2777179D01*
X1400759Y2776619D01*
X1400509Y2775872D01*
G01X1408259Y2783372D02*
X1408134Y2783185D01*
X1407884D01*
X1407759Y2783372D01*
X1407884Y2783559D01*
X1408134D01*
X1408259Y2783372D01*
G01X1400509Y2790872D02*
X1400759Y2790125D01*
X1401384Y2789565D01*
X1402134Y2789192D01*
X1403134Y2788912D01*
X1404259Y2788819D01*
X1405384Y2788912D01*
X1406384Y2789192D01*
X1407134Y2789565D01*
X1407759Y2790125D01*
X1408009Y2790872D01*
X1407759Y2791619D01*
X1407134Y2792179D01*
X1406384Y2792552D01*
X1405384Y2792832D01*
X1404259Y2792925D01*
X1403134Y2792832D01*
X1402134Y2792552D01*
X1401384Y2792179D01*
X1400759Y2791619D01*
X1400509Y2790872D01*
G01X1408009Y2798372D02*
X1400509D01*
X1402009Y2797252D01*
G01X1408009D02*
Y2799492D01*
G01Y2805685D02*
X1406384Y2805872D01*
X1405009Y2806152D01*
X1403759Y2806525D01*
X1402384Y2806992D01*
X1400509Y2807739D01*
Y2804005D01*
G01X1408009Y2813185D02*
X1406384Y2813372D01*
X1405009Y2813652D01*
X1403759Y2814025D01*
X1402384Y2814492D01*
X1400509Y2815239D01*
Y2811505D01*
G01X1402134Y2820032D02*
X1400509Y2820499D01*
G01Y2821712D02*
X1402134Y2821245D01*
G01X1410509Y2828839D02*
X1409259Y2829772D01*
X1408009Y2830239D01*
X1403009D01*
X1401759Y2829772D01*
X1400509Y2828839D01*
G01X1408259Y2835872D02*
X1408134Y2835685D01*
X1407884D01*
X1407759Y2835872D01*
X1407884Y2836059D01*
X1408134D01*
X1408259Y2835872D01*
G01X1418989Y2052740D02*
X1419614Y2053487D01*
X1419989Y2054327D01*
Y2055073D01*
X1419614Y2055820D01*
X1418989Y2056380D01*
X1418114Y2056660D01*
X1417239Y2056473D01*
X1416489Y2056007D01*
X1415989Y2055167D01*
X1415739Y2054047D01*
X1415239Y2053393D01*
X1414364Y2053113D01*
X1413489Y2053300D01*
X1412864Y2053767D01*
X1412489Y2054420D01*
Y2055073D01*
X1412739Y2055727D01*
X1413364Y2056287D01*
G01X1412489Y2061080D02*
Y2063320D01*
G01Y2062200D02*
X1419989D01*
G01Y2061080D02*
Y2063320D01*
G01X1412489Y2067833D02*
X1419989D01*
Y2071567D01*
G01X1412489Y2074867D02*
X1419989Y2077200D01*
X1412489Y2079533D01*
G01X1419989Y2086567D02*
Y2082833D01*
X1412489D01*
Y2086567D01*
G01X1416114Y2085073D02*
Y2082833D01*
G01X1419989Y2090333D02*
X1412489D01*
Y2092667D01*
X1412864Y2093413D01*
X1413364Y2093880D01*
X1414364Y2094067D01*
X1415364Y2093880D01*
X1415989Y2093320D01*
X1416364Y2092667D01*
Y2090333D01*
G01Y2092667D02*
X1419989Y2094067D01*
G01X1422489Y2099233D02*
X1421239Y2098300D01*
X1419989Y2097833D01*
X1414989D01*
X1413739Y2098300D01*
X1412489Y2099233D01*
G01Y2106080D02*
Y2108320D01*
G01Y2107200D02*
X1419989D01*
G01Y2106080D02*
Y2108320D01*
G01Y2112273D02*
X1412489D01*
X1418739Y2114700D01*
X1412489Y2117127D01*
X1419989D01*
G01Y2119773D02*
X1412489D01*
X1418739Y2122200D01*
X1412489Y2124627D01*
X1419989D01*
G01Y2131567D02*
Y2127833D01*
X1412489D01*
Y2131567D01*
G01X1416114Y2130073D02*
Y2127833D01*
G01X1419989Y2135333D02*
X1412489D01*
Y2137667D01*
X1412864Y2138413D01*
X1413364Y2138880D01*
X1414364Y2139067D01*
X1415364Y2138880D01*
X1415989Y2138320D01*
X1416364Y2137667D01*
Y2135333D01*
G01Y2137667D02*
X1419989Y2139067D01*
G01X1418989Y2142740D02*
X1419614Y2143487D01*
X1419989Y2144327D01*
Y2145073D01*
X1419614Y2145820D01*
X1418989Y2146380D01*
X1418114Y2146660D01*
X1417239Y2146473D01*
X1416489Y2146007D01*
X1415989Y2145167D01*
X1415739Y2144047D01*
X1415239Y2143393D01*
X1414364Y2143113D01*
X1413489Y2143300D01*
X1412864Y2143767D01*
X1412489Y2144420D01*
Y2145073D01*
X1412739Y2145727D01*
X1413364Y2146287D01*
G01X1412489Y2151080D02*
Y2153320D01*
G01Y2152200D02*
X1419989D01*
G01Y2151080D02*
Y2153320D01*
G01Y2159700D02*
X1419864Y2158953D01*
X1419364Y2158300D01*
X1418614Y2157740D01*
X1417739Y2157367D01*
X1416739Y2157180D01*
X1415739D01*
X1414739Y2157367D01*
X1413864Y2157740D01*
X1413114Y2158300D01*
X1412614Y2158953D01*
X1412489Y2159700D01*
X1412614Y2160447D01*
X1413114Y2161100D01*
X1413864Y2161660D01*
X1414739Y2162033D01*
X1415739Y2162220D01*
X1416739D01*
X1417739Y2162033D01*
X1418614Y2161660D01*
X1419364Y2161100D01*
X1419864Y2160447D01*
X1419989Y2159700D01*
G01Y2165053D02*
X1412489D01*
X1419989Y2169347D01*
X1412489D01*
G01X1422489Y2175167D02*
X1421239Y2176100D01*
X1419989Y2176567D01*
X1414989D01*
X1413739Y2176100D01*
X1412489Y2175167D01*
G01X1420239Y2182200D02*
X1420114Y2182013D01*
X1419864D01*
X1419739Y2182200D01*
X1419864Y2182387D01*
X1420114D01*
X1420239Y2182200D01*
G01X1416864D02*
X1416739Y2182013D01*
X1416489D01*
X1416364Y2182200D01*
X1416489Y2182387D01*
X1416739D01*
X1416864Y2182200D01*
G01X1419989Y2187833D02*
X1412489D01*
Y2190167D01*
X1412864Y2190913D01*
X1413364Y2191380D01*
X1414364Y2191567D01*
X1415364Y2191380D01*
X1415989Y2190820D01*
X1416364Y2190167D01*
Y2187833D01*
G01Y2190167D02*
X1419989Y2191567D01*
G01Y2199067D02*
Y2195333D01*
X1412489D01*
Y2199067D01*
G01X1416114Y2197573D02*
Y2195333D01*
G01X1413114Y2206753D02*
X1412739Y2206193D01*
X1412489Y2205540D01*
Y2204793D01*
X1412864Y2203953D01*
X1413489Y2203300D01*
X1414239Y2202833D01*
X1415489Y2202460D01*
X1416614Y2202367D01*
X1417739Y2202553D01*
X1418489Y2202833D01*
X1419239Y2203393D01*
X1419739Y2204047D01*
X1419989Y2204700D01*
Y2205353D01*
X1419739Y2206007D01*
X1419364Y2206567D01*
X1418864Y2207033D01*
G01X1419989Y2212200D02*
X1419864Y2211453D01*
X1419364Y2210800D01*
X1418614Y2210240D01*
X1417739Y2209867D01*
X1416739Y2209680D01*
X1415739D01*
X1414739Y2209867D01*
X1413864Y2210240D01*
X1413114Y2210800D01*
X1412614Y2211453D01*
X1412489Y2212200D01*
X1412614Y2212947D01*
X1413114Y2213600D01*
X1413864Y2214160D01*
X1414739Y2214533D01*
X1415739Y2214720D01*
X1416739D01*
X1417739Y2214533D01*
X1418614Y2214160D01*
X1419364Y2213600D01*
X1419864Y2212947D01*
X1419989Y2212200D01*
G01Y2217273D02*
X1412489D01*
X1418739Y2219700D01*
X1412489Y2222127D01*
X1419989D01*
G01Y2224773D02*
X1412489D01*
X1418739Y2227200D01*
X1412489Y2229627D01*
X1419989D01*
G01Y2236567D02*
Y2232833D01*
X1412489D01*
Y2236567D01*
G01X1416114Y2235073D02*
Y2232833D01*
G01X1419989Y2240053D02*
X1412489D01*
X1419989Y2244347D01*
X1412489D01*
G01X1419989Y2247647D02*
X1412489D01*
Y2249513D01*
X1412864Y2250260D01*
X1413364Y2250820D01*
X1414114Y2251287D01*
X1414989Y2251660D01*
X1416239Y2251753D01*
X1417489Y2251660D01*
X1418364Y2251287D01*
X1419114Y2250820D01*
X1419614Y2250260D01*
X1419989Y2249513D01*
Y2247647D01*
G01Y2259067D02*
Y2255333D01*
X1412489D01*
Y2259067D01*
G01X1416114Y2257573D02*
Y2255333D01*
G01X1419989Y2262647D02*
X1412489D01*
Y2264513D01*
X1412864Y2265260D01*
X1413364Y2265820D01*
X1414114Y2266287D01*
X1414989Y2266660D01*
X1416239Y2266753D01*
X1417489Y2266660D01*
X1418364Y2266287D01*
X1419114Y2265820D01*
X1419614Y2265260D01*
X1419989Y2264513D01*
Y2262647D01*
G01Y2277647D02*
X1412489D01*
Y2279513D01*
X1412864Y2280260D01*
X1413364Y2280820D01*
X1414114Y2281287D01*
X1414989Y2281660D01*
X1416239Y2281753D01*
X1417489Y2281660D01*
X1418364Y2281287D01*
X1419114Y2280820D01*
X1419614Y2280260D01*
X1419989Y2279513D01*
Y2277647D01*
G01Y2285333D02*
X1412489D01*
Y2287667D01*
X1412864Y2288413D01*
X1413364Y2288880D01*
X1414364Y2289067D01*
X1415364Y2288880D01*
X1415989Y2288320D01*
X1416364Y2287667D01*
Y2285333D01*
G01Y2287667D02*
X1419989Y2289067D01*
G01X1412489Y2293580D02*
Y2295820D01*
G01Y2294700D02*
X1419989D01*
G01Y2293580D02*
Y2295820D01*
G01X1412489Y2300333D02*
X1419989D01*
Y2304067D01*
G01X1412489Y2307833D02*
X1419989D01*
Y2311567D01*
G01X1418989Y2322740D02*
X1419614Y2323487D01*
X1419989Y2324327D01*
Y2325073D01*
X1419614Y2325820D01*
X1418989Y2326380D01*
X1418114Y2326660D01*
X1417239Y2326473D01*
X1416489Y2326007D01*
X1415989Y2325167D01*
X1415739Y2324047D01*
X1415239Y2323393D01*
X1414364Y2323113D01*
X1413489Y2323300D01*
X1412864Y2323767D01*
X1412489Y2324420D01*
Y2325073D01*
X1412739Y2325727D01*
X1413364Y2326287D01*
G01X1412489Y2331080D02*
Y2333320D01*
G01Y2332200D02*
X1419989D01*
G01Y2331080D02*
Y2333320D01*
G01X1412489Y2337927D02*
Y2341473D01*
X1419989Y2337927D01*
Y2341473D01*
G01Y2349067D02*
Y2345333D01*
X1412489D01*
Y2349067D01*
G01X1416114Y2347573D02*
Y2345333D01*
G01X1419989Y2360427D02*
X1412489D01*
Y2363973D01*
G01X1416114Y2362667D02*
Y2360427D01*
G01X1419989Y2369700D02*
X1419864Y2368953D01*
X1419364Y2368300D01*
X1418614Y2367740D01*
X1417739Y2367367D01*
X1416739Y2367180D01*
X1415739D01*
X1414739Y2367367D01*
X1413864Y2367740D01*
X1413114Y2368300D01*
X1412614Y2368953D01*
X1412489Y2369700D01*
X1412614Y2370447D01*
X1413114Y2371100D01*
X1413864Y2371660D01*
X1414739Y2372033D01*
X1415739Y2372220D01*
X1416739D01*
X1417739Y2372033D01*
X1418614Y2371660D01*
X1419364Y2371100D01*
X1419864Y2370447D01*
X1419989Y2369700D01*
G01Y2375333D02*
X1412489D01*
Y2377667D01*
X1412864Y2378413D01*
X1413364Y2378880D01*
X1414364Y2379067D01*
X1415364Y2378880D01*
X1415989Y2378320D01*
X1416364Y2377667D01*
Y2375333D01*
G01Y2377667D02*
X1419989Y2379067D01*
G01X1412489Y2392200D02*
X1412739Y2391453D01*
X1413364Y2390893D01*
X1414114Y2390520D01*
X1415114Y2390240D01*
X1416239Y2390147D01*
X1417364Y2390240D01*
X1418364Y2390520D01*
X1419114Y2390893D01*
X1419739Y2391453D01*
X1419989Y2392200D01*
X1419739Y2392947D01*
X1419114Y2393507D01*
X1418364Y2393880D01*
X1417364Y2394160D01*
X1416239Y2394253D01*
X1415114Y2394160D01*
X1414114Y2393880D01*
X1413364Y2393507D01*
X1412739Y2392947D01*
X1412489Y2392200D01*
G01X1420239Y2399700D02*
X1420114Y2399513D01*
X1419864D01*
X1419739Y2399700D01*
X1419864Y2399887D01*
X1420114D01*
X1420239Y2399700D01*
G01X1418489Y2405147D02*
X1419364Y2405707D01*
X1419864Y2406453D01*
X1419989Y2407293D01*
X1419864Y2408040D01*
X1419239Y2408787D01*
X1418489Y2409253D01*
X1417739Y2409347D01*
X1416864Y2409160D01*
X1416239Y2408507D01*
X1415989Y2407853D01*
Y2407013D01*
G01Y2407853D02*
X1415614Y2408413D01*
X1414989Y2408880D01*
X1414239Y2409067D01*
X1413489Y2408880D01*
X1412864Y2408413D01*
X1412489Y2407573D01*
X1412614Y2406733D01*
X1413114Y2405893D01*
G01X1416864Y2412927D02*
X1415989Y2413580D01*
X1415489Y2414140D01*
X1415239Y2414887D01*
X1415489Y2415540D01*
X1415989Y2416007D01*
X1416739Y2416380D01*
X1417614Y2416473D01*
X1418364Y2416380D01*
X1419114Y2416007D01*
X1419739Y2415447D01*
X1419989Y2414793D01*
X1419739Y2414047D01*
X1418989Y2413393D01*
X1417864Y2413020D01*
X1416614Y2412927D01*
X1414989Y2413113D01*
X1414114Y2413393D01*
X1413239Y2413860D01*
X1412614Y2414513D01*
X1412489Y2415167D01*
X1412739Y2415820D01*
X1413364Y2416287D01*
G01X1419989Y2419773D02*
X1412489D01*
X1418739Y2422200D01*
X1412489Y2424627D01*
X1419989D01*
G01Y2427273D02*
X1412489D01*
X1418739Y2429700D01*
X1412489Y2432127D01*
X1419989D01*
G01Y2442927D02*
X1412489D01*
Y2446473D01*
G01X1416114Y2445167D02*
Y2442927D01*
G01X1412489Y2451080D02*
Y2453320D01*
G01Y2452200D02*
X1419989D01*
G01Y2451080D02*
Y2453320D01*
G01Y2457553D02*
X1412489D01*
X1419989Y2461847D01*
X1412489D01*
G01Y2466080D02*
Y2468320D01*
G01Y2467200D02*
X1419989D01*
G01Y2466080D02*
Y2468320D01*
G01X1418989Y2472740D02*
X1419614Y2473487D01*
X1419989Y2474327D01*
Y2475073D01*
X1419614Y2475820D01*
X1418989Y2476380D01*
X1418114Y2476660D01*
X1417239Y2476473D01*
X1416489Y2476007D01*
X1415989Y2475167D01*
X1415739Y2474047D01*
X1415239Y2473393D01*
X1414364Y2473113D01*
X1413489Y2473300D01*
X1412864Y2473767D01*
X1412489Y2474420D01*
Y2475073D01*
X1412739Y2475727D01*
X1413364Y2476287D01*
G01X1419989Y2480240D02*
X1412489D01*
G01Y2484160D02*
X1419989D01*
G01X1416239D02*
Y2480240D01*
G01X1419989Y2491567D02*
Y2487833D01*
X1412489D01*
Y2491567D01*
G01X1416114Y2490073D02*
Y2487833D01*
G01X1419989Y2495147D02*
X1412489D01*
Y2497013D01*
X1412864Y2497760D01*
X1413364Y2498320D01*
X1414114Y2498787D01*
X1414989Y2499160D01*
X1416239Y2499253D01*
X1417489Y2499160D01*
X1418364Y2498787D01*
X1419114Y2498320D01*
X1419614Y2497760D01*
X1419989Y2497013D01*
Y2495147D01*
G01Y2510333D02*
X1412489D01*
Y2512573D01*
X1412864Y2513320D01*
X1413739Y2513880D01*
X1414739Y2514067D01*
X1415739Y2513880D01*
X1416489Y2513413D01*
X1416864Y2512573D01*
Y2510333D01*
G01X1412489Y2519700D02*
X1419989D01*
G01X1412489Y2517553D02*
Y2521847D01*
G01X1419989Y2525240D02*
X1412489D01*
G01Y2529160D02*
X1419989D01*
G01X1416239D02*
Y2525240D01*
G01X1412489Y2541080D02*
Y2543320D01*
G01Y2542200D02*
X1419989D01*
G01Y2541080D02*
Y2543320D01*
G01X1418989Y2547740D02*
X1419614Y2548487D01*
X1419989Y2549327D01*
Y2550073D01*
X1419614Y2550820D01*
X1418989Y2551380D01*
X1418114Y2551660D01*
X1417239Y2551473D01*
X1416489Y2551007D01*
X1415989Y2550167D01*
X1415739Y2549047D01*
X1415239Y2548393D01*
X1414364Y2548113D01*
X1413489Y2548300D01*
X1412864Y2548767D01*
X1412489Y2549420D01*
Y2550073D01*
X1412739Y2550727D01*
X1413364Y2551287D01*
G01X1412489Y2564700D02*
X1412739Y2563953D01*
X1413364Y2563393D01*
X1414114Y2563020D01*
X1415114Y2562740D01*
X1416239Y2562647D01*
X1417364Y2562740D01*
X1418364Y2563020D01*
X1419114Y2563393D01*
X1419739Y2563953D01*
X1419989Y2564700D01*
X1419739Y2565447D01*
X1419114Y2566007D01*
X1418364Y2566380D01*
X1417364Y2566660D01*
X1416239Y2566753D01*
X1415114Y2566660D01*
X1414114Y2566380D01*
X1413364Y2566007D01*
X1412739Y2565447D01*
X1412489Y2564700D01*
G01X1420239Y2572200D02*
X1420114Y2572013D01*
X1419864D01*
X1419739Y2572200D01*
X1419864Y2572387D01*
X1420114D01*
X1420239Y2572200D01*
G01X1419989Y2580820D02*
X1412489D01*
X1417864Y2577367D01*
Y2582033D01*
G01X1418864Y2585147D02*
X1419489Y2585707D01*
X1419864Y2586360D01*
X1419989Y2587200D01*
X1419739Y2588040D01*
X1419239Y2588693D01*
X1418364Y2589160D01*
X1417364Y2589253D01*
X1416364Y2589067D01*
X1415739Y2588600D01*
X1415239Y2587947D01*
X1415114Y2587293D01*
X1415239Y2586640D01*
X1415739Y2585800D01*
X1412489Y2586080D01*
Y2588600D01*
G01X1419989Y2592273D02*
X1412489D01*
X1418739Y2594700D01*
X1412489Y2597127D01*
X1419989D01*
G01Y2599773D02*
X1412489D01*
X1418739Y2602200D01*
X1412489Y2604627D01*
X1419989D01*
G01Y2614773D02*
X1412489D01*
X1418739Y2617200D01*
X1412489Y2619627D01*
X1419989D01*
G01Y2626567D02*
Y2622833D01*
X1412489D01*
Y2626567D01*
G01X1416114Y2625073D02*
Y2622833D01*
G01X1412489Y2632200D02*
X1419989D01*
G01X1412489Y2630053D02*
Y2634347D01*
G01X1419989Y2637833D02*
X1412489D01*
Y2640167D01*
X1412864Y2640913D01*
X1413364Y2641380D01*
X1414364Y2641567D01*
X1415364Y2641380D01*
X1415989Y2640820D01*
X1416364Y2640167D01*
Y2637833D01*
G01Y2640167D02*
X1419989Y2641567D01*
G01X1412489Y2646080D02*
Y2648320D01*
G01Y2647200D02*
X1419989D01*
G01Y2646080D02*
Y2648320D01*
G01X1413114Y2656753D02*
X1412739Y2656193D01*
X1412489Y2655540D01*
Y2654793D01*
X1412864Y2653953D01*
X1413489Y2653300D01*
X1414239Y2652833D01*
X1415489Y2652460D01*
X1416614Y2652367D01*
X1417739Y2652553D01*
X1418489Y2652833D01*
X1419239Y2653393D01*
X1419739Y2654047D01*
X1419989Y2654700D01*
Y2655353D01*
X1419739Y2656007D01*
X1419364Y2656567D01*
X1418864Y2657033D01*
G01X1419989Y2667647D02*
X1412489D01*
Y2669513D01*
X1412864Y2670260D01*
X1413364Y2670820D01*
X1414114Y2671287D01*
X1414989Y2671660D01*
X1416239Y2671753D01*
X1417489Y2671660D01*
X1418364Y2671287D01*
X1419114Y2670820D01*
X1419614Y2670260D01*
X1419989Y2669513D01*
Y2667647D01*
G01Y2675333D02*
X1412489D01*
Y2677667D01*
X1412864Y2678413D01*
X1413364Y2678880D01*
X1414364Y2679067D01*
X1415364Y2678880D01*
X1415989Y2678320D01*
X1416364Y2677667D01*
Y2675333D01*
G01Y2677667D02*
X1419989Y2679067D01*
G01X1412489Y2683580D02*
Y2685820D01*
G01Y2684700D02*
X1419989D01*
G01Y2683580D02*
Y2685820D01*
G01X1412489Y2690333D02*
X1419989D01*
Y2694067D01*
G01X1412489Y2697833D02*
X1419989D01*
Y2701567D01*
G01X1422489Y2706733D02*
X1421239Y2705800D01*
X1419989Y2705333D01*
X1414989D01*
X1413739Y2705800D01*
X1412489Y2706733D01*
G01Y2714700D02*
X1412739Y2713953D01*
X1413364Y2713393D01*
X1414114Y2713020D01*
X1415114Y2712740D01*
X1416239Y2712647D01*
X1417364Y2712740D01*
X1418364Y2713020D01*
X1419114Y2713393D01*
X1419739Y2713953D01*
X1419989Y2714700D01*
X1419739Y2715447D01*
X1419114Y2716007D01*
X1418364Y2716380D01*
X1417364Y2716660D01*
X1416239Y2716753D01*
X1415114Y2716660D01*
X1414114Y2716380D01*
X1413364Y2716007D01*
X1412739Y2715447D01*
X1412489Y2714700D01*
G01X1420239Y2722200D02*
X1420114Y2722013D01*
X1419864D01*
X1419739Y2722200D01*
X1419864Y2722387D01*
X1420114D01*
X1420239Y2722200D01*
G01X1412489Y2729700D02*
X1412739Y2728953D01*
X1413364Y2728393D01*
X1414114Y2728020D01*
X1415114Y2727740D01*
X1416239Y2727647D01*
X1417364Y2727740D01*
X1418364Y2728020D01*
X1419114Y2728393D01*
X1419739Y2728953D01*
X1419989Y2729700D01*
X1419739Y2730447D01*
X1419114Y2731007D01*
X1418364Y2731380D01*
X1417364Y2731660D01*
X1416239Y2731753D01*
X1415114Y2731660D01*
X1414114Y2731380D01*
X1413364Y2731007D01*
X1412739Y2730447D01*
X1412489Y2729700D01*
G01X1419989Y2737200D02*
X1412489D01*
X1413989Y2736080D01*
G01X1419989D02*
Y2738320D01*
G01Y2744513D02*
X1418364Y2744700D01*
X1416989Y2744980D01*
X1415739Y2745353D01*
X1414364Y2745820D01*
X1412489Y2746567D01*
Y2742833D01*
G01X1419989Y2752013D02*
X1418364Y2752200D01*
X1416989Y2752480D01*
X1415739Y2752853D01*
X1414364Y2753320D01*
X1412489Y2754067D01*
Y2750333D01*
G01X1414114Y2758860D02*
X1412489Y2759327D01*
G01Y2760540D02*
X1414114Y2760073D01*
G01X1422489Y2767667D02*
X1421239Y2768600D01*
X1419989Y2769067D01*
X1414989D01*
X1413739Y2768600D01*
X1412489Y2767667D01*
G01X1420239Y2774700D02*
X1420114Y2774513D01*
X1419864D01*
X1419739Y2774700D01*
X1419864Y2774887D01*
X1420114D01*
X1420239Y2774700D01*
G01X1439562Y2020694D02*
X1432062D01*
X1438312Y2023121D01*
X1432062Y2025548D01*
X1439562D01*
G01Y2028288D02*
X1432062Y2030621D01*
X1439562Y2032954D01*
G01X1436937Y2032114D02*
Y2029128D01*
G01X1439562Y2036254D02*
X1432062D01*
Y2038588D01*
X1432437Y2039334D01*
X1432937Y2039801D01*
X1433937Y2039988D01*
X1434937Y2039801D01*
X1435562Y2039241D01*
X1435937Y2038588D01*
Y2036254D01*
G01Y2038588D02*
X1439562Y2039988D01*
G01Y2043568D02*
X1432062D01*
G01Y2047114D02*
X1436687Y2043568D01*
G01X1439562Y2047674D02*
X1434562Y2045154D01*
G01X1439812Y2053121D02*
X1439687Y2052934D01*
X1439437D01*
X1439312Y2053121D01*
X1439437Y2053308D01*
X1439687D01*
X1439812Y2053121D01*
G01X1436437D02*
X1436312Y2052934D01*
X1436062D01*
X1435937Y2053121D01*
X1436062Y2053308D01*
X1436312D01*
X1436437Y2053121D01*
G01X1432062Y2060621D02*
X1439562D01*
G01X1432062Y2058474D02*
Y2062768D01*
G01Y2067001D02*
Y2069241D01*
G01Y2068121D02*
X1439562D01*
G01Y2067001D02*
Y2069241D01*
G01Y2073474D02*
X1432062D01*
X1439562Y2077768D01*
X1432062D01*
G01Y2088754D02*
X1439562D01*
Y2092488D01*
G01Y2099988D02*
Y2096254D01*
X1432062D01*
Y2099988D01*
G01X1435687Y2098494D02*
Y2096254D01*
G01X1439562Y2103288D02*
X1432062Y2105621D01*
X1439562Y2107954D01*
G01X1436937Y2107114D02*
Y2104128D01*
G01X1439562Y2111068D02*
X1432062D01*
Y2112934D01*
X1432437Y2113681D01*
X1432937Y2114241D01*
X1433687Y2114708D01*
X1434562Y2115081D01*
X1435812Y2115174D01*
X1437062Y2115081D01*
X1437937Y2114708D01*
X1438687Y2114241D01*
X1439187Y2113681D01*
X1439562Y2112934D01*
Y2111068D01*
G01X1439812Y2120621D02*
X1439687Y2120434D01*
X1439437D01*
X1439312Y2120621D01*
X1439437Y2120808D01*
X1439687D01*
X1439812Y2120621D01*
G01X1436437D02*
X1436312Y2120434D01*
X1436062D01*
X1435937Y2120621D01*
X1436062Y2120808D01*
X1436312D01*
X1436437Y2120621D01*
G01X1439562Y2126254D02*
X1432062D01*
Y2128588D01*
X1432437Y2129334D01*
X1432937Y2129801D01*
X1433937Y2129988D01*
X1434937Y2129801D01*
X1435562Y2129241D01*
X1435937Y2128588D01*
Y2126254D01*
G01Y2128588D02*
X1439562Y2129988D01*
G01Y2137488D02*
Y2133754D01*
X1432062D01*
Y2137488D01*
G01X1435687Y2135994D02*
Y2133754D01*
G01X1432687Y2145174D02*
X1432312Y2144614D01*
X1432062Y2143961D01*
Y2143214D01*
X1432437Y2142374D01*
X1433062Y2141721D01*
X1433812Y2141254D01*
X1435062Y2140881D01*
X1436187Y2140788D01*
X1437312Y2140974D01*
X1438062Y2141254D01*
X1438812Y2141814D01*
X1439312Y2142468D01*
X1439562Y2143121D01*
Y2143774D01*
X1439312Y2144428D01*
X1438937Y2144988D01*
X1438437Y2145454D01*
G01X1439562Y2150621D02*
X1439437Y2149874D01*
X1438937Y2149221D01*
X1438187Y2148661D01*
X1437312Y2148288D01*
X1436312Y2148101D01*
X1435312D01*
X1434312Y2148288D01*
X1433437Y2148661D01*
X1432687Y2149221D01*
X1432187Y2149874D01*
X1432062Y2150621D01*
X1432187Y2151368D01*
X1432687Y2152021D01*
X1433437Y2152581D01*
X1434312Y2152954D01*
X1435312Y2153141D01*
X1436312D01*
X1437312Y2152954D01*
X1438187Y2152581D01*
X1438937Y2152021D01*
X1439437Y2151368D01*
X1439562Y2150621D01*
G01Y2155694D02*
X1432062D01*
X1438312Y2158121D01*
X1432062Y2160548D01*
X1439562D01*
G01Y2163194D02*
X1432062D01*
X1438312Y2165621D01*
X1432062Y2168048D01*
X1439562D01*
G01Y2174988D02*
Y2171254D01*
X1432062D01*
Y2174988D01*
G01X1435687Y2173494D02*
Y2171254D01*
G01X1439562Y2178474D02*
X1432062D01*
X1439562Y2182768D01*
X1432062D01*
G01X1439562Y2186068D02*
X1432062D01*
Y2187934D01*
X1432437Y2188681D01*
X1432937Y2189241D01*
X1433687Y2189708D01*
X1434562Y2190081D01*
X1435812Y2190174D01*
X1437062Y2190081D01*
X1437937Y2189708D01*
X1438687Y2189241D01*
X1439187Y2188681D01*
X1439562Y2187934D01*
Y2186068D01*
G01Y2197488D02*
Y2193754D01*
X1432062D01*
Y2197488D01*
G01X1435687Y2195994D02*
Y2193754D01*
G01X1439562Y2201068D02*
X1432062D01*
Y2202934D01*
X1432437Y2203681D01*
X1432937Y2204241D01*
X1433687Y2204708D01*
X1434562Y2205081D01*
X1435812Y2205174D01*
X1437062Y2205081D01*
X1437937Y2204708D01*
X1438687Y2204241D01*
X1439187Y2203681D01*
X1439562Y2202934D01*
Y2201068D01*
G01Y2216068D02*
X1432062D01*
Y2217934D01*
X1432437Y2218681D01*
X1432937Y2219241D01*
X1433687Y2219708D01*
X1434562Y2220081D01*
X1435812Y2220174D01*
X1437062Y2220081D01*
X1437937Y2219708D01*
X1438687Y2219241D01*
X1439187Y2218681D01*
X1439562Y2217934D01*
Y2216068D01*
G01Y2223754D02*
X1432062D01*
Y2226088D01*
X1432437Y2226834D01*
X1432937Y2227301D01*
X1433937Y2227488D01*
X1434937Y2227301D01*
X1435562Y2226741D01*
X1435937Y2226088D01*
Y2223754D01*
G01Y2226088D02*
X1439562Y2227488D01*
G01X1432062Y2232001D02*
Y2234241D01*
G01Y2233121D02*
X1439562D01*
G01Y2232001D02*
Y2234241D01*
G01X1432062Y2238754D02*
X1439562D01*
Y2242488D01*
G01X1432062Y2246254D02*
X1439562D01*
Y2249988D01*
G01X1438562Y2261161D02*
X1439187Y2261908D01*
X1439562Y2262748D01*
Y2263494D01*
X1439187Y2264241D01*
X1438562Y2264801D01*
X1437687Y2265081D01*
X1436812Y2264894D01*
X1436062Y2264428D01*
X1435562Y2263588D01*
X1435312Y2262468D01*
X1434812Y2261814D01*
X1433937Y2261534D01*
X1433062Y2261721D01*
X1432437Y2262188D01*
X1432062Y2262841D01*
Y2263494D01*
X1432312Y2264148D01*
X1432937Y2264708D01*
G01X1432062Y2269501D02*
Y2271741D01*
G01Y2270621D02*
X1439562D01*
G01Y2269501D02*
Y2271741D01*
G01X1432062Y2276348D02*
Y2279894D01*
X1439562Y2276348D01*
Y2279894D01*
G01Y2287488D02*
Y2283754D01*
X1432062D01*
Y2287488D01*
G01X1435687Y2285994D02*
Y2283754D01*
G01X1439562Y2298848D02*
X1432062D01*
Y2302394D01*
G01X1435687Y2301088D02*
Y2298848D01*
G01X1439562Y2308121D02*
X1439437Y2307374D01*
X1438937Y2306721D01*
X1438187Y2306161D01*
X1437312Y2305788D01*
X1436312Y2305601D01*
X1435312D01*
X1434312Y2305788D01*
X1433437Y2306161D01*
X1432687Y2306721D01*
X1432187Y2307374D01*
X1432062Y2308121D01*
X1432187Y2308868D01*
X1432687Y2309521D01*
X1433437Y2310081D01*
X1434312Y2310454D01*
X1435312Y2310641D01*
X1436312D01*
X1437312Y2310454D01*
X1438187Y2310081D01*
X1438937Y2309521D01*
X1439437Y2308868D01*
X1439562Y2308121D01*
G01Y2313754D02*
X1432062D01*
Y2316088D01*
X1432437Y2316834D01*
X1432937Y2317301D01*
X1433937Y2317488D01*
X1434937Y2317301D01*
X1435562Y2316741D01*
X1435937Y2316088D01*
Y2313754D01*
G01Y2316088D02*
X1439562Y2317488D01*
G01X1432062Y2330621D02*
X1432312Y2329874D01*
X1432937Y2329314D01*
X1433687Y2328941D01*
X1434687Y2328661D01*
X1435812Y2328568D01*
X1436937Y2328661D01*
X1437937Y2328941D01*
X1438687Y2329314D01*
X1439312Y2329874D01*
X1439562Y2330621D01*
X1439312Y2331368D01*
X1438687Y2331928D01*
X1437937Y2332301D01*
X1436937Y2332581D01*
X1435812Y2332674D01*
X1434687Y2332581D01*
X1433687Y2332301D01*
X1432937Y2331928D01*
X1432312Y2331368D01*
X1432062Y2330621D01*
G01X1439812Y2338121D02*
X1439687Y2337934D01*
X1439437D01*
X1439312Y2338121D01*
X1439437Y2338308D01*
X1439687D01*
X1439812Y2338121D01*
G01X1438437Y2343568D02*
X1439062Y2344128D01*
X1439437Y2344781D01*
X1439562Y2345621D01*
X1439312Y2346461D01*
X1438812Y2347114D01*
X1437937Y2347581D01*
X1436937Y2347674D01*
X1435937Y2347488D01*
X1435312Y2347021D01*
X1434812Y2346368D01*
X1434687Y2345714D01*
X1434812Y2345061D01*
X1435312Y2344221D01*
X1432062Y2344501D01*
Y2347021D01*
G01X1439562Y2350694D02*
X1432062D01*
X1438312Y2353121D01*
X1432062Y2355548D01*
X1439562D01*
G01Y2358194D02*
X1432062D01*
X1438312Y2360621D01*
X1432062Y2363048D01*
X1439562D01*
G01Y2373848D02*
X1432062D01*
Y2377394D01*
G01X1435687Y2376088D02*
Y2373848D01*
G01X1432062Y2382001D02*
Y2384241D01*
G01Y2383121D02*
X1439562D01*
G01Y2382001D02*
Y2384241D01*
G01Y2388474D02*
X1432062D01*
X1439562Y2392768D01*
X1432062D01*
G01Y2397001D02*
Y2399241D01*
G01Y2398121D02*
X1439562D01*
G01Y2397001D02*
Y2399241D01*
G01X1438562Y2403661D02*
X1439187Y2404408D01*
X1439562Y2405248D01*
Y2405994D01*
X1439187Y2406741D01*
X1438562Y2407301D01*
X1437687Y2407581D01*
X1436812Y2407394D01*
X1436062Y2406928D01*
X1435562Y2406088D01*
X1435312Y2404968D01*
X1434812Y2404314D01*
X1433937Y2404034D01*
X1433062Y2404221D01*
X1432437Y2404688D01*
X1432062Y2405341D01*
Y2405994D01*
X1432312Y2406648D01*
X1432937Y2407208D01*
G01X1439562Y2411161D02*
X1432062D01*
G01Y2415081D02*
X1439562D01*
G01X1435812D02*
Y2411161D01*
G01X1439562Y2422488D02*
Y2418754D01*
X1432062D01*
Y2422488D01*
G01X1435687Y2420994D02*
Y2418754D01*
G01X1439562Y2426068D02*
X1432062D01*
Y2427934D01*
X1432437Y2428681D01*
X1432937Y2429241D01*
X1433687Y2429708D01*
X1434562Y2430081D01*
X1435812Y2430174D01*
X1437062Y2430081D01*
X1437937Y2429708D01*
X1438687Y2429241D01*
X1439187Y2428681D01*
X1439562Y2427934D01*
Y2426068D01*
G01Y2441254D02*
X1432062D01*
Y2443494D01*
X1432437Y2444241D01*
X1433312Y2444801D01*
X1434312Y2444988D01*
X1435312Y2444801D01*
X1436062Y2444334D01*
X1436437Y2443494D01*
Y2441254D01*
G01X1432062Y2450621D02*
X1439562D01*
G01X1432062Y2448474D02*
Y2452768D01*
G01X1439562Y2456161D02*
X1432062D01*
G01Y2460081D02*
X1439562D01*
G01X1435812D02*
Y2456161D01*
G01X1432062Y2472001D02*
Y2474241D01*
G01Y2473121D02*
X1439562D01*
G01Y2472001D02*
Y2474241D01*
G01X1438562Y2478661D02*
X1439187Y2479408D01*
X1439562Y2480248D01*
Y2480994D01*
X1439187Y2481741D01*
X1438562Y2482301D01*
X1437687Y2482581D01*
X1436812Y2482394D01*
X1436062Y2481928D01*
X1435562Y2481088D01*
X1435312Y2479968D01*
X1434812Y2479314D01*
X1433937Y2479034D01*
X1433062Y2479221D01*
X1432437Y2479688D01*
X1432062Y2480341D01*
Y2480994D01*
X1432312Y2481648D01*
X1432937Y2482208D01*
G01X1432062Y2495621D02*
X1432312Y2494874D01*
X1432937Y2494314D01*
X1433687Y2493941D01*
X1434687Y2493661D01*
X1435812Y2493568D01*
X1436937Y2493661D01*
X1437937Y2493941D01*
X1438687Y2494314D01*
X1439312Y2494874D01*
X1439562Y2495621D01*
X1439312Y2496368D01*
X1438687Y2496928D01*
X1437937Y2497301D01*
X1436937Y2497581D01*
X1435812Y2497674D01*
X1434687Y2497581D01*
X1433687Y2497301D01*
X1432937Y2496928D01*
X1432312Y2496368D01*
X1432062Y2495621D01*
G01X1439812Y2503121D02*
X1439687Y2502934D01*
X1439437D01*
X1439312Y2503121D01*
X1439437Y2503308D01*
X1439687D01*
X1439812Y2503121D01*
G01X1436437Y2508848D02*
X1435562Y2509501D01*
X1435062Y2510061D01*
X1434812Y2510808D01*
X1435062Y2511461D01*
X1435562Y2511928D01*
X1436312Y2512301D01*
X1437187Y2512394D01*
X1437937Y2512301D01*
X1438687Y2511928D01*
X1439312Y2511368D01*
X1439562Y2510714D01*
X1439312Y2509968D01*
X1438562Y2509314D01*
X1437437Y2508941D01*
X1436187Y2508848D01*
X1434562Y2509034D01*
X1433687Y2509314D01*
X1432812Y2509781D01*
X1432187Y2510434D01*
X1432062Y2511088D01*
X1432312Y2511741D01*
X1432937Y2512208D01*
G01X1439562Y2515694D02*
X1432062D01*
X1438312Y2518121D01*
X1432062Y2520548D01*
X1439562D01*
G01Y2523194D02*
X1432062D01*
X1438312Y2525621D01*
X1432062Y2528048D01*
X1439562D01*
G01Y2538194D02*
X1432062D01*
X1438312Y2540621D01*
X1432062Y2543048D01*
X1439562D01*
G01Y2549988D02*
Y2546254D01*
X1432062D01*
Y2549988D01*
G01X1435687Y2548494D02*
Y2546254D01*
G01X1432062Y2555621D02*
X1439562D01*
G01X1432062Y2553474D02*
Y2557768D01*
G01X1439562Y2561254D02*
X1432062D01*
Y2563588D01*
X1432437Y2564334D01*
X1432937Y2564801D01*
X1433937Y2564988D01*
X1434937Y2564801D01*
X1435562Y2564241D01*
X1435937Y2563588D01*
Y2561254D01*
G01Y2563588D02*
X1439562Y2564988D01*
G01X1432062Y2569501D02*
Y2571741D01*
G01Y2570621D02*
X1439562D01*
G01Y2569501D02*
Y2571741D01*
G01X1432687Y2580174D02*
X1432312Y2579614D01*
X1432062Y2578961D01*
Y2578214D01*
X1432437Y2577374D01*
X1433062Y2576721D01*
X1433812Y2576254D01*
X1435062Y2575881D01*
X1436187Y2575788D01*
X1437312Y2575974D01*
X1438062Y2576254D01*
X1438812Y2576814D01*
X1439312Y2577468D01*
X1439562Y2578121D01*
Y2578774D01*
X1439312Y2579428D01*
X1438937Y2579988D01*
X1438437Y2580454D01*
G01X1439562Y2591068D02*
X1432062D01*
Y2592934D01*
X1432437Y2593681D01*
X1432937Y2594241D01*
X1433687Y2594708D01*
X1434562Y2595081D01*
X1435812Y2595174D01*
X1437062Y2595081D01*
X1437937Y2594708D01*
X1438687Y2594241D01*
X1439187Y2593681D01*
X1439562Y2592934D01*
Y2591068D01*
G01Y2598754D02*
X1432062D01*
Y2601088D01*
X1432437Y2601834D01*
X1432937Y2602301D01*
X1433937Y2602488D01*
X1434937Y2602301D01*
X1435562Y2601741D01*
X1435937Y2601088D01*
Y2598754D01*
G01Y2601088D02*
X1439562Y2602488D01*
G01X1432062Y2607001D02*
Y2609241D01*
G01Y2608121D02*
X1439562D01*
G01Y2607001D02*
Y2609241D01*
G01X1432062Y2613754D02*
X1439562D01*
Y2617488D01*
G01X1432062Y2621254D02*
X1439562D01*
Y2624988D01*
G01X1442062Y2630154D02*
X1440812Y2629221D01*
X1439562Y2628754D01*
X1434562D01*
X1433312Y2629221D01*
X1432062Y2630154D01*
G01Y2638121D02*
X1432312Y2637374D01*
X1432937Y2636814D01*
X1433687Y2636441D01*
X1434687Y2636161D01*
X1435812Y2636068D01*
X1436937Y2636161D01*
X1437937Y2636441D01*
X1438687Y2636814D01*
X1439312Y2637374D01*
X1439562Y2638121D01*
X1439312Y2638868D01*
X1438687Y2639428D01*
X1437937Y2639801D01*
X1436937Y2640081D01*
X1435812Y2640174D01*
X1434687Y2640081D01*
X1433687Y2639801D01*
X1432937Y2639428D01*
X1432312Y2638868D01*
X1432062Y2638121D01*
G01X1439812Y2645621D02*
X1439687Y2645434D01*
X1439437D01*
X1439312Y2645621D01*
X1439437Y2645808D01*
X1439687D01*
X1439812Y2645621D01*
G01X1432062Y2653121D02*
X1432312Y2652374D01*
X1432937Y2651814D01*
X1433687Y2651441D01*
X1434687Y2651161D01*
X1435812Y2651068D01*
X1436937Y2651161D01*
X1437937Y2651441D01*
X1438687Y2651814D01*
X1439312Y2652374D01*
X1439562Y2653121D01*
X1439312Y2653868D01*
X1438687Y2654428D01*
X1437937Y2654801D01*
X1436937Y2655081D01*
X1435812Y2655174D01*
X1434687Y2655081D01*
X1433687Y2654801D01*
X1432937Y2654428D01*
X1432312Y2653868D01*
X1432062Y2653121D01*
G01X1433312Y2658848D02*
X1432562Y2659408D01*
X1432187Y2660061D01*
X1432062Y2660808D01*
X1432312Y2661741D01*
X1432937Y2662394D01*
X1433687Y2662581D01*
X1434437Y2662488D01*
X1435062Y2662114D01*
X1436312Y2660248D01*
X1437187Y2659408D01*
X1438437Y2658848D01*
X1439562Y2658661D01*
Y2662581D01*
G01X1438062Y2666068D02*
X1438937Y2666628D01*
X1439437Y2667374D01*
X1439562Y2668214D01*
X1439437Y2668961D01*
X1438812Y2669708D01*
X1438062Y2670174D01*
X1437312Y2670268D01*
X1436437Y2670081D01*
X1435812Y2669428D01*
X1435562Y2668774D01*
Y2667934D01*
G01Y2668774D02*
X1435187Y2669334D01*
X1434562Y2669801D01*
X1433812Y2669988D01*
X1433062Y2669801D01*
X1432437Y2669334D01*
X1432062Y2668494D01*
X1432187Y2667654D01*
X1432687Y2666814D01*
G01X1436437Y2673848D02*
X1435562Y2674501D01*
X1435062Y2675061D01*
X1434812Y2675808D01*
X1435062Y2676461D01*
X1435562Y2676928D01*
X1436312Y2677301D01*
X1437187Y2677394D01*
X1437937Y2677301D01*
X1438687Y2676928D01*
X1439312Y2676368D01*
X1439562Y2675714D01*
X1439312Y2674968D01*
X1438562Y2674314D01*
X1437437Y2673941D01*
X1436187Y2673848D01*
X1434562Y2674034D01*
X1433687Y2674314D01*
X1432812Y2674781D01*
X1432187Y2675434D01*
X1432062Y2676088D01*
X1432312Y2676741D01*
X1432937Y2677208D01*
G01X1433687Y2682281D02*
X1432062Y2682748D01*
G01Y2683961D02*
X1433687Y2683494D01*
G01X1442062Y2691088D02*
X1440812Y2692021D01*
X1439562Y2692488D01*
X1434562D01*
X1433312Y2692021D01*
X1432062Y2691088D01*
G01X1439812Y2698121D02*
X1439687Y2697934D01*
X1439437D01*
X1439312Y2698121D01*
X1439437Y2698308D01*
X1439687D01*
X1439812Y2698121D01*
G01X1468055Y-377922D02*
X1455555D01*
X1458055Y-379782D01*
G01X1468055D02*
Y-376062D01*
G01Y-363662D02*
X1455555D01*
X1464513Y-369397D01*
Y-361647D01*
G01X1462847Y-356067D02*
X1461388Y-354982D01*
X1460555Y-354052D01*
X1460138Y-352812D01*
X1460555Y-351727D01*
X1461388Y-350952D01*
X1462638Y-350332D01*
X1464097Y-350177D01*
X1465347Y-350332D01*
X1466597Y-350952D01*
X1467638Y-351882D01*
X1468055Y-352967D01*
X1467638Y-354207D01*
X1466389Y-355292D01*
X1464513Y-355912D01*
X1462430Y-356067D01*
X1459722Y-355757D01*
X1458263Y-355292D01*
X1456805Y-354517D01*
X1455763Y-353432D01*
X1455555Y-352347D01*
X1455972Y-351262D01*
X1457013Y-350487D01*
G01X1468055Y-340722D02*
X1455555D01*
X1458055Y-342582D01*
G01X1468055D02*
Y-338862D01*
G01Y-328322D02*
X1467847Y-327237D01*
X1467222Y-325997D01*
X1466180Y-325222D01*
X1464722Y-324912D01*
X1463264Y-325222D01*
X1462013Y-326152D01*
X1461388Y-327547D01*
Y-329097D01*
X1460972Y-330027D01*
X1459930Y-330802D01*
X1458472Y-331112D01*
X1457013Y-330647D01*
X1455972Y-329562D01*
X1455555Y-328322D01*
X1455972Y-327082D01*
X1457013Y-325997D01*
X1458472Y-325532D01*
X1459930Y-325842D01*
X1460972Y-326617D01*
X1461388Y-327547D01*
Y-329097D01*
X1462013Y-330492D01*
X1463264Y-331422D01*
X1464722Y-331732D01*
X1466180Y-331422D01*
X1467222Y-330647D01*
X1467847Y-329407D01*
X1468055Y-328322D01*
G01X1468472Y-315922D02*
X1468263Y-316232D01*
X1467847D01*
X1467638Y-315922D01*
X1467847Y-315612D01*
X1468263D01*
X1468472Y-315922D01*
G01X1455555Y-303522D02*
X1455972Y-304762D01*
X1457013Y-305692D01*
X1458263Y-306312D01*
X1459930Y-306777D01*
X1461805Y-306932D01*
X1463680Y-306777D01*
X1465347Y-306312D01*
X1466597Y-305692D01*
X1467638Y-304762D01*
X1468055Y-303522D01*
X1467638Y-302282D01*
X1466597Y-301352D01*
X1465347Y-300732D01*
X1463680Y-300267D01*
X1461805Y-300112D01*
X1459930Y-300267D01*
X1458263Y-300732D01*
X1457013Y-301352D01*
X1455972Y-302282D01*
X1455555Y-303522D01*
G01X1466180Y-294532D02*
X1467222Y-293602D01*
X1467847Y-292517D01*
X1468055Y-291122D01*
X1467638Y-289727D01*
X1466805Y-288642D01*
X1465347Y-287867D01*
X1463680Y-287712D01*
X1462013Y-288022D01*
X1460972Y-288797D01*
X1460138Y-289882D01*
X1459930Y-290967D01*
X1460138Y-292052D01*
X1460972Y-293447D01*
X1455555Y-292982D01*
Y-288797D01*
G01X1465555Y-259932D02*
X1467014Y-259002D01*
X1467847Y-257762D01*
X1468055Y-256367D01*
X1467847Y-255127D01*
X1466805Y-253887D01*
X1465555Y-253112D01*
X1464305Y-252957D01*
X1462847Y-253267D01*
X1461805Y-254352D01*
X1461388Y-255437D01*
Y-256832D01*
G01Y-255437D02*
X1460763Y-254507D01*
X1459722Y-253732D01*
X1458472Y-253422D01*
X1457222Y-253732D01*
X1456180Y-254507D01*
X1455555Y-255902D01*
X1455763Y-257297D01*
X1456597Y-258692D01*
G01X1468055Y-244432D02*
X1465347Y-244122D01*
X1463055Y-243657D01*
X1460972Y-243037D01*
X1458680Y-242262D01*
X1455555Y-241022D01*
Y-247222D01*
G01X1468055Y-231722D02*
X1455555D01*
X1458055Y-233582D01*
G01X1468055D02*
Y-229862D01*
G01X1468472Y-219322D02*
X1468263Y-219632D01*
X1467847D01*
X1467638Y-219322D01*
X1467847Y-219012D01*
X1468263D01*
X1468472Y-219322D01*
G01X1465555Y-210332D02*
X1467014Y-209402D01*
X1467847Y-208162D01*
X1468055Y-206767D01*
X1467847Y-205527D01*
X1466805Y-204287D01*
X1465555Y-203512D01*
X1464305Y-203357D01*
X1462847Y-203667D01*
X1461805Y-204752D01*
X1461388Y-205837D01*
Y-207232D01*
G01Y-205837D02*
X1460763Y-204907D01*
X1459722Y-204132D01*
X1458472Y-203822D01*
X1457222Y-204132D01*
X1456180Y-204907D01*
X1455555Y-206302D01*
X1455763Y-207697D01*
X1456597Y-209092D01*
G01X1446967Y2062902D02*
X1446592Y2062342D01*
X1446342Y2061689D01*
Y2060942D01*
X1446717Y2060102D01*
X1447342Y2059449D01*
X1448092Y2058982D01*
X1449342Y2058609D01*
X1450467Y2058516D01*
X1451592Y2058702D01*
X1452342Y2058982D01*
X1453092Y2059542D01*
X1453592Y2060196D01*
X1453842Y2060849D01*
Y2061502D01*
X1453592Y2062156D01*
X1453217Y2062716D01*
X1452717Y2063182D01*
G01X1453842Y2068349D02*
X1453717Y2067602D01*
X1453217Y2066949D01*
X1452467Y2066389D01*
X1451592Y2066016D01*
X1450592Y2065829D01*
X1449592D01*
X1448592Y2066016D01*
X1447717Y2066389D01*
X1446967Y2066949D01*
X1446467Y2067602D01*
X1446342Y2068349D01*
X1446467Y2069096D01*
X1446967Y2069749D01*
X1447717Y2070309D01*
X1448592Y2070682D01*
X1449592Y2070869D01*
X1450592D01*
X1451592Y2070682D01*
X1452467Y2070309D01*
X1453217Y2069749D01*
X1453717Y2069096D01*
X1453842Y2068349D01*
G01Y2073982D02*
X1446342D01*
Y2076222D01*
X1446717Y2076969D01*
X1447592Y2077529D01*
X1448592Y2077716D01*
X1449592Y2077529D01*
X1450342Y2077062D01*
X1450717Y2076222D01*
Y2073982D01*
G01X1453842Y2081482D02*
X1446342D01*
Y2083722D01*
X1446717Y2084469D01*
X1447592Y2085029D01*
X1448592Y2085216D01*
X1449592Y2085029D01*
X1450342Y2084562D01*
X1450717Y2083722D01*
Y2081482D01*
G01X1453842Y2092716D02*
Y2088982D01*
X1446342D01*
Y2092716D01*
G01X1449967Y2091222D02*
Y2088982D01*
G01X1453842Y2096482D02*
X1446342D01*
Y2098816D01*
X1446717Y2099562D01*
X1447217Y2100029D01*
X1448217Y2100216D01*
X1449217Y2100029D01*
X1449842Y2099469D01*
X1450217Y2098816D01*
Y2096482D01*
G01Y2098816D02*
X1453842Y2100216D01*
G01Y2113349D02*
X1453717Y2112602D01*
X1453217Y2111949D01*
X1452467Y2111389D01*
X1451592Y2111016D01*
X1450592Y2110829D01*
X1449592D01*
X1448592Y2111016D01*
X1447717Y2111389D01*
X1446967Y2111949D01*
X1446467Y2112602D01*
X1446342Y2113349D01*
X1446467Y2114096D01*
X1446967Y2114749D01*
X1447717Y2115309D01*
X1448592Y2115682D01*
X1449592Y2115869D01*
X1450592D01*
X1451592Y2115682D01*
X1452467Y2115309D01*
X1453217Y2114749D01*
X1453717Y2114096D01*
X1453842Y2113349D01*
G01X1452842Y2118889D02*
X1453467Y2119636D01*
X1453842Y2120476D01*
Y2121222D01*
X1453467Y2121969D01*
X1452842Y2122529D01*
X1451967Y2122809D01*
X1451092Y2122622D01*
X1450342Y2122156D01*
X1449842Y2121316D01*
X1449592Y2120196D01*
X1449092Y2119542D01*
X1448217Y2119262D01*
X1447342Y2119449D01*
X1446717Y2119916D01*
X1446342Y2120569D01*
Y2121222D01*
X1446592Y2121876D01*
X1447217Y2122436D01*
G01X1453842Y2126482D02*
X1446342D01*
Y2128722D01*
X1446717Y2129469D01*
X1447592Y2130029D01*
X1448592Y2130216D01*
X1449592Y2130029D01*
X1450342Y2129562D01*
X1450717Y2128722D01*
Y2126482D01*
G01X1454092Y2134169D02*
X1446342Y2137529D01*
G01Y2143349D02*
X1453842D01*
G01X1446342Y2141202D02*
Y2145496D01*
G01Y2149729D02*
Y2151969D01*
G01Y2150849D02*
X1453842D01*
G01Y2149729D02*
Y2151969D01*
G01Y2156202D02*
X1446342D01*
X1453842Y2160496D01*
X1446342D01*
G01X1456342Y2165382D02*
X1455092Y2164449D01*
X1453842Y2163982D01*
X1448842D01*
X1447592Y2164449D01*
X1446342Y2165382D01*
G01Y2172229D02*
Y2174469D01*
G01Y2173349D02*
X1453842D01*
G01Y2172229D02*
Y2174469D01*
G01Y2178422D02*
X1446342D01*
X1452592Y2180849D01*
X1446342Y2183276D01*
X1453842D01*
G01Y2185922D02*
X1446342D01*
X1452592Y2188349D01*
X1446342Y2190776D01*
X1453842D01*
G01Y2197716D02*
Y2193982D01*
X1446342D01*
Y2197716D01*
G01X1449967Y2196222D02*
Y2193982D01*
G01X1453842Y2201482D02*
X1446342D01*
Y2203816D01*
X1446717Y2204562D01*
X1447217Y2205029D01*
X1448217Y2205216D01*
X1449217Y2205029D01*
X1449842Y2204469D01*
X1450217Y2203816D01*
Y2201482D01*
G01Y2203816D02*
X1453842Y2205216D01*
G01X1452842Y2208889D02*
X1453467Y2209636D01*
X1453842Y2210476D01*
Y2211222D01*
X1453467Y2211969D01*
X1452842Y2212529D01*
X1451967Y2212809D01*
X1451092Y2212622D01*
X1450342Y2212156D01*
X1449842Y2211316D01*
X1449592Y2210196D01*
X1449092Y2209542D01*
X1448217Y2209262D01*
X1447342Y2209449D01*
X1446717Y2209916D01*
X1446342Y2210569D01*
Y2211222D01*
X1446592Y2211876D01*
X1447217Y2212436D01*
G01X1446342Y2217229D02*
Y2219469D01*
G01Y2218349D02*
X1453842D01*
G01Y2217229D02*
Y2219469D01*
G01Y2225849D02*
X1453717Y2225102D01*
X1453217Y2224449D01*
X1452467Y2223889D01*
X1451592Y2223516D01*
X1450592Y2223329D01*
X1449592D01*
X1448592Y2223516D01*
X1447717Y2223889D01*
X1446967Y2224449D01*
X1446467Y2225102D01*
X1446342Y2225849D01*
X1446467Y2226596D01*
X1446967Y2227249D01*
X1447717Y2227809D01*
X1448592Y2228182D01*
X1449592Y2228369D01*
X1450592D01*
X1451592Y2228182D01*
X1452467Y2227809D01*
X1453217Y2227249D01*
X1453717Y2226596D01*
X1453842Y2225849D01*
G01Y2231202D02*
X1446342D01*
X1453842Y2235496D01*
X1446342D01*
G01X1456342Y2241316D02*
X1455092Y2242249D01*
X1453842Y2242716D01*
X1448842D01*
X1447592Y2242249D01*
X1446342Y2241316D01*
G01X1454092Y2248349D02*
X1453967Y2248162D01*
X1453717D01*
X1453592Y2248349D01*
X1453717Y2248536D01*
X1453967D01*
X1454092Y2248349D01*
G01X1450717D02*
X1450592Y2248162D01*
X1450342D01*
X1450217Y2248349D01*
X1450342Y2248536D01*
X1450592D01*
X1450717Y2248349D01*
G01X1453842Y2253982D02*
X1446342D01*
Y2256316D01*
X1446717Y2257062D01*
X1447217Y2257529D01*
X1448217Y2257716D01*
X1449217Y2257529D01*
X1449842Y2256969D01*
X1450217Y2256316D01*
Y2253982D01*
G01Y2256316D02*
X1453842Y2257716D01*
G01Y2265216D02*
Y2261482D01*
X1446342D01*
Y2265216D01*
G01X1449967Y2263722D02*
Y2261482D01*
G01X1446967Y2272902D02*
X1446592Y2272342D01*
X1446342Y2271689D01*
Y2270942D01*
X1446717Y2270102D01*
X1447342Y2269449D01*
X1448092Y2268982D01*
X1449342Y2268609D01*
X1450467Y2268516D01*
X1451592Y2268702D01*
X1452342Y2268982D01*
X1453092Y2269542D01*
X1453592Y2270196D01*
X1453842Y2270849D01*
Y2271502D01*
X1453592Y2272156D01*
X1453217Y2272716D01*
X1452717Y2273182D01*
G01X1453842Y2278349D02*
X1453717Y2277602D01*
X1453217Y2276949D01*
X1452467Y2276389D01*
X1451592Y2276016D01*
X1450592Y2275829D01*
X1449592D01*
X1448592Y2276016D01*
X1447717Y2276389D01*
X1446967Y2276949D01*
X1446467Y2277602D01*
X1446342Y2278349D01*
X1446467Y2279096D01*
X1446967Y2279749D01*
X1447717Y2280309D01*
X1448592Y2280682D01*
X1449592Y2280869D01*
X1450592D01*
X1451592Y2280682D01*
X1452467Y2280309D01*
X1453217Y2279749D01*
X1453717Y2279096D01*
X1453842Y2278349D01*
G01Y2283422D02*
X1446342D01*
X1452592Y2285849D01*
X1446342Y2288276D01*
X1453842D01*
G01Y2290922D02*
X1446342D01*
X1452592Y2293349D01*
X1446342Y2295776D01*
X1453842D01*
G01Y2302716D02*
Y2298982D01*
X1446342D01*
Y2302716D01*
G01X1449967Y2301222D02*
Y2298982D01*
G01X1453842Y2306202D02*
X1446342D01*
X1453842Y2310496D01*
X1446342D01*
G01X1453842Y2313796D02*
X1446342D01*
Y2315662D01*
X1446717Y2316409D01*
X1447217Y2316969D01*
X1447967Y2317436D01*
X1448842Y2317809D01*
X1450092Y2317902D01*
X1451342Y2317809D01*
X1452217Y2317436D01*
X1452967Y2316969D01*
X1453467Y2316409D01*
X1453842Y2315662D01*
Y2313796D01*
G01Y2325216D02*
Y2321482D01*
X1446342D01*
Y2325216D01*
G01X1449967Y2323722D02*
Y2321482D01*
G01X1453842Y2328796D02*
X1446342D01*
Y2330662D01*
X1446717Y2331409D01*
X1447217Y2331969D01*
X1447967Y2332436D01*
X1448842Y2332809D01*
X1450092Y2332902D01*
X1451342Y2332809D01*
X1452217Y2332436D01*
X1452967Y2331969D01*
X1453467Y2331409D01*
X1453842Y2330662D01*
Y2328796D01*
G01Y2343796D02*
X1446342D01*
Y2345662D01*
X1446717Y2346409D01*
X1447217Y2346969D01*
X1447967Y2347436D01*
X1448842Y2347809D01*
X1450092Y2347902D01*
X1451342Y2347809D01*
X1452217Y2347436D01*
X1452967Y2346969D01*
X1453467Y2346409D01*
X1453842Y2345662D01*
Y2343796D01*
G01Y2351482D02*
X1446342D01*
Y2353816D01*
X1446717Y2354562D01*
X1447217Y2355029D01*
X1448217Y2355216D01*
X1449217Y2355029D01*
X1449842Y2354469D01*
X1450217Y2353816D01*
Y2351482D01*
G01Y2353816D02*
X1453842Y2355216D01*
G01X1446342Y2359729D02*
Y2361969D01*
G01Y2360849D02*
X1453842D01*
G01Y2359729D02*
Y2361969D01*
G01X1446342Y2366482D02*
X1453842D01*
Y2370216D01*
G01X1446342Y2373982D02*
X1453842D01*
Y2377716D01*
G01X1452842Y2388889D02*
X1453467Y2389636D01*
X1453842Y2390476D01*
Y2391222D01*
X1453467Y2391969D01*
X1452842Y2392529D01*
X1451967Y2392809D01*
X1451092Y2392622D01*
X1450342Y2392156D01*
X1449842Y2391316D01*
X1449592Y2390196D01*
X1449092Y2389542D01*
X1448217Y2389262D01*
X1447342Y2389449D01*
X1446717Y2389916D01*
X1446342Y2390569D01*
Y2391222D01*
X1446592Y2391876D01*
X1447217Y2392436D01*
G01X1446342Y2397229D02*
Y2399469D01*
G01Y2398349D02*
X1453842D01*
G01Y2397229D02*
Y2399469D01*
G01X1446342Y2404076D02*
Y2407622D01*
X1453842Y2404076D01*
Y2407622D01*
G01Y2415216D02*
Y2411482D01*
X1446342D01*
Y2415216D01*
G01X1449967Y2413722D02*
Y2411482D01*
G01X1453842Y2426576D02*
X1446342D01*
Y2430122D01*
G01X1449967Y2428816D02*
Y2426576D01*
G01X1453842Y2435849D02*
X1453717Y2435102D01*
X1453217Y2434449D01*
X1452467Y2433889D01*
X1451592Y2433516D01*
X1450592Y2433329D01*
X1449592D01*
X1448592Y2433516D01*
X1447717Y2433889D01*
X1446967Y2434449D01*
X1446467Y2435102D01*
X1446342Y2435849D01*
X1446467Y2436596D01*
X1446967Y2437249D01*
X1447717Y2437809D01*
X1448592Y2438182D01*
X1449592Y2438369D01*
X1450592D01*
X1451592Y2438182D01*
X1452467Y2437809D01*
X1453217Y2437249D01*
X1453717Y2436596D01*
X1453842Y2435849D01*
G01Y2441482D02*
X1446342D01*
Y2443816D01*
X1446717Y2444562D01*
X1447217Y2445029D01*
X1448217Y2445216D01*
X1449217Y2445029D01*
X1449842Y2444469D01*
X1450217Y2443816D01*
Y2441482D01*
G01Y2443816D02*
X1453842Y2445216D01*
G01X1446342Y2458349D02*
X1446592Y2457602D01*
X1447217Y2457042D01*
X1447967Y2456669D01*
X1448967Y2456389D01*
X1450092Y2456296D01*
X1451217Y2456389D01*
X1452217Y2456669D01*
X1452967Y2457042D01*
X1453592Y2457602D01*
X1453842Y2458349D01*
X1453592Y2459096D01*
X1452967Y2459656D01*
X1452217Y2460029D01*
X1451217Y2460309D01*
X1450092Y2460402D01*
X1448967Y2460309D01*
X1447967Y2460029D01*
X1447217Y2459656D01*
X1446592Y2459096D01*
X1446342Y2458349D01*
G01X1454092Y2465849D02*
X1453967Y2465662D01*
X1453717D01*
X1453592Y2465849D01*
X1453717Y2466036D01*
X1453967D01*
X1454092Y2465849D01*
G01X1452717Y2471296D02*
X1453342Y2471856D01*
X1453717Y2472509D01*
X1453842Y2473349D01*
X1453592Y2474189D01*
X1453092Y2474842D01*
X1452217Y2475309D01*
X1451217Y2475402D01*
X1450217Y2475216D01*
X1449592Y2474749D01*
X1449092Y2474096D01*
X1448967Y2473442D01*
X1449092Y2472789D01*
X1449592Y2471949D01*
X1446342Y2472229D01*
Y2474749D01*
G01X1453842Y2478422D02*
X1446342D01*
X1452592Y2480849D01*
X1446342Y2483276D01*
X1453842D01*
G01Y2485922D02*
X1446342D01*
X1452592Y2488349D01*
X1446342Y2490776D01*
X1453842D01*
G01Y2501576D02*
X1446342D01*
Y2505122D01*
G01X1449967Y2503816D02*
Y2501576D01*
G01X1446342Y2509729D02*
Y2511969D01*
G01Y2510849D02*
X1453842D01*
G01Y2509729D02*
Y2511969D01*
G01Y2516202D02*
X1446342D01*
X1453842Y2520496D01*
X1446342D01*
G01Y2524729D02*
Y2526969D01*
G01Y2525849D02*
X1453842D01*
G01Y2524729D02*
Y2526969D01*
G01X1452842Y2531389D02*
X1453467Y2532136D01*
X1453842Y2532976D01*
Y2533722D01*
X1453467Y2534469D01*
X1452842Y2535029D01*
X1451967Y2535309D01*
X1451092Y2535122D01*
X1450342Y2534656D01*
X1449842Y2533816D01*
X1449592Y2532696D01*
X1449092Y2532042D01*
X1448217Y2531762D01*
X1447342Y2531949D01*
X1446717Y2532416D01*
X1446342Y2533069D01*
Y2533722D01*
X1446592Y2534376D01*
X1447217Y2534936D01*
G01X1453842Y2538889D02*
X1446342D01*
G01Y2542809D02*
X1453842D01*
G01X1450092D02*
Y2538889D01*
G01X1453842Y2550216D02*
Y2546482D01*
X1446342D01*
Y2550216D01*
G01X1449967Y2548722D02*
Y2546482D01*
G01X1453842Y2553796D02*
X1446342D01*
Y2555662D01*
X1446717Y2556409D01*
X1447217Y2556969D01*
X1447967Y2557436D01*
X1448842Y2557809D01*
X1450092Y2557902D01*
X1451342Y2557809D01*
X1452217Y2557436D01*
X1452967Y2556969D01*
X1453467Y2556409D01*
X1453842Y2555662D01*
Y2553796D01*
G01Y2568982D02*
X1446342D01*
Y2571222D01*
X1446717Y2571969D01*
X1447592Y2572529D01*
X1448592Y2572716D01*
X1449592Y2572529D01*
X1450342Y2572062D01*
X1450717Y2571222D01*
Y2568982D01*
G01X1446342Y2578349D02*
X1453842D01*
G01X1446342Y2576202D02*
Y2580496D01*
G01X1453842Y2583889D02*
X1446342D01*
G01Y2587809D02*
X1453842D01*
G01X1450092D02*
Y2583889D01*
G01X1446342Y2599729D02*
Y2601969D01*
G01Y2600849D02*
X1453842D01*
G01Y2599729D02*
Y2601969D01*
G01X1452842Y2606389D02*
X1453467Y2607136D01*
X1453842Y2607976D01*
Y2608722D01*
X1453467Y2609469D01*
X1452842Y2610029D01*
X1451967Y2610309D01*
X1451092Y2610122D01*
X1450342Y2609656D01*
X1449842Y2608816D01*
X1449592Y2607696D01*
X1449092Y2607042D01*
X1448217Y2606762D01*
X1447342Y2606949D01*
X1446717Y2607416D01*
X1446342Y2608069D01*
Y2608722D01*
X1446592Y2609376D01*
X1447217Y2609936D01*
G01X1446342Y2623349D02*
X1446592Y2622602D01*
X1447217Y2622042D01*
X1447967Y2621669D01*
X1448967Y2621389D01*
X1450092Y2621296D01*
X1451217Y2621389D01*
X1452217Y2621669D01*
X1452967Y2622042D01*
X1453592Y2622602D01*
X1453842Y2623349D01*
X1453592Y2624096D01*
X1452967Y2624656D01*
X1452217Y2625029D01*
X1451217Y2625309D01*
X1450092Y2625402D01*
X1448967Y2625309D01*
X1447967Y2625029D01*
X1447217Y2624656D01*
X1446592Y2624096D01*
X1446342Y2623349D01*
G01X1454092Y2630849D02*
X1453967Y2630662D01*
X1453717D01*
X1453592Y2630849D01*
X1453717Y2631036D01*
X1453967D01*
X1454092Y2630849D01*
G01X1450717Y2636576D02*
X1449842Y2637229D01*
X1449342Y2637789D01*
X1449092Y2638536D01*
X1449342Y2639189D01*
X1449842Y2639656D01*
X1450592Y2640029D01*
X1451467Y2640122D01*
X1452217Y2640029D01*
X1452967Y2639656D01*
X1453592Y2639096D01*
X1453842Y2638442D01*
X1453592Y2637696D01*
X1452842Y2637042D01*
X1451717Y2636669D01*
X1450467Y2636576D01*
X1448842Y2636762D01*
X1447967Y2637042D01*
X1447092Y2637509D01*
X1446467Y2638162D01*
X1446342Y2638816D01*
X1446592Y2639469D01*
X1447217Y2639936D01*
G01X1453842Y2643422D02*
X1446342D01*
X1452592Y2645849D01*
X1446342Y2648276D01*
X1453842D01*
G01Y2650922D02*
X1446342D01*
X1452592Y2653349D01*
X1446342Y2655776D01*
X1453842D01*
G01Y2665922D02*
X1446342D01*
X1452592Y2668349D01*
X1446342Y2670776D01*
X1453842D01*
G01Y2677716D02*
Y2673982D01*
X1446342D01*
Y2677716D01*
G01X1449967Y2676222D02*
Y2673982D01*
G01X1446342Y2683349D02*
X1453842D01*
G01X1446342Y2681202D02*
Y2685496D01*
G01X1453842Y2688982D02*
X1446342D01*
Y2691316D01*
X1446717Y2692062D01*
X1447217Y2692529D01*
X1448217Y2692716D01*
X1449217Y2692529D01*
X1449842Y2691969D01*
X1450217Y2691316D01*
Y2688982D01*
G01Y2691316D02*
X1453842Y2692716D01*
G01X1446342Y2697229D02*
Y2699469D01*
G01Y2698349D02*
X1453842D01*
G01Y2697229D02*
Y2699469D01*
G01X1446967Y2707902D02*
X1446592Y2707342D01*
X1446342Y2706689D01*
Y2705942D01*
X1446717Y2705102D01*
X1447342Y2704449D01*
X1448092Y2703982D01*
X1449342Y2703609D01*
X1450467Y2703516D01*
X1451592Y2703702D01*
X1452342Y2703982D01*
X1453092Y2704542D01*
X1453592Y2705196D01*
X1453842Y2705849D01*
Y2706502D01*
X1453592Y2707156D01*
X1453217Y2707716D01*
X1452717Y2708182D01*
G01X1453842Y2718796D02*
X1446342D01*
Y2720662D01*
X1446717Y2721409D01*
X1447217Y2721969D01*
X1447967Y2722436D01*
X1448842Y2722809D01*
X1450092Y2722902D01*
X1451342Y2722809D01*
X1452217Y2722436D01*
X1452967Y2721969D01*
X1453467Y2721409D01*
X1453842Y2720662D01*
Y2718796D01*
G01Y2726482D02*
X1446342D01*
Y2728816D01*
X1446717Y2729562D01*
X1447217Y2730029D01*
X1448217Y2730216D01*
X1449217Y2730029D01*
X1449842Y2729469D01*
X1450217Y2728816D01*
Y2726482D01*
G01Y2728816D02*
X1453842Y2730216D01*
G01X1446342Y2734729D02*
Y2736969D01*
G01Y2735849D02*
X1453842D01*
G01Y2734729D02*
Y2736969D01*
G01X1446342Y2741482D02*
X1453842D01*
Y2745216D01*
G01X1446342Y2748982D02*
X1453842D01*
Y2752716D01*
G01X1456342Y2757882D02*
X1455092Y2756949D01*
X1453842Y2756482D01*
X1448842D01*
X1447592Y2756949D01*
X1446342Y2757882D01*
G01Y2765849D02*
X1446592Y2765102D01*
X1447217Y2764542D01*
X1447967Y2764169D01*
X1448967Y2763889D01*
X1450092Y2763796D01*
X1451217Y2763889D01*
X1452217Y2764169D01*
X1452967Y2764542D01*
X1453592Y2765102D01*
X1453842Y2765849D01*
X1453592Y2766596D01*
X1452967Y2767156D01*
X1452217Y2767529D01*
X1451217Y2767809D01*
X1450092Y2767902D01*
X1448967Y2767809D01*
X1447967Y2767529D01*
X1447217Y2767156D01*
X1446592Y2766596D01*
X1446342Y2765849D01*
G01X1454092Y2773349D02*
X1453967Y2773162D01*
X1453717D01*
X1453592Y2773349D01*
X1453717Y2773536D01*
X1453967D01*
X1454092Y2773349D01*
G01X1446342Y2780849D02*
X1446592Y2780102D01*
X1447217Y2779542D01*
X1447967Y2779169D01*
X1448967Y2778889D01*
X1450092Y2778796D01*
X1451217Y2778889D01*
X1452217Y2779169D01*
X1452967Y2779542D01*
X1453592Y2780102D01*
X1453842Y2780849D01*
X1453592Y2781596D01*
X1452967Y2782156D01*
X1452217Y2782529D01*
X1451217Y2782809D01*
X1450092Y2782902D01*
X1448967Y2782809D01*
X1447967Y2782529D01*
X1447217Y2782156D01*
X1446592Y2781596D01*
X1446342Y2780849D01*
G01X1447592Y2786576D02*
X1446842Y2787136D01*
X1446467Y2787789D01*
X1446342Y2788536D01*
X1446592Y2789469D01*
X1447217Y2790122D01*
X1447967Y2790309D01*
X1448717Y2790216D01*
X1449342Y2789842D01*
X1450592Y2787976D01*
X1451467Y2787136D01*
X1452717Y2786576D01*
X1453842Y2786389D01*
Y2790309D01*
G01X1452342Y2793796D02*
X1453217Y2794356D01*
X1453717Y2795102D01*
X1453842Y2795942D01*
X1453717Y2796689D01*
X1453092Y2797436D01*
X1452342Y2797902D01*
X1451592Y2797996D01*
X1450717Y2797809D01*
X1450092Y2797156D01*
X1449842Y2796502D01*
Y2795662D01*
G01Y2796502D02*
X1449467Y2797062D01*
X1448842Y2797529D01*
X1448092Y2797716D01*
X1447342Y2797529D01*
X1446717Y2797062D01*
X1446342Y2796222D01*
X1446467Y2795382D01*
X1446967Y2794542D01*
G01X1450717Y2801576D02*
X1449842Y2802229D01*
X1449342Y2802789D01*
X1449092Y2803536D01*
X1449342Y2804189D01*
X1449842Y2804656D01*
X1450592Y2805029D01*
X1451467Y2805122D01*
X1452217Y2805029D01*
X1452967Y2804656D01*
X1453592Y2804096D01*
X1453842Y2803442D01*
X1453592Y2802696D01*
X1452842Y2802042D01*
X1451717Y2801669D01*
X1450467Y2801576D01*
X1448842Y2801762D01*
X1447967Y2802042D01*
X1447092Y2802509D01*
X1446467Y2803162D01*
X1446342Y2803816D01*
X1446592Y2804469D01*
X1447217Y2804936D01*
G01X1447967Y2810009D02*
X1446342Y2810476D01*
G01Y2811689D02*
X1447967Y2811222D01*
G01X1456342Y2818816D02*
X1455092Y2819749D01*
X1453842Y2820216D01*
X1448842D01*
X1447592Y2819749D01*
X1446342Y2818816D01*
G01X1454092Y2825849D02*
X1453967Y2825662D01*
X1453717D01*
X1453592Y2825849D01*
X1453717Y2826036D01*
X1453967D01*
X1454092Y2825849D01*
G01X1465742Y2058889D02*
X1466367Y2059636D01*
X1466742Y2060476D01*
Y2061222D01*
X1466367Y2061969D01*
X1465742Y2062529D01*
X1464867Y2062809D01*
X1463992Y2062622D01*
X1463242Y2062156D01*
X1462742Y2061316D01*
X1462492Y2060196D01*
X1461992Y2059542D01*
X1461117Y2059262D01*
X1460242Y2059449D01*
X1459617Y2059916D01*
X1459242Y2060569D01*
Y2061222D01*
X1459492Y2061876D01*
X1460117Y2062436D01*
G01X1459242Y2067229D02*
Y2069469D01*
G01Y2068349D02*
X1466742D01*
G01Y2067229D02*
Y2069469D01*
G01X1459242Y2073982D02*
X1466742D01*
Y2077716D01*
G01X1459242Y2081016D02*
X1466742Y2083349D01*
X1459242Y2085682D01*
G01X1466742Y2092716D02*
Y2088982D01*
X1459242D01*
Y2092716D01*
G01X1462867Y2091222D02*
Y2088982D01*
G01X1466742Y2096482D02*
X1459242D01*
Y2098816D01*
X1459617Y2099562D01*
X1460117Y2100029D01*
X1461117Y2100216D01*
X1462117Y2100029D01*
X1462742Y2099469D01*
X1463117Y2098816D01*
Y2096482D01*
G01Y2098816D02*
X1466742Y2100216D01*
G01X1469242Y2105382D02*
X1467992Y2104449D01*
X1466742Y2103982D01*
X1461742D01*
X1460492Y2104449D01*
X1459242Y2105382D01*
G01Y2112229D02*
Y2114469D01*
G01Y2113349D02*
X1466742D01*
G01Y2112229D02*
Y2114469D01*
G01Y2118422D02*
X1459242D01*
X1465492Y2120849D01*
X1459242Y2123276D01*
X1466742D01*
G01Y2125922D02*
X1459242D01*
X1465492Y2128349D01*
X1459242Y2130776D01*
X1466742D01*
G01Y2137716D02*
Y2133982D01*
X1459242D01*
Y2137716D01*
G01X1462867Y2136222D02*
Y2133982D01*
G01X1466742Y2141482D02*
X1459242D01*
Y2143816D01*
X1459617Y2144562D01*
X1460117Y2145029D01*
X1461117Y2145216D01*
X1462117Y2145029D01*
X1462742Y2144469D01*
X1463117Y2143816D01*
Y2141482D01*
G01Y2143816D02*
X1466742Y2145216D01*
G01X1465742Y2148889D02*
X1466367Y2149636D01*
X1466742Y2150476D01*
Y2151222D01*
X1466367Y2151969D01*
X1465742Y2152529D01*
X1464867Y2152809D01*
X1463992Y2152622D01*
X1463242Y2152156D01*
X1462742Y2151316D01*
X1462492Y2150196D01*
X1461992Y2149542D01*
X1461117Y2149262D01*
X1460242Y2149449D01*
X1459617Y2149916D01*
X1459242Y2150569D01*
Y2151222D01*
X1459492Y2151876D01*
X1460117Y2152436D01*
G01X1459242Y2157229D02*
Y2159469D01*
G01Y2158349D02*
X1466742D01*
G01Y2157229D02*
Y2159469D01*
G01Y2165849D02*
X1466617Y2165102D01*
X1466117Y2164449D01*
X1465367Y2163889D01*
X1464492Y2163516D01*
X1463492Y2163329D01*
X1462492D01*
X1461492Y2163516D01*
X1460617Y2163889D01*
X1459867Y2164449D01*
X1459367Y2165102D01*
X1459242Y2165849D01*
X1459367Y2166596D01*
X1459867Y2167249D01*
X1460617Y2167809D01*
X1461492Y2168182D01*
X1462492Y2168369D01*
X1463492D01*
X1464492Y2168182D01*
X1465367Y2167809D01*
X1466117Y2167249D01*
X1466617Y2166596D01*
X1466742Y2165849D01*
G01Y2171202D02*
X1459242D01*
X1466742Y2175496D01*
X1459242D01*
G01X1469242Y2181316D02*
X1467992Y2182249D01*
X1466742Y2182716D01*
X1461742D01*
X1460492Y2182249D01*
X1459242Y2181316D01*
G01X1466992Y2188349D02*
X1466867Y2188162D01*
X1466617D01*
X1466492Y2188349D01*
X1466617Y2188536D01*
X1466867D01*
X1466992Y2188349D01*
G01X1463617D02*
X1463492Y2188162D01*
X1463242D01*
X1463117Y2188349D01*
X1463242Y2188536D01*
X1463492D01*
X1463617Y2188349D01*
G01X1466742Y2193982D02*
X1459242D01*
Y2196316D01*
X1459617Y2197062D01*
X1460117Y2197529D01*
X1461117Y2197716D01*
X1462117Y2197529D01*
X1462742Y2196969D01*
X1463117Y2196316D01*
Y2193982D01*
G01Y2196316D02*
X1466742Y2197716D01*
G01Y2205216D02*
Y2201482D01*
X1459242D01*
Y2205216D01*
G01X1462867Y2203722D02*
Y2201482D01*
G01X1459867Y2212902D02*
X1459492Y2212342D01*
X1459242Y2211689D01*
Y2210942D01*
X1459617Y2210102D01*
X1460242Y2209449D01*
X1460992Y2208982D01*
X1462242Y2208609D01*
X1463367Y2208516D01*
X1464492Y2208702D01*
X1465242Y2208982D01*
X1465992Y2209542D01*
X1466492Y2210196D01*
X1466742Y2210849D01*
Y2211502D01*
X1466492Y2212156D01*
X1466117Y2212716D01*
X1465617Y2213182D01*
G01X1466742Y2218349D02*
X1466617Y2217602D01*
X1466117Y2216949D01*
X1465367Y2216389D01*
X1464492Y2216016D01*
X1463492Y2215829D01*
X1462492D01*
X1461492Y2216016D01*
X1460617Y2216389D01*
X1459867Y2216949D01*
X1459367Y2217602D01*
X1459242Y2218349D01*
X1459367Y2219096D01*
X1459867Y2219749D01*
X1460617Y2220309D01*
X1461492Y2220682D01*
X1462492Y2220869D01*
X1463492D01*
X1464492Y2220682D01*
X1465367Y2220309D01*
X1466117Y2219749D01*
X1466617Y2219096D01*
X1466742Y2218349D01*
G01Y2223422D02*
X1459242D01*
X1465492Y2225849D01*
X1459242Y2228276D01*
X1466742D01*
G01Y2230922D02*
X1459242D01*
X1465492Y2233349D01*
X1459242Y2235776D01*
X1466742D01*
G01Y2242716D02*
Y2238982D01*
X1459242D01*
Y2242716D01*
G01X1462867Y2241222D02*
Y2238982D01*
G01X1466742Y2246202D02*
X1459242D01*
X1466742Y2250496D01*
X1459242D01*
G01X1466742Y2253796D02*
X1459242D01*
Y2255662D01*
X1459617Y2256409D01*
X1460117Y2256969D01*
X1460867Y2257436D01*
X1461742Y2257809D01*
X1462992Y2257902D01*
X1464242Y2257809D01*
X1465117Y2257436D01*
X1465867Y2256969D01*
X1466367Y2256409D01*
X1466742Y2255662D01*
Y2253796D01*
G01Y2265216D02*
Y2261482D01*
X1459242D01*
Y2265216D01*
G01X1462867Y2263722D02*
Y2261482D01*
G01X1466742Y2268796D02*
X1459242D01*
Y2270662D01*
X1459617Y2271409D01*
X1460117Y2271969D01*
X1460867Y2272436D01*
X1461742Y2272809D01*
X1462992Y2272902D01*
X1464242Y2272809D01*
X1465117Y2272436D01*
X1465867Y2271969D01*
X1466367Y2271409D01*
X1466742Y2270662D01*
Y2268796D01*
G01Y2283796D02*
X1459242D01*
Y2285662D01*
X1459617Y2286409D01*
X1460117Y2286969D01*
X1460867Y2287436D01*
X1461742Y2287809D01*
X1462992Y2287902D01*
X1464242Y2287809D01*
X1465117Y2287436D01*
X1465867Y2286969D01*
X1466367Y2286409D01*
X1466742Y2285662D01*
Y2283796D01*
G01Y2291482D02*
X1459242D01*
Y2293816D01*
X1459617Y2294562D01*
X1460117Y2295029D01*
X1461117Y2295216D01*
X1462117Y2295029D01*
X1462742Y2294469D01*
X1463117Y2293816D01*
Y2291482D01*
G01Y2293816D02*
X1466742Y2295216D01*
G01X1459242Y2299729D02*
Y2301969D01*
G01Y2300849D02*
X1466742D01*
G01Y2299729D02*
Y2301969D01*
G01X1459242Y2306482D02*
X1466742D01*
Y2310216D01*
G01X1459242Y2313982D02*
X1466742D01*
Y2317716D01*
G01X1465742Y2328889D02*
X1466367Y2329636D01*
X1466742Y2330476D01*
Y2331222D01*
X1466367Y2331969D01*
X1465742Y2332529D01*
X1464867Y2332809D01*
X1463992Y2332622D01*
X1463242Y2332156D01*
X1462742Y2331316D01*
X1462492Y2330196D01*
X1461992Y2329542D01*
X1461117Y2329262D01*
X1460242Y2329449D01*
X1459617Y2329916D01*
X1459242Y2330569D01*
Y2331222D01*
X1459492Y2331876D01*
X1460117Y2332436D01*
G01X1459242Y2337229D02*
Y2339469D01*
G01Y2338349D02*
X1466742D01*
G01Y2337229D02*
Y2339469D01*
G01X1459242Y2344076D02*
Y2347622D01*
X1466742Y2344076D01*
Y2347622D01*
G01Y2355216D02*
Y2351482D01*
X1459242D01*
Y2355216D01*
G01X1462867Y2353722D02*
Y2351482D01*
G01X1466742Y2366576D02*
X1459242D01*
Y2370122D01*
G01X1462867Y2368816D02*
Y2366576D01*
G01X1466742Y2375849D02*
X1466617Y2375102D01*
X1466117Y2374449D01*
X1465367Y2373889D01*
X1464492Y2373516D01*
X1463492Y2373329D01*
X1462492D01*
X1461492Y2373516D01*
X1460617Y2373889D01*
X1459867Y2374449D01*
X1459367Y2375102D01*
X1459242Y2375849D01*
X1459367Y2376596D01*
X1459867Y2377249D01*
X1460617Y2377809D01*
X1461492Y2378182D01*
X1462492Y2378369D01*
X1463492D01*
X1464492Y2378182D01*
X1465367Y2377809D01*
X1466117Y2377249D01*
X1466617Y2376596D01*
X1466742Y2375849D01*
G01Y2381482D02*
X1459242D01*
Y2383816D01*
X1459617Y2384562D01*
X1460117Y2385029D01*
X1461117Y2385216D01*
X1462117Y2385029D01*
X1462742Y2384469D01*
X1463117Y2383816D01*
Y2381482D01*
G01Y2383816D02*
X1466742Y2385216D01*
G01X1459242Y2398349D02*
X1459492Y2397602D01*
X1460117Y2397042D01*
X1460867Y2396669D01*
X1461867Y2396389D01*
X1462992Y2396296D01*
X1464117Y2396389D01*
X1465117Y2396669D01*
X1465867Y2397042D01*
X1466492Y2397602D01*
X1466742Y2398349D01*
X1466492Y2399096D01*
X1465867Y2399656D01*
X1465117Y2400029D01*
X1464117Y2400309D01*
X1462992Y2400402D01*
X1461867Y2400309D01*
X1460867Y2400029D01*
X1460117Y2399656D01*
X1459492Y2399096D01*
X1459242Y2398349D01*
G01X1466992Y2405849D02*
X1466867Y2405662D01*
X1466617D01*
X1466492Y2405849D01*
X1466617Y2406036D01*
X1466867D01*
X1466992Y2405849D01*
G01X1465617Y2411296D02*
X1466242Y2411856D01*
X1466617Y2412509D01*
X1466742Y2413349D01*
X1466492Y2414189D01*
X1465992Y2414842D01*
X1465117Y2415309D01*
X1464117Y2415402D01*
X1463117Y2415216D01*
X1462492Y2414749D01*
X1461992Y2414096D01*
X1461867Y2413442D01*
X1461992Y2412789D01*
X1462492Y2411949D01*
X1459242Y2412229D01*
Y2414749D01*
G01X1466742Y2418422D02*
X1459242D01*
X1465492Y2420849D01*
X1459242Y2423276D01*
X1466742D01*
G01Y2425922D02*
X1459242D01*
X1465492Y2428349D01*
X1459242Y2430776D01*
X1466742D01*
G01Y2441576D02*
X1459242D01*
Y2445122D01*
G01X1462867Y2443816D02*
Y2441576D01*
G01X1459242Y2449729D02*
Y2451969D01*
G01Y2450849D02*
X1466742D01*
G01Y2449729D02*
Y2451969D01*
G01Y2456202D02*
X1459242D01*
X1466742Y2460496D01*
X1459242D01*
G01Y2464729D02*
Y2466969D01*
G01Y2465849D02*
X1466742D01*
G01Y2464729D02*
Y2466969D01*
G01X1465742Y2471389D02*
X1466367Y2472136D01*
X1466742Y2472976D01*
Y2473722D01*
X1466367Y2474469D01*
X1465742Y2475029D01*
X1464867Y2475309D01*
X1463992Y2475122D01*
X1463242Y2474656D01*
X1462742Y2473816D01*
X1462492Y2472696D01*
X1461992Y2472042D01*
X1461117Y2471762D01*
X1460242Y2471949D01*
X1459617Y2472416D01*
X1459242Y2473069D01*
Y2473722D01*
X1459492Y2474376D01*
X1460117Y2474936D01*
G01X1466742Y2478889D02*
X1459242D01*
G01Y2482809D02*
X1466742D01*
G01X1462992D02*
Y2478889D01*
G01X1466742Y2490216D02*
Y2486482D01*
X1459242D01*
Y2490216D01*
G01X1462867Y2488722D02*
Y2486482D01*
G01X1466742Y2493796D02*
X1459242D01*
Y2495662D01*
X1459617Y2496409D01*
X1460117Y2496969D01*
X1460867Y2497436D01*
X1461742Y2497809D01*
X1462992Y2497902D01*
X1464242Y2497809D01*
X1465117Y2497436D01*
X1465867Y2496969D01*
X1466367Y2496409D01*
X1466742Y2495662D01*
Y2493796D01*
G01Y2508982D02*
X1459242D01*
Y2511222D01*
X1459617Y2511969D01*
X1460492Y2512529D01*
X1461492Y2512716D01*
X1462492Y2512529D01*
X1463242Y2512062D01*
X1463617Y2511222D01*
Y2508982D01*
G01X1459242Y2518349D02*
X1466742D01*
G01X1459242Y2516202D02*
Y2520496D01*
G01X1466742Y2523889D02*
X1459242D01*
G01Y2527809D02*
X1466742D01*
G01X1462992D02*
Y2523889D01*
G01X1459242Y2539729D02*
Y2541969D01*
G01Y2540849D02*
X1466742D01*
G01Y2539729D02*
Y2541969D01*
G01X1465742Y2546389D02*
X1466367Y2547136D01*
X1466742Y2547976D01*
Y2548722D01*
X1466367Y2549469D01*
X1465742Y2550029D01*
X1464867Y2550309D01*
X1463992Y2550122D01*
X1463242Y2549656D01*
X1462742Y2548816D01*
X1462492Y2547696D01*
X1461992Y2547042D01*
X1461117Y2546762D01*
X1460242Y2546949D01*
X1459617Y2547416D01*
X1459242Y2548069D01*
Y2548722D01*
X1459492Y2549376D01*
X1460117Y2549936D01*
G01X1459242Y2563349D02*
X1459492Y2562602D01*
X1460117Y2562042D01*
X1460867Y2561669D01*
X1461867Y2561389D01*
X1462992Y2561296D01*
X1464117Y2561389D01*
X1465117Y2561669D01*
X1465867Y2562042D01*
X1466492Y2562602D01*
X1466742Y2563349D01*
X1466492Y2564096D01*
X1465867Y2564656D01*
X1465117Y2565029D01*
X1464117Y2565309D01*
X1462992Y2565402D01*
X1461867Y2565309D01*
X1460867Y2565029D01*
X1460117Y2564656D01*
X1459492Y2564096D01*
X1459242Y2563349D01*
G01X1466992Y2570849D02*
X1466867Y2570662D01*
X1466617D01*
X1466492Y2570849D01*
X1466617Y2571036D01*
X1466867D01*
X1466992Y2570849D01*
G01X1463617Y2576576D02*
X1462742Y2577229D01*
X1462242Y2577789D01*
X1461992Y2578536D01*
X1462242Y2579189D01*
X1462742Y2579656D01*
X1463492Y2580029D01*
X1464367Y2580122D01*
X1465117Y2580029D01*
X1465867Y2579656D01*
X1466492Y2579096D01*
X1466742Y2578442D01*
X1466492Y2577696D01*
X1465742Y2577042D01*
X1464617Y2576669D01*
X1463367Y2576576D01*
X1461742Y2576762D01*
X1460867Y2577042D01*
X1459992Y2577509D01*
X1459367Y2578162D01*
X1459242Y2578816D01*
X1459492Y2579469D01*
X1460117Y2579936D01*
G01X1466742Y2583422D02*
X1459242D01*
X1465492Y2585849D01*
X1459242Y2588276D01*
X1466742D01*
G01Y2590922D02*
X1459242D01*
X1465492Y2593349D01*
X1459242Y2595776D01*
X1466742D01*
G01Y2605922D02*
X1459242D01*
X1465492Y2608349D01*
X1459242Y2610776D01*
X1466742D01*
G01Y2617716D02*
Y2613982D01*
X1459242D01*
Y2617716D01*
G01X1462867Y2616222D02*
Y2613982D01*
G01X1459242Y2623349D02*
X1466742D01*
G01X1459242Y2621202D02*
Y2625496D01*
G01X1466742Y2628982D02*
X1459242D01*
Y2631316D01*
X1459617Y2632062D01*
X1460117Y2632529D01*
X1461117Y2632716D01*
X1462117Y2632529D01*
X1462742Y2631969D01*
X1463117Y2631316D01*
Y2628982D01*
G01Y2631316D02*
X1466742Y2632716D01*
G01X1459242Y2637229D02*
Y2639469D01*
G01Y2638349D02*
X1466742D01*
G01Y2637229D02*
Y2639469D01*
G01X1459867Y2647902D02*
X1459492Y2647342D01*
X1459242Y2646689D01*
Y2645942D01*
X1459617Y2645102D01*
X1460242Y2644449D01*
X1460992Y2643982D01*
X1462242Y2643609D01*
X1463367Y2643516D01*
X1464492Y2643702D01*
X1465242Y2643982D01*
X1465992Y2644542D01*
X1466492Y2645196D01*
X1466742Y2645849D01*
Y2646502D01*
X1466492Y2647156D01*
X1466117Y2647716D01*
X1465617Y2648182D01*
G01X1466742Y2658796D02*
X1459242D01*
Y2660662D01*
X1459617Y2661409D01*
X1460117Y2661969D01*
X1460867Y2662436D01*
X1461742Y2662809D01*
X1462992Y2662902D01*
X1464242Y2662809D01*
X1465117Y2662436D01*
X1465867Y2661969D01*
X1466367Y2661409D01*
X1466742Y2660662D01*
Y2658796D01*
G01Y2666482D02*
X1459242D01*
Y2668816D01*
X1459617Y2669562D01*
X1460117Y2670029D01*
X1461117Y2670216D01*
X1462117Y2670029D01*
X1462742Y2669469D01*
X1463117Y2668816D01*
Y2666482D01*
G01Y2668816D02*
X1466742Y2670216D01*
G01X1459242Y2674729D02*
Y2676969D01*
G01Y2675849D02*
X1466742D01*
G01Y2674729D02*
Y2676969D01*
G01X1459242Y2681482D02*
X1466742D01*
Y2685216D01*
G01X1459242Y2688982D02*
X1466742D01*
Y2692716D01*
G01X1469242Y2697882D02*
X1467992Y2696949D01*
X1466742Y2696482D01*
X1461742D01*
X1460492Y2696949D01*
X1459242Y2697882D01*
G01Y2705849D02*
X1459492Y2705102D01*
X1460117Y2704542D01*
X1460867Y2704169D01*
X1461867Y2703889D01*
X1462992Y2703796D01*
X1464117Y2703889D01*
X1465117Y2704169D01*
X1465867Y2704542D01*
X1466492Y2705102D01*
X1466742Y2705849D01*
X1466492Y2706596D01*
X1465867Y2707156D01*
X1465117Y2707529D01*
X1464117Y2707809D01*
X1462992Y2707902D01*
X1461867Y2707809D01*
X1460867Y2707529D01*
X1460117Y2707156D01*
X1459492Y2706596D01*
X1459242Y2705849D01*
G01X1466992Y2713349D02*
X1466867Y2713162D01*
X1466617D01*
X1466492Y2713349D01*
X1466617Y2713536D01*
X1466867D01*
X1466992Y2713349D01*
G01X1459242Y2720849D02*
X1459492Y2720102D01*
X1460117Y2719542D01*
X1460867Y2719169D01*
X1461867Y2718889D01*
X1462992Y2718796D01*
X1464117Y2718889D01*
X1465117Y2719169D01*
X1465867Y2719542D01*
X1466492Y2720102D01*
X1466742Y2720849D01*
X1466492Y2721596D01*
X1465867Y2722156D01*
X1465117Y2722529D01*
X1464117Y2722809D01*
X1462992Y2722902D01*
X1461867Y2722809D01*
X1460867Y2722529D01*
X1460117Y2722156D01*
X1459492Y2721596D01*
X1459242Y2720849D01*
G01X1460492Y2726576D02*
X1459742Y2727136D01*
X1459367Y2727789D01*
X1459242Y2728536D01*
X1459492Y2729469D01*
X1460117Y2730122D01*
X1460867Y2730309D01*
X1461617Y2730216D01*
X1462242Y2729842D01*
X1463492Y2727976D01*
X1464367Y2727136D01*
X1465617Y2726576D01*
X1466742Y2726389D01*
Y2730309D01*
G01X1465242Y2733796D02*
X1466117Y2734356D01*
X1466617Y2735102D01*
X1466742Y2735942D01*
X1466617Y2736689D01*
X1465992Y2737436D01*
X1465242Y2737902D01*
X1464492Y2737996D01*
X1463617Y2737809D01*
X1462992Y2737156D01*
X1462742Y2736502D01*
Y2735662D01*
G01Y2736502D02*
X1462367Y2737062D01*
X1461742Y2737529D01*
X1460992Y2737716D01*
X1460242Y2737529D01*
X1459617Y2737062D01*
X1459242Y2736222D01*
X1459367Y2735382D01*
X1459867Y2734542D01*
G01X1463617Y2741576D02*
X1462742Y2742229D01*
X1462242Y2742789D01*
X1461992Y2743536D01*
X1462242Y2744189D01*
X1462742Y2744656D01*
X1463492Y2745029D01*
X1464367Y2745122D01*
X1465117Y2745029D01*
X1465867Y2744656D01*
X1466492Y2744096D01*
X1466742Y2743442D01*
X1466492Y2742696D01*
X1465742Y2742042D01*
X1464617Y2741669D01*
X1463367Y2741576D01*
X1461742Y2741762D01*
X1460867Y2742042D01*
X1459992Y2742509D01*
X1459367Y2743162D01*
X1459242Y2743816D01*
X1459492Y2744469D01*
X1460117Y2744936D01*
G01X1460867Y2750009D02*
X1459242Y2750476D01*
G01Y2751689D02*
X1460867Y2751222D01*
G01X1469242Y2758816D02*
X1467992Y2759749D01*
X1466742Y2760216D01*
X1461742D01*
X1460492Y2759749D01*
X1459242Y2758816D01*
G01X1466992Y2765849D02*
X1466867Y2765662D01*
X1466617D01*
X1466492Y2765849D01*
X1466617Y2766036D01*
X1466867D01*
X1466992Y2765849D01*
G01X1485274Y-378077D02*
X1472774D01*
X1475274Y-379937D01*
G01X1485274D02*
Y-376217D01*
G01Y-363817D02*
X1472774D01*
X1481732Y-369552D01*
Y-361802D01*
G01X1483816Y-355912D02*
X1484857Y-354827D01*
X1485274Y-353587D01*
X1484857Y-352347D01*
X1483608Y-351262D01*
X1481732Y-350487D01*
X1479857Y-350177D01*
X1477566D01*
X1475691Y-350487D01*
X1474024Y-351262D01*
X1473191Y-352192D01*
X1472774Y-353277D01*
X1473191Y-354517D01*
X1474024Y-355447D01*
X1475274Y-356067D01*
X1476941Y-356377D01*
X1478399Y-356067D01*
X1479857Y-355292D01*
X1480691Y-354362D01*
X1480899Y-353277D01*
X1480483Y-352037D01*
X1479441Y-351107D01*
X1477566Y-350177D01*
G01X1483816Y-343512D02*
X1484857Y-342427D01*
X1485274Y-341187D01*
X1484857Y-339947D01*
X1483608Y-338862D01*
X1481732Y-338087D01*
X1479857Y-337777D01*
X1477566D01*
X1475691Y-338087D01*
X1474024Y-338862D01*
X1473191Y-339792D01*
X1472774Y-340877D01*
X1473191Y-342117D01*
X1474024Y-343047D01*
X1475274Y-343667D01*
X1476941Y-343977D01*
X1478399Y-343667D01*
X1479857Y-342892D01*
X1480691Y-341962D01*
X1480899Y-340877D01*
X1480483Y-339637D01*
X1479441Y-338707D01*
X1477566Y-337777D01*
G01X1480066Y-331422D02*
X1478607Y-330337D01*
X1477774Y-329407D01*
X1477357Y-328167D01*
X1477774Y-327082D01*
X1478607Y-326307D01*
X1479857Y-325687D01*
X1481316Y-325532D01*
X1482566Y-325687D01*
X1483816Y-326307D01*
X1484857Y-327237D01*
X1485274Y-328322D01*
X1484857Y-329562D01*
X1483608Y-330647D01*
X1481732Y-331267D01*
X1479649Y-331422D01*
X1476941Y-331112D01*
X1475482Y-330647D01*
X1474024Y-329872D01*
X1472982Y-328787D01*
X1472774Y-327702D01*
X1473191Y-326617D01*
X1474232Y-325842D01*
G01X1485691Y-316077D02*
X1485482Y-316387D01*
X1485066D01*
X1484857Y-316077D01*
X1485066Y-315767D01*
X1485482D01*
X1485691Y-316077D01*
G01X1472774Y-303677D02*
X1473191Y-304917D01*
X1474232Y-305847D01*
X1475482Y-306467D01*
X1477149Y-306932D01*
X1479024Y-307087D01*
X1480899Y-306932D01*
X1482566Y-306467D01*
X1483816Y-305847D01*
X1484857Y-304917D01*
X1485274Y-303677D01*
X1484857Y-302437D01*
X1483816Y-301507D01*
X1482566Y-300887D01*
X1480899Y-300422D01*
X1479024Y-300267D01*
X1477149Y-300422D01*
X1475482Y-300887D01*
X1474232Y-301507D01*
X1473191Y-302437D01*
X1472774Y-303677D01*
G01X1480066Y-294222D02*
X1478607Y-293137D01*
X1477774Y-292207D01*
X1477357Y-290967D01*
X1477774Y-289882D01*
X1478607Y-289107D01*
X1479857Y-288487D01*
X1481316Y-288332D01*
X1482566Y-288487D01*
X1483816Y-289107D01*
X1484857Y-290037D01*
X1485274Y-291122D01*
X1484857Y-292362D01*
X1483608Y-293447D01*
X1481732Y-294067D01*
X1479649Y-294222D01*
X1476941Y-293912D01*
X1475482Y-293447D01*
X1474024Y-292672D01*
X1472982Y-291587D01*
X1472774Y-290502D01*
X1473191Y-289417D01*
X1474232Y-288642D01*
G01X1482774Y-260087D02*
X1484233Y-259157D01*
X1485066Y-257917D01*
X1485274Y-256522D01*
X1485066Y-255282D01*
X1484024Y-254042D01*
X1482774Y-253267D01*
X1481524Y-253112D01*
X1480066Y-253422D01*
X1479024Y-254507D01*
X1478607Y-255592D01*
Y-256987D01*
G01Y-255592D02*
X1477982Y-254662D01*
X1476941Y-253887D01*
X1475691Y-253577D01*
X1474441Y-253887D01*
X1473399Y-254662D01*
X1472774Y-256057D01*
X1472982Y-257452D01*
X1473816Y-258847D01*
G01X1485274Y-244277D02*
X1485066Y-243192D01*
X1484441Y-241952D01*
X1483399Y-241177D01*
X1481941Y-240867D01*
X1480483Y-241177D01*
X1479232Y-242107D01*
X1478607Y-243502D01*
Y-245052D01*
X1478191Y-245982D01*
X1477149Y-246757D01*
X1475691Y-247067D01*
X1474232Y-246602D01*
X1473191Y-245517D01*
X1472774Y-244277D01*
X1473191Y-243037D01*
X1474232Y-241952D01*
X1475691Y-241487D01*
X1477149Y-241797D01*
X1478191Y-242572D01*
X1478607Y-243502D01*
Y-245052D01*
X1479232Y-246447D01*
X1480483Y-247377D01*
X1481941Y-247687D01*
X1483399Y-247377D01*
X1484441Y-246602D01*
X1485066Y-245362D01*
X1485274Y-244277D01*
G01X1472774Y-231877D02*
X1473191Y-233117D01*
X1474232Y-234047D01*
X1475482Y-234667D01*
X1477149Y-235132D01*
X1479024Y-235287D01*
X1480899Y-235132D01*
X1482566Y-234667D01*
X1483816Y-234047D01*
X1484857Y-233117D01*
X1485274Y-231877D01*
X1484857Y-230637D01*
X1483816Y-229707D01*
X1482566Y-229087D01*
X1480899Y-228622D01*
X1479024Y-228467D01*
X1477149Y-228622D01*
X1475482Y-229087D01*
X1474232Y-229707D01*
X1473191Y-230637D01*
X1472774Y-231877D01*
G01X1485691Y-219477D02*
X1485482Y-219787D01*
X1485066D01*
X1484857Y-219477D01*
X1485066Y-219167D01*
X1485482D01*
X1485691Y-219477D01*
G01X1483816Y-209712D02*
X1484857Y-208627D01*
X1485274Y-207387D01*
X1484857Y-206147D01*
X1483608Y-205062D01*
X1481732Y-204287D01*
X1479857Y-203977D01*
X1477566D01*
X1475691Y-204287D01*
X1474024Y-205062D01*
X1473191Y-205992D01*
X1472774Y-207077D01*
X1473191Y-208317D01*
X1474024Y-209247D01*
X1475274Y-209867D01*
X1476941Y-210177D01*
X1478399Y-209867D01*
X1479857Y-209092D01*
X1480691Y-208162D01*
X1480899Y-207077D01*
X1480483Y-205837D01*
X1479441Y-204907D01*
X1477566Y-203977D01*
G01X1503805Y-390297D02*
X1491305D01*
X1493805Y-392157D01*
G01X1503805D02*
Y-388437D01*
G01X1501930Y-381307D02*
X1502972Y-380377D01*
X1503597Y-379292D01*
X1503805Y-377897D01*
X1503388Y-376502D01*
X1502555Y-375417D01*
X1501097Y-374642D01*
X1499430Y-374487D01*
X1497763Y-374797D01*
X1496722Y-375572D01*
X1495888Y-376657D01*
X1495680Y-377742D01*
X1495888Y-378827D01*
X1496722Y-380222D01*
X1491305Y-379757D01*
Y-375572D01*
G01Y-365497D02*
X1491722Y-366737D01*
X1492763Y-367667D01*
X1494013Y-368287D01*
X1495680Y-368752D01*
X1497555Y-368907D01*
X1499430Y-368752D01*
X1501097Y-368287D01*
X1502347Y-367667D01*
X1503388Y-366737D01*
X1503805Y-365497D01*
X1503388Y-364257D01*
X1502347Y-363327D01*
X1501097Y-362707D01*
X1499430Y-362242D01*
X1497555Y-362087D01*
X1495680Y-362242D01*
X1494013Y-362707D01*
X1492763Y-363327D01*
X1491722Y-364257D01*
X1491305Y-365497D01*
G01X1503805Y-353097D02*
X1491305D01*
X1493805Y-354957D01*
G01X1503805D02*
Y-351237D01*
G01Y-338837D02*
X1491305D01*
X1500263Y-344572D01*
Y-336822D01*
G01X1504222Y-328297D02*
X1504013Y-328607D01*
X1503597D01*
X1503388Y-328297D01*
X1503597Y-327987D01*
X1504013D01*
X1504222Y-328297D01*
G01X1503805Y-315897D02*
X1491305D01*
X1493805Y-317757D01*
G01X1503805D02*
Y-314037D01*
G01Y-303497D02*
X1503597Y-302412D01*
X1502972Y-301172D01*
X1501930Y-300397D01*
X1500472Y-300087D01*
X1499014Y-300397D01*
X1497763Y-301327D01*
X1497138Y-302722D01*
Y-304272D01*
X1496722Y-305202D01*
X1495680Y-305977D01*
X1494222Y-306287D01*
X1492763Y-305822D01*
X1491722Y-304737D01*
X1491305Y-303497D01*
X1491722Y-302257D01*
X1492763Y-301172D01*
X1494222Y-300707D01*
X1495680Y-301017D01*
X1496722Y-301792D01*
X1497138Y-302722D01*
Y-304272D01*
X1497763Y-305667D01*
X1499014Y-306597D01*
X1500472Y-306907D01*
X1501930Y-306597D01*
X1502972Y-305822D01*
X1503597Y-304582D01*
X1503805Y-303497D01*
G01X1501305Y-272307D02*
X1502764Y-271377D01*
X1503597Y-270137D01*
X1503805Y-268742D01*
X1503597Y-267502D01*
X1502555Y-266262D01*
X1501305Y-265487D01*
X1500055Y-265332D01*
X1498597Y-265642D01*
X1497555Y-266727D01*
X1497138Y-267812D01*
Y-269207D01*
G01Y-267812D02*
X1496513Y-266882D01*
X1495472Y-266107D01*
X1494222Y-265797D01*
X1492972Y-266107D01*
X1491930Y-266882D01*
X1491305Y-268277D01*
X1491513Y-269672D01*
X1492347Y-271067D01*
G01X1503805Y-256497D02*
X1503597Y-255412D01*
X1502972Y-254172D01*
X1501930Y-253397D01*
X1500472Y-253087D01*
X1499014Y-253397D01*
X1497763Y-254327D01*
X1497138Y-255722D01*
Y-257272D01*
X1496722Y-258202D01*
X1495680Y-258977D01*
X1494222Y-259287D01*
X1492763Y-258822D01*
X1491722Y-257737D01*
X1491305Y-256497D01*
X1491722Y-255257D01*
X1492763Y-254172D01*
X1494222Y-253707D01*
X1495680Y-254017D01*
X1496722Y-254792D01*
X1497138Y-255722D01*
Y-257272D01*
X1497763Y-258667D01*
X1499014Y-259597D01*
X1500472Y-259907D01*
X1501930Y-259597D01*
X1502972Y-258822D01*
X1503597Y-257582D01*
X1503805Y-256497D01*
G01Y-244097D02*
X1491305D01*
X1493805Y-245957D01*
G01X1503805D02*
Y-242237D01*
G01X1504222Y-231697D02*
X1504013Y-232007D01*
X1503597D01*
X1503388Y-231697D01*
X1503597Y-231387D01*
X1504013D01*
X1504222Y-231697D01*
G01X1501305Y-222707D02*
X1502764Y-221777D01*
X1503597Y-220537D01*
X1503805Y-219142D01*
X1503597Y-217902D01*
X1502555Y-216662D01*
X1501305Y-215887D01*
X1500055Y-215732D01*
X1498597Y-216042D01*
X1497555Y-217127D01*
X1497138Y-218212D01*
Y-219607D01*
G01Y-218212D02*
X1496513Y-217282D01*
X1495472Y-216507D01*
X1494222Y-216197D01*
X1492972Y-216507D01*
X1491930Y-217282D01*
X1491305Y-218677D01*
X1491513Y-220072D01*
X1492347Y-221467D01*
G01X1498597Y-209842D02*
X1497138Y-208757D01*
X1496305Y-207827D01*
X1495888Y-206587D01*
X1496305Y-205502D01*
X1497138Y-204727D01*
X1498388Y-204107D01*
X1499847Y-203952D01*
X1501097Y-204107D01*
X1502347Y-204727D01*
X1503388Y-205657D01*
X1503805Y-206742D01*
X1503388Y-207982D01*
X1502139Y-209067D01*
X1500263Y-209687D01*
X1498180Y-209842D01*
X1495472Y-209532D01*
X1494013Y-209067D01*
X1492555Y-208292D01*
X1491513Y-207207D01*
X1491305Y-206122D01*
X1491722Y-205037D01*
X1492763Y-204262D01*
G01X1519809Y-390296D02*
X1507309D01*
X1509809Y-392156D01*
G01X1519809D02*
Y-388436D01*
G01X1517934Y-381306D02*
X1518976Y-380376D01*
X1519601Y-379291D01*
X1519809Y-377896D01*
X1519392Y-376501D01*
X1518559Y-375416D01*
X1517101Y-374641D01*
X1515434Y-374486D01*
X1513767Y-374796D01*
X1512726Y-375571D01*
X1511892Y-376656D01*
X1511684Y-377741D01*
X1511892Y-378826D01*
X1512726Y-380221D01*
X1507309Y-379756D01*
Y-375571D01*
G01Y-365496D02*
X1507726Y-366736D01*
X1508767Y-367666D01*
X1510017Y-368286D01*
X1511684Y-368751D01*
X1513559Y-368906D01*
X1515434Y-368751D01*
X1517101Y-368286D01*
X1518351Y-367666D01*
X1519392Y-366736D01*
X1519809Y-365496D01*
X1519392Y-364256D01*
X1518351Y-363326D01*
X1517101Y-362706D01*
X1515434Y-362241D01*
X1513559Y-362086D01*
X1511684Y-362241D01*
X1510017Y-362706D01*
X1508767Y-363326D01*
X1507726Y-364256D01*
X1507309Y-365496D01*
G01X1519809Y-353406D02*
X1517101Y-353096D01*
X1514809Y-352631D01*
X1512726Y-352011D01*
X1510434Y-351236D01*
X1507309Y-349996D01*
Y-356196D01*
G01X1517309Y-344106D02*
X1518768Y-343176D01*
X1519601Y-341936D01*
X1519809Y-340541D01*
X1519601Y-339301D01*
X1518559Y-338061D01*
X1517309Y-337286D01*
X1516059Y-337131D01*
X1514601Y-337441D01*
X1513559Y-338526D01*
X1513142Y-339611D01*
Y-341006D01*
G01Y-339611D02*
X1512517Y-338681D01*
X1511476Y-337906D01*
X1510226Y-337596D01*
X1508976Y-337906D01*
X1507934Y-338681D01*
X1507309Y-340076D01*
X1507517Y-341471D01*
X1508351Y-342866D01*
G01X1520226Y-328296D02*
X1520017Y-328606D01*
X1519601D01*
X1519392Y-328296D01*
X1519601Y-327986D01*
X1520017D01*
X1520226Y-328296D01*
G01X1519809Y-315896D02*
X1519601Y-314811D01*
X1518976Y-313571D01*
X1517934Y-312796D01*
X1516476Y-312486D01*
X1515018Y-312796D01*
X1513767Y-313726D01*
X1513142Y-315121D01*
Y-316671D01*
X1512726Y-317601D01*
X1511684Y-318376D01*
X1510226Y-318686D01*
X1508767Y-318221D01*
X1507726Y-317136D01*
X1507309Y-315896D01*
X1507726Y-314656D01*
X1508767Y-313571D01*
X1510226Y-313106D01*
X1511684Y-313416D01*
X1512726Y-314191D01*
X1513142Y-315121D01*
Y-316671D01*
X1513767Y-318066D01*
X1515018Y-318996D01*
X1516476Y-319306D01*
X1517934Y-318996D01*
X1518976Y-318221D01*
X1519601Y-316981D01*
X1519809Y-315896D01*
G01X1509392Y-306441D02*
X1508143Y-305511D01*
X1507517Y-304426D01*
X1507309Y-303186D01*
X1507726Y-301636D01*
X1508767Y-300551D01*
X1510017Y-300241D01*
X1511268Y-300396D01*
X1512309Y-301016D01*
X1514392Y-304116D01*
X1515851Y-305511D01*
X1517934Y-306441D01*
X1519809Y-306751D01*
Y-300241D01*
G01X1517309Y-272306D02*
X1518768Y-271376D01*
X1519601Y-270136D01*
X1519809Y-268741D01*
X1519601Y-267501D01*
X1518559Y-266261D01*
X1517309Y-265486D01*
X1516059Y-265331D01*
X1514601Y-265641D01*
X1513559Y-266726D01*
X1513142Y-267811D01*
Y-269206D01*
G01Y-267811D02*
X1512517Y-266881D01*
X1511476Y-266106D01*
X1510226Y-265796D01*
X1508976Y-266106D01*
X1507934Y-266881D01*
X1507309Y-268276D01*
X1507517Y-269671D01*
X1508351Y-271066D01*
G01X1519809Y-256496D02*
X1519601Y-255411D01*
X1518976Y-254171D01*
X1517934Y-253396D01*
X1516476Y-253086D01*
X1515018Y-253396D01*
X1513767Y-254326D01*
X1513142Y-255721D01*
Y-257271D01*
X1512726Y-258201D01*
X1511684Y-258976D01*
X1510226Y-259286D01*
X1508767Y-258821D01*
X1507726Y-257736D01*
X1507309Y-256496D01*
X1507726Y-255256D01*
X1508767Y-254171D01*
X1510226Y-253706D01*
X1511684Y-254016D01*
X1512726Y-254791D01*
X1513142Y-255721D01*
Y-257271D01*
X1513767Y-258666D01*
X1515018Y-259596D01*
X1516476Y-259906D01*
X1517934Y-259596D01*
X1518976Y-258821D01*
X1519601Y-257581D01*
X1519809Y-256496D01*
G01X1509392Y-247041D02*
X1508143Y-246111D01*
X1507517Y-245026D01*
X1507309Y-243786D01*
X1507726Y-242236D01*
X1508767Y-241151D01*
X1510017Y-240841D01*
X1511268Y-240996D01*
X1512309Y-241616D01*
X1514392Y-244716D01*
X1515851Y-246111D01*
X1517934Y-247041D01*
X1519809Y-247351D01*
Y-240841D01*
G01X1520226Y-231696D02*
X1520017Y-232006D01*
X1519601D01*
X1519392Y-231696D01*
X1519601Y-231386D01*
X1520017D01*
X1520226Y-231696D01*
G01X1519809Y-219296D02*
X1519601Y-218211D01*
X1518976Y-216971D01*
X1517934Y-216196D01*
X1516476Y-215886D01*
X1515018Y-216196D01*
X1513767Y-217126D01*
X1513142Y-218521D01*
Y-220071D01*
X1512726Y-221001D01*
X1511684Y-221776D01*
X1510226Y-222086D01*
X1508767Y-221621D01*
X1507726Y-220536D01*
X1507309Y-219296D01*
X1507726Y-218056D01*
X1508767Y-216971D01*
X1510226Y-216506D01*
X1511684Y-216816D01*
X1512726Y-217591D01*
X1513142Y-218521D01*
Y-220071D01*
X1513767Y-221466D01*
X1515018Y-222396D01*
X1516476Y-222706D01*
X1517934Y-222396D01*
X1518976Y-221621D01*
X1519601Y-220381D01*
X1519809Y-219296D01*
G01Y-206896D02*
X1519601Y-205811D01*
X1518976Y-204571D01*
X1517934Y-203796D01*
X1516476Y-203486D01*
X1515018Y-203796D01*
X1513767Y-204726D01*
X1513142Y-206121D01*
Y-207671D01*
X1512726Y-208601D01*
X1511684Y-209376D01*
X1510226Y-209686D01*
X1508767Y-209221D01*
X1507726Y-208136D01*
X1507309Y-206896D01*
X1507726Y-205656D01*
X1508767Y-204571D01*
X1510226Y-204106D01*
X1511684Y-204416D01*
X1512726Y-205191D01*
X1513142Y-206121D01*
Y-207671D01*
X1513767Y-209066D01*
X1515018Y-209996D01*
X1516476Y-210306D01*
X1517934Y-209996D01*
X1518976Y-209221D01*
X1519601Y-207981D01*
X1519809Y-206896D01*
G01X1502251Y1188155D02*
Y1195655D01*
X1506545Y1188155D01*
Y1195655D01*
G01X1510031Y1188155D02*
Y1195655D01*
X1512271D01*
X1513018Y1195280D01*
X1513578Y1194405D01*
X1513765Y1193405D01*
X1513578Y1192405D01*
X1513111Y1191655D01*
X1512271Y1191280D01*
X1510031D01*
G01X1519398Y1195655D02*
Y1188155D01*
G01X1517251Y1195655D02*
X1521545D01*
G01X1524938Y1188155D02*
Y1195655D01*
G01X1528858D02*
Y1188155D01*
G01Y1191905D02*
X1524938D01*
G01X1513327Y1676732D02*
G03I-2500J0D01*
G01X1505453Y1672795D02*
G03I-2500J0D01*
G01X1513327Y1690905D02*
G03I-2500J0D01*
G01X1505453Y1686968D02*
G03I-2500J0D01*
G01X1513327Y1705078D02*
G03I-2500J0D01*
G01X1505453Y1701141D02*
G03I-2500J0D01*
G01Y1715314D02*
G03I-2500J0D01*
G01X1513327Y1719251D02*
G03I-2500J0D01*
G01X1505453Y1729488D02*
G03I-2500J0D01*
G01X1513327Y1733425D02*
G03I-2500J0D01*
G01X1535928Y-390525D02*
X1523428D01*
X1525928Y-392385D01*
G01X1535928D02*
Y-388665D01*
G01X1534053Y-381535D02*
X1535095Y-380605D01*
X1535720Y-379520D01*
X1535928Y-378125D01*
X1535511Y-376730D01*
X1534678Y-375645D01*
X1533220Y-374870D01*
X1531553Y-374715D01*
X1529886Y-375025D01*
X1528845Y-375800D01*
X1528011Y-376885D01*
X1527803Y-377970D01*
X1528011Y-379055D01*
X1528845Y-380450D01*
X1523428Y-379985D01*
Y-375800D01*
G01X1535928Y-365725D02*
X1523428D01*
X1525928Y-367585D01*
G01X1535928D02*
Y-363865D01*
G01X1533428Y-356735D02*
X1534887Y-355805D01*
X1535720Y-354565D01*
X1535928Y-353170D01*
X1535720Y-351930D01*
X1534678Y-350690D01*
X1533428Y-349915D01*
X1532178Y-349760D01*
X1530720Y-350070D01*
X1529678Y-351155D01*
X1529261Y-352240D01*
Y-353635D01*
G01Y-352240D02*
X1528636Y-351310D01*
X1527595Y-350535D01*
X1526345Y-350225D01*
X1525095Y-350535D01*
X1524053Y-351310D01*
X1523428Y-352705D01*
X1523636Y-354100D01*
X1524470Y-355495D01*
G01X1530720Y-343870D02*
X1529261Y-342785D01*
X1528428Y-341855D01*
X1528011Y-340615D01*
X1528428Y-339530D01*
X1529261Y-338755D01*
X1530511Y-338135D01*
X1531970Y-337980D01*
X1533220Y-338135D01*
X1534470Y-338755D01*
X1535511Y-339685D01*
X1535928Y-340770D01*
X1535511Y-342010D01*
X1534262Y-343095D01*
X1532386Y-343715D01*
X1530303Y-343870D01*
X1527595Y-343560D01*
X1526136Y-343095D01*
X1524678Y-342320D01*
X1523636Y-341235D01*
X1523428Y-340150D01*
X1523845Y-339065D01*
X1524886Y-338290D01*
G01X1536345Y-328525D02*
X1536136Y-328835D01*
X1535720D01*
X1535511Y-328525D01*
X1535720Y-328215D01*
X1536136D01*
X1536345Y-328525D01*
G01X1535928Y-316125D02*
X1523428D01*
X1525928Y-317985D01*
G01X1535928D02*
Y-314265D01*
G01Y-303725D02*
X1535720Y-302640D01*
X1535095Y-301400D01*
X1534053Y-300625D01*
X1532595Y-300315D01*
X1531137Y-300625D01*
X1529886Y-301555D01*
X1529261Y-302950D01*
Y-304500D01*
X1528845Y-305430D01*
X1527803Y-306205D01*
X1526345Y-306515D01*
X1524886Y-306050D01*
X1523845Y-304965D01*
X1523428Y-303725D01*
X1523845Y-302485D01*
X1524886Y-301400D01*
X1526345Y-300935D01*
X1527803Y-301245D01*
X1528845Y-302020D01*
X1529261Y-302950D01*
Y-304500D01*
X1529886Y-305895D01*
X1531137Y-306825D01*
X1532595Y-307135D01*
X1534053Y-306825D01*
X1535095Y-306050D01*
X1535720Y-304810D01*
X1535928Y-303725D01*
G01X1533428Y-272535D02*
X1534887Y-271605D01*
X1535720Y-270365D01*
X1535928Y-268970D01*
X1535720Y-267730D01*
X1534678Y-266490D01*
X1533428Y-265715D01*
X1532178Y-265560D01*
X1530720Y-265870D01*
X1529678Y-266955D01*
X1529261Y-268040D01*
Y-269435D01*
G01Y-268040D02*
X1528636Y-267110D01*
X1527595Y-266335D01*
X1526345Y-266025D01*
X1525095Y-266335D01*
X1524053Y-267110D01*
X1523428Y-268505D01*
X1523636Y-269900D01*
X1524470Y-271295D01*
G01X1535928Y-256725D02*
X1535720Y-255640D01*
X1535095Y-254400D01*
X1534053Y-253625D01*
X1532595Y-253315D01*
X1531137Y-253625D01*
X1529886Y-254555D01*
X1529261Y-255950D01*
Y-257500D01*
X1528845Y-258430D01*
X1527803Y-259205D01*
X1526345Y-259515D01*
X1524886Y-259050D01*
X1523845Y-257965D01*
X1523428Y-256725D01*
X1523845Y-255485D01*
X1524886Y-254400D01*
X1526345Y-253935D01*
X1527803Y-254245D01*
X1528845Y-255020D01*
X1529261Y-255950D01*
Y-257500D01*
X1529886Y-258895D01*
X1531137Y-259825D01*
X1532595Y-260135D01*
X1534053Y-259825D01*
X1535095Y-259050D01*
X1535720Y-257810D01*
X1535928Y-256725D01*
G01Y-242465D02*
X1523428D01*
X1532386Y-248200D01*
Y-240450D01*
G01X1536345Y-231925D02*
X1536136Y-232235D01*
X1535720D01*
X1535511Y-231925D01*
X1535720Y-231615D01*
X1536136D01*
X1536345Y-231925D01*
G01X1535928Y-217665D02*
X1523428D01*
X1532386Y-223400D01*
Y-215650D01*
G01X1530720Y-210070D02*
X1529261Y-208985D01*
X1528428Y-208055D01*
X1528011Y-206815D01*
X1528428Y-205730D01*
X1529261Y-204955D01*
X1530511Y-204335D01*
X1531970Y-204180D01*
X1533220Y-204335D01*
X1534470Y-204955D01*
X1535511Y-205885D01*
X1535928Y-206970D01*
X1535511Y-208210D01*
X1534262Y-209295D01*
X1532386Y-209915D01*
X1530303Y-210070D01*
X1527595Y-209760D01*
X1526136Y-209295D01*
X1524678Y-208520D01*
X1523636Y-207435D01*
X1523428Y-206350D01*
X1523845Y-205265D01*
X1524886Y-204490D01*
G01X1510658Y824956D02*
Y832456D01*
X1514952Y824956D01*
Y832456D01*
G01X1518438Y824956D02*
Y832456D01*
X1520678D01*
X1521425Y832081D01*
X1521985Y831206D01*
X1522172Y830206D01*
X1521985Y829206D01*
X1521518Y828456D01*
X1520678Y828081D01*
X1518438D01*
G01X1527805Y832456D02*
Y824956D01*
G01X1525658Y832456D02*
X1529952D01*
G01X1533345Y824956D02*
Y832456D01*
G01X1537265D02*
Y824956D01*
G01Y828706D02*
X1533345D01*
G01X1529075Y1676732D02*
G03I-2500J0D01*
G01X1521201Y1672795D02*
G03I-2500J0D01*
G01X1529075Y1690905D02*
G03I-2500J0D01*
G01X1521201Y1686968D02*
G03I-2500J0D01*
G01X1529075Y1705078D02*
G03I-2500J0D01*
G01X1521201Y1701141D02*
G03I-2500J0D01*
G01Y1715314D02*
G03I-2500J0D01*
G01X1529075Y1719251D02*
G03I-2500J0D01*
G01X1521201Y1729488D02*
G03I-2500J0D01*
G01X1529075Y1733425D02*
G03I-2500J0D01*
G01X1544823Y1676732D02*
G03I-2500J0D01*
G01X1536949Y1672795D02*
G03I-2500J0D01*
G01X1544823Y1690905D02*
G03I-2500J0D01*
G01X1536949Y1686968D02*
G03I-2500J0D01*
G01X1544823Y1705078D02*
G03I-2500J0D01*
G01X1536949Y1701141D02*
G03I-2500J0D01*
G01Y1715314D02*
G03I-2500J0D01*
G01X1544823Y1719251D02*
G03I-2500J0D01*
G01X1536949Y1729488D02*
G03I-2500J0D01*
G01X1544823Y1733425D02*
G03I-2500J0D01*
G01X1556959Y-390296D02*
X1544459D01*
X1546959Y-392156D01*
G01X1556959D02*
Y-388436D01*
G01X1555084Y-381306D02*
X1556126Y-380376D01*
X1556751Y-379291D01*
X1556959Y-377896D01*
X1556542Y-376501D01*
X1555709Y-375416D01*
X1554251Y-374641D01*
X1552584Y-374486D01*
X1550917Y-374796D01*
X1549876Y-375571D01*
X1549042Y-376656D01*
X1548834Y-377741D01*
X1549042Y-378826D01*
X1549876Y-380221D01*
X1544459Y-379756D01*
Y-375571D01*
G01X1555084Y-368906D02*
X1556126Y-367976D01*
X1556751Y-366891D01*
X1556959Y-365496D01*
X1556542Y-364101D01*
X1555709Y-363016D01*
X1554251Y-362241D01*
X1552584Y-362086D01*
X1550917Y-362396D01*
X1549876Y-363171D01*
X1549042Y-364256D01*
X1548834Y-365341D01*
X1549042Y-366426D01*
X1549876Y-367821D01*
X1544459Y-367356D01*
Y-363171D01*
G01Y-353096D02*
X1544876Y-354336D01*
X1545917Y-355266D01*
X1547167Y-355886D01*
X1548834Y-356351D01*
X1550709Y-356506D01*
X1552584Y-356351D01*
X1554251Y-355886D01*
X1555501Y-355266D01*
X1556542Y-354336D01*
X1556959Y-353096D01*
X1556542Y-351856D01*
X1555501Y-350926D01*
X1554251Y-350306D01*
X1552584Y-349841D01*
X1550709Y-349686D01*
X1548834Y-349841D01*
X1547167Y-350306D01*
X1545917Y-350926D01*
X1544876Y-351856D01*
X1544459Y-353096D01*
G01X1556959Y-341006D02*
X1554251Y-340696D01*
X1551959Y-340231D01*
X1549876Y-339611D01*
X1547584Y-338836D01*
X1544459Y-337596D01*
Y-343796D01*
G01X1557376Y-328296D02*
X1557167Y-328606D01*
X1556751D01*
X1556542Y-328296D01*
X1556751Y-327986D01*
X1557167D01*
X1557376Y-328296D01*
G01X1544459Y-315896D02*
X1544876Y-317136D01*
X1545917Y-318066D01*
X1547167Y-318686D01*
X1548834Y-319151D01*
X1550709Y-319306D01*
X1552584Y-319151D01*
X1554251Y-318686D01*
X1555501Y-318066D01*
X1556542Y-317136D01*
X1556959Y-315896D01*
X1556542Y-314656D01*
X1555501Y-313726D01*
X1554251Y-313106D01*
X1552584Y-312641D01*
X1550709Y-312486D01*
X1548834Y-312641D01*
X1547167Y-313106D01*
X1545917Y-313726D01*
X1544876Y-314656D01*
X1544459Y-315896D01*
G01X1555501Y-306131D02*
X1556542Y-305046D01*
X1556959Y-303806D01*
X1556542Y-302566D01*
X1555293Y-301481D01*
X1553417Y-300706D01*
X1551542Y-300396D01*
X1549251D01*
X1547376Y-300706D01*
X1545709Y-301481D01*
X1544876Y-302411D01*
X1544459Y-303496D01*
X1544876Y-304736D01*
X1545709Y-305666D01*
X1546959Y-306286D01*
X1548626Y-306596D01*
X1550084Y-306286D01*
X1551542Y-305511D01*
X1552376Y-304581D01*
X1552584Y-303496D01*
X1552168Y-302256D01*
X1551126Y-301326D01*
X1549251Y-300396D01*
G01X1554459Y-272306D02*
X1555918Y-271376D01*
X1556751Y-270136D01*
X1556959Y-268741D01*
X1556751Y-267501D01*
X1555709Y-266261D01*
X1554459Y-265486D01*
X1553209Y-265331D01*
X1551751Y-265641D01*
X1550709Y-266726D01*
X1550292Y-267811D01*
Y-269206D01*
G01Y-267811D02*
X1549667Y-266881D01*
X1548626Y-266106D01*
X1547376Y-265796D01*
X1546126Y-266106D01*
X1545084Y-266881D01*
X1544459Y-268276D01*
X1544667Y-269671D01*
X1545501Y-271066D01*
G01X1555501Y-259131D02*
X1556542Y-258046D01*
X1556959Y-256806D01*
X1556542Y-255566D01*
X1555293Y-254481D01*
X1553417Y-253706D01*
X1551542Y-253396D01*
X1549251D01*
X1547376Y-253706D01*
X1545709Y-254481D01*
X1544876Y-255411D01*
X1544459Y-256496D01*
X1544876Y-257736D01*
X1545709Y-258666D01*
X1546959Y-259286D01*
X1548626Y-259596D01*
X1550084Y-259286D01*
X1551542Y-258511D01*
X1552376Y-257581D01*
X1552584Y-256496D01*
X1552168Y-255256D01*
X1551126Y-254326D01*
X1549251Y-253396D01*
G01X1554459Y-247506D02*
X1555918Y-246576D01*
X1556751Y-245336D01*
X1556959Y-243941D01*
X1556751Y-242701D01*
X1555709Y-241461D01*
X1554459Y-240686D01*
X1553209Y-240531D01*
X1551751Y-240841D01*
X1550709Y-241926D01*
X1550292Y-243011D01*
Y-244406D01*
G01Y-243011D02*
X1549667Y-242081D01*
X1548626Y-241306D01*
X1547376Y-240996D01*
X1546126Y-241306D01*
X1545084Y-242081D01*
X1544459Y-243476D01*
X1544667Y-244871D01*
X1545501Y-246266D01*
G01X1557376Y-231696D02*
X1557167Y-232006D01*
X1556751D01*
X1556542Y-231696D01*
X1556751Y-231386D01*
X1557167D01*
X1557376Y-231696D01*
G01X1556959Y-219296D02*
X1556751Y-218211D01*
X1556126Y-216971D01*
X1555084Y-216196D01*
X1553626Y-215886D01*
X1552168Y-216196D01*
X1550917Y-217126D01*
X1550292Y-218521D01*
Y-220071D01*
X1549876Y-221001D01*
X1548834Y-221776D01*
X1547376Y-222086D01*
X1545917Y-221621D01*
X1544876Y-220536D01*
X1544459Y-219296D01*
X1544876Y-218056D01*
X1545917Y-216971D01*
X1547376Y-216506D01*
X1548834Y-216816D01*
X1549876Y-217591D01*
X1550292Y-218521D01*
Y-220071D01*
X1550917Y-221466D01*
X1552168Y-222396D01*
X1553626Y-222706D01*
X1555084Y-222396D01*
X1556126Y-221621D01*
X1556751Y-220381D01*
X1556959Y-219296D01*
G01Y-206896D02*
X1556751Y-205811D01*
X1556126Y-204571D01*
X1555084Y-203796D01*
X1553626Y-203486D01*
X1552168Y-203796D01*
X1550917Y-204726D01*
X1550292Y-206121D01*
Y-207671D01*
X1549876Y-208601D01*
X1548834Y-209376D01*
X1547376Y-209686D01*
X1545917Y-209221D01*
X1544876Y-208136D01*
X1544459Y-206896D01*
X1544876Y-205656D01*
X1545917Y-204571D01*
X1547376Y-204106D01*
X1548834Y-204416D01*
X1549876Y-205191D01*
X1550292Y-206121D01*
Y-207671D01*
X1550917Y-209066D01*
X1552168Y-209996D01*
X1553626Y-210306D01*
X1555084Y-209996D01*
X1556126Y-209221D01*
X1556751Y-207981D01*
X1556959Y-206896D01*
G01X1554533Y1006558D02*
Y1014058D01*
X1558827Y1006558D01*
Y1014058D01*
G01X1562313Y1006558D02*
Y1014058D01*
X1564553D01*
X1565300Y1013683D01*
X1565860Y1012808D01*
X1566047Y1011808D01*
X1565860Y1010808D01*
X1565393Y1010058D01*
X1564553Y1009683D01*
X1562313D01*
G01X1571680Y1014058D02*
Y1006558D01*
G01X1569533Y1014058D02*
X1573827D01*
G01X1577220Y1006558D02*
Y1014058D01*
G01X1581140D02*
Y1006558D01*
G01Y1010308D02*
X1577220D01*
G01X1560571Y1676732D02*
G03I-2500J0D01*
G01X1552697Y1672795D02*
G03I-2500J0D01*
G01X1560571Y1690905D02*
G03I-2500J0D01*
G01X1552697Y1686968D02*
G03I-2500J0D01*
G01X1560571Y1705078D02*
G03I-2500J0D01*
G01X1552697Y1701141D02*
G03I-2500J0D01*
G01Y1715314D02*
G03I-2500J0D01*
G01X1560571Y1719251D02*
G03I-2500J0D01*
G01X1552697Y1729488D02*
G03I-2500J0D01*
G01X1560571Y1733425D02*
G03I-2500J0D01*
G01X1572382Y1672795D02*
G03I-2500J0D01*
G01Y1686968D02*
G03I-2500J0D01*
G01Y1701141D02*
G03I-2500J0D01*
G01Y1715314D02*
G03I-2500J0D01*
G01Y1729488D02*
G03I-2500J0D01*
G01X1588130Y1672795D02*
G03I-2500J0D01*
G01X1580256Y1676732D02*
G03I-2500J0D01*
G01X1588130Y1686968D02*
G03I-2500J0D01*
G01X1580256Y1690905D02*
G03I-2500J0D01*
G01X1588130Y1701141D02*
G03I-2500J0D01*
G01Y1715314D02*
G03I-2500J0D01*
G01X1580256Y1705078D02*
G03I-2500J0D01*
G01X1588130Y1729488D02*
G03I-2500J0D01*
G01X1580256Y1719251D02*
G03I-2500J0D01*
G01Y1733425D02*
G03I-2500J0D01*
G01X1611752Y1676732D02*
G03I-2500J0D01*
G01X1596004D02*
G03I-2500J0D01*
G01X1603878Y1672795D02*
G03I-2500J0D01*
G01X1611752Y1690905D02*
G03I-2500J0D01*
G01X1596004D02*
G03I-2500J0D01*
G01X1603878Y1686968D02*
G03I-2500J0D01*
G01X1611752Y1705078D02*
G03I-2500J0D01*
G01X1596004D02*
G03I-2500J0D01*
G01X1603878Y1701141D02*
G03I-2500J0D01*
G01Y1715314D02*
G03I-2500J0D01*
G01X1611752Y1719251D02*
G03I-2500J0D01*
G01X1596004D02*
G03I-2500J0D01*
G01X1603878Y1729488D02*
G03I-2500J0D01*
G01X1611752Y1733425D02*
G03I-2500J0D01*
G01X1596004D02*
G03I-2500J0D01*
G01X1627500Y1676732D02*
G03I-2500J0D01*
G01X1619626Y1672795D02*
G03I-2500J0D01*
G01X1627500Y1690905D02*
G03I-2500J0D01*
G01X1619626Y1686968D02*
G03I-2500J0D01*
G01X1627500Y1705078D02*
G03I-2500J0D01*
G01X1619626Y1701141D02*
G03I-2500J0D01*
G01Y1715314D02*
G03I-2500J0D01*
G01X1627500Y1719251D02*
G03I-2500J0D01*
G01X1619626Y1729488D02*
G03I-2500J0D01*
G01X1627500Y1733425D02*
G03I-2500J0D01*
G01X1705595Y-377924D02*
X1693095D01*
X1695595Y-379784D01*
G01X1705595D02*
Y-376064D01*
G01X1700387Y-368469D02*
X1698928Y-367384D01*
X1698095Y-366454D01*
X1697678Y-365214D01*
X1698095Y-364129D01*
X1698928Y-363354D01*
X1700178Y-362734D01*
X1701637Y-362579D01*
X1702887Y-362734D01*
X1704137Y-363354D01*
X1705178Y-364284D01*
X1705595Y-365369D01*
X1705178Y-366609D01*
X1703929Y-367694D01*
X1702053Y-368314D01*
X1699970Y-368469D01*
X1697262Y-368159D01*
X1695803Y-367694D01*
X1694345Y-366919D01*
X1693303Y-365834D01*
X1693095Y-364749D01*
X1693512Y-363664D01*
X1694553Y-362889D01*
G01X1705595Y-353124D02*
X1705387Y-352039D01*
X1704762Y-350799D01*
X1703720Y-350024D01*
X1702262Y-349714D01*
X1700804Y-350024D01*
X1699553Y-350954D01*
X1698928Y-352349D01*
Y-353899D01*
X1698512Y-354829D01*
X1697470Y-355604D01*
X1696012Y-355914D01*
X1694553Y-355449D01*
X1693512Y-354364D01*
X1693095Y-353124D01*
X1693512Y-351884D01*
X1694553Y-350799D01*
X1696012Y-350334D01*
X1697470Y-350644D01*
X1698512Y-351419D01*
X1698928Y-352349D01*
Y-353899D01*
X1699553Y-355294D01*
X1700804Y-356224D01*
X1702262Y-356534D01*
X1703720Y-356224D01*
X1704762Y-355449D01*
X1705387Y-354209D01*
X1705595Y-353124D01*
G01X1693095Y-340724D02*
X1693512Y-341964D01*
X1694553Y-342894D01*
X1695803Y-343514D01*
X1697470Y-343979D01*
X1699345Y-344134D01*
X1701220Y-343979D01*
X1702887Y-343514D01*
X1704137Y-342894D01*
X1705178Y-341964D01*
X1705595Y-340724D01*
X1705178Y-339484D01*
X1704137Y-338554D01*
X1702887Y-337934D01*
X1701220Y-337469D01*
X1699345Y-337314D01*
X1697470Y-337469D01*
X1695803Y-337934D01*
X1694553Y-338554D01*
X1693512Y-339484D01*
X1693095Y-340724D01*
G01X1703095Y-331734D02*
X1704554Y-330804D01*
X1705387Y-329564D01*
X1705595Y-328169D01*
X1705387Y-326929D01*
X1704345Y-325689D01*
X1703095Y-324914D01*
X1701845Y-324759D01*
X1700387Y-325069D01*
X1699345Y-326154D01*
X1698928Y-327239D01*
Y-328634D01*
G01Y-327239D02*
X1698303Y-326309D01*
X1697262Y-325534D01*
X1696012Y-325224D01*
X1694762Y-325534D01*
X1693720Y-326309D01*
X1693095Y-327704D01*
X1693303Y-329099D01*
X1694137Y-330494D01*
G01X1706012Y-315924D02*
X1705803Y-316234D01*
X1705387D01*
X1705178Y-315924D01*
X1705387Y-315614D01*
X1705803D01*
X1706012Y-315924D01*
G01X1695178Y-306469D02*
X1693929Y-305539D01*
X1693303Y-304454D01*
X1693095Y-303214D01*
X1693512Y-301664D01*
X1694553Y-300579D01*
X1695803Y-300269D01*
X1697054Y-300424D01*
X1698095Y-301044D01*
X1700178Y-304144D01*
X1701637Y-305539D01*
X1703720Y-306469D01*
X1705595Y-306779D01*
Y-300269D01*
G01Y-291434D02*
X1702887Y-291124D01*
X1700595Y-290659D01*
X1698512Y-290039D01*
X1696220Y-289264D01*
X1693095Y-288024D01*
Y-294224D01*
G01X1705595Y-254664D02*
X1693095D01*
X1702053Y-260399D01*
Y-252649D01*
G01X1695178Y-247069D02*
X1693929Y-246139D01*
X1693303Y-245054D01*
X1693095Y-243814D01*
X1693512Y-242264D01*
X1694553Y-241179D01*
X1695803Y-240869D01*
X1697054Y-241024D01*
X1698095Y-241644D01*
X1700178Y-244744D01*
X1701637Y-246139D01*
X1703720Y-247069D01*
X1705595Y-247379D01*
Y-240869D01*
G01X1700387Y-234669D02*
X1698928Y-233584D01*
X1698095Y-232654D01*
X1697678Y-231414D01*
X1698095Y-230329D01*
X1698928Y-229554D01*
X1700178Y-228934D01*
X1701637Y-228779D01*
X1702887Y-228934D01*
X1704137Y-229554D01*
X1705178Y-230484D01*
X1705595Y-231569D01*
X1705178Y-232809D01*
X1703929Y-233894D01*
X1702053Y-234514D01*
X1699970Y-234669D01*
X1697262Y-234359D01*
X1695803Y-233894D01*
X1694345Y-233119D01*
X1693303Y-232034D01*
X1693095Y-230949D01*
X1693512Y-229864D01*
X1694553Y-229089D01*
G01X1706012Y-219324D02*
X1705803Y-219634D01*
X1705387D01*
X1705178Y-219324D01*
X1705387Y-219014D01*
X1705803D01*
X1706012Y-219324D01*
G01X1705595Y-206924D02*
X1705387Y-205839D01*
X1704762Y-204599D01*
X1703720Y-203824D01*
X1702262Y-203514D01*
X1700804Y-203824D01*
X1699553Y-204754D01*
X1698928Y-206149D01*
Y-207699D01*
X1698512Y-208629D01*
X1697470Y-209404D01*
X1696012Y-209714D01*
X1694553Y-209249D01*
X1693512Y-208164D01*
X1693095Y-206924D01*
X1693512Y-205684D01*
X1694553Y-204599D01*
X1696012Y-204134D01*
X1697470Y-204444D01*
X1698512Y-205219D01*
X1698928Y-206149D01*
Y-207699D01*
X1699553Y-209094D01*
X1700804Y-210024D01*
X1702262Y-210334D01*
X1703720Y-210024D01*
X1704762Y-209249D01*
X1705387Y-208009D01*
X1705595Y-206924D01*
G01X1694860Y319597D02*
Y327097D01*
X1699154Y319597D01*
Y327097D01*
G01X1702640Y319597D02*
Y327097D01*
X1704880D01*
X1705627Y326722D01*
X1706187Y325847D01*
X1706374Y324847D01*
X1706187Y323847D01*
X1705720Y323097D01*
X1704880Y322722D01*
X1702640D01*
G01X1712007Y327097D02*
Y319597D01*
G01X1709860Y327097D02*
X1714154D01*
G01X1717547Y319597D02*
Y327097D01*
G01X1721467D02*
Y319597D01*
G01Y323347D02*
X1717547D01*
G01X1745956Y-390068D02*
X1733456D01*
X1735956Y-391928D01*
G01X1745956D02*
Y-388208D01*
G01Y-377978D02*
X1743248Y-377668D01*
X1740956Y-377203D01*
X1738873Y-376583D01*
X1736581Y-375808D01*
X1733456Y-374568D01*
Y-380768D01*
G01X1743456Y-368678D02*
X1744915Y-367748D01*
X1745748Y-366508D01*
X1745956Y-365113D01*
X1745748Y-363873D01*
X1744706Y-362633D01*
X1743456Y-361858D01*
X1742206Y-361703D01*
X1740748Y-362013D01*
X1739706Y-363098D01*
X1739289Y-364183D01*
Y-365578D01*
G01Y-364183D02*
X1738664Y-363253D01*
X1737623Y-362478D01*
X1736373Y-362168D01*
X1735123Y-362478D01*
X1734081Y-363253D01*
X1733456Y-364648D01*
X1733664Y-366043D01*
X1734498Y-367438D01*
G01X1744498Y-355503D02*
X1745539Y-354418D01*
X1745956Y-353178D01*
X1745539Y-351938D01*
X1744290Y-350853D01*
X1742414Y-350078D01*
X1740539Y-349768D01*
X1738248D01*
X1736373Y-350078D01*
X1734706Y-350853D01*
X1733873Y-351783D01*
X1733456Y-352868D01*
X1733873Y-354108D01*
X1734706Y-355038D01*
X1735956Y-355658D01*
X1737623Y-355968D01*
X1739081Y-355658D01*
X1740539Y-354883D01*
X1741373Y-353953D01*
X1741581Y-352868D01*
X1741165Y-351628D01*
X1740123Y-350698D01*
X1738248Y-349768D01*
G01X1745956Y-340778D02*
X1743248Y-340468D01*
X1740956Y-340003D01*
X1738873Y-339383D01*
X1736581Y-338608D01*
X1733456Y-337368D01*
Y-343568D01*
G01X1746373Y-328068D02*
X1746164Y-328378D01*
X1745748D01*
X1745539Y-328068D01*
X1745748Y-327758D01*
X1746164D01*
X1746373Y-328068D01*
G01X1733456Y-315668D02*
X1733873Y-316908D01*
X1734914Y-317838D01*
X1736164Y-318458D01*
X1737831Y-318923D01*
X1739706Y-319078D01*
X1741581Y-318923D01*
X1743248Y-318458D01*
X1744498Y-317838D01*
X1745539Y-316908D01*
X1745956Y-315668D01*
X1745539Y-314428D01*
X1744498Y-313498D01*
X1743248Y-312878D01*
X1741581Y-312413D01*
X1739706Y-312258D01*
X1737831Y-312413D01*
X1736164Y-312878D01*
X1734914Y-313498D01*
X1733873Y-314428D01*
X1733456Y-315668D01*
G01X1740748Y-306213D02*
X1739289Y-305128D01*
X1738456Y-304198D01*
X1738039Y-302958D01*
X1738456Y-301873D01*
X1739289Y-301098D01*
X1740539Y-300478D01*
X1741998Y-300323D01*
X1743248Y-300478D01*
X1744498Y-301098D01*
X1745539Y-302028D01*
X1745956Y-303113D01*
X1745539Y-304353D01*
X1744290Y-305438D01*
X1742414Y-306058D01*
X1740331Y-306213D01*
X1737623Y-305903D01*
X1736164Y-305438D01*
X1734706Y-304663D01*
X1733664Y-303578D01*
X1733456Y-302493D01*
X1733873Y-301408D01*
X1734914Y-300633D01*
G01X1745956Y-266808D02*
X1733456D01*
X1742414Y-272543D01*
Y-264793D01*
G01X1745956Y-254408D02*
X1733456D01*
X1742414Y-260143D01*
Y-252393D01*
G01X1745956Y-243868D02*
X1733456D01*
X1735956Y-245728D01*
G01X1745956D02*
Y-242008D01*
G01X1746373Y-231468D02*
X1746164Y-231778D01*
X1745748D01*
X1745539Y-231468D01*
X1745748Y-231158D01*
X1746164D01*
X1746373Y-231468D01*
G01X1745956Y-219068D02*
X1745748Y-217983D01*
X1745123Y-216743D01*
X1744081Y-215968D01*
X1742623Y-215658D01*
X1741165Y-215968D01*
X1739914Y-216898D01*
X1739289Y-218293D01*
Y-219843D01*
X1738873Y-220773D01*
X1737831Y-221548D01*
X1736373Y-221858D01*
X1734914Y-221393D01*
X1733873Y-220308D01*
X1733456Y-219068D01*
X1733873Y-217828D01*
X1734914Y-216743D01*
X1736373Y-216278D01*
X1737831Y-216588D01*
X1738873Y-217363D01*
X1739289Y-218293D01*
Y-219843D01*
X1739914Y-221238D01*
X1741165Y-222168D01*
X1742623Y-222478D01*
X1744081Y-222168D01*
X1745123Y-221393D01*
X1745748Y-220153D01*
X1745956Y-219068D01*
G01X1744498Y-209303D02*
X1745539Y-208218D01*
X1745956Y-206978D01*
X1745539Y-205738D01*
X1744290Y-204653D01*
X1742414Y-203878D01*
X1740539Y-203568D01*
X1738248D01*
X1736373Y-203878D01*
X1734706Y-204653D01*
X1733873Y-205583D01*
X1733456Y-206668D01*
X1733873Y-207908D01*
X1734706Y-208838D01*
X1735956Y-209458D01*
X1737623Y-209768D01*
X1739081Y-209458D01*
X1740539Y-208683D01*
X1741373Y-207753D01*
X1741581Y-206668D01*
X1741165Y-205428D01*
X1740123Y-204498D01*
X1738248Y-203568D01*
G01X1721865Y1680983D02*
Y1688483D01*
X1726159Y1680983D01*
Y1688483D01*
G01X1729645Y1680983D02*
Y1688483D01*
X1731885D01*
X1732632Y1688108D01*
X1733192Y1687233D01*
X1733379Y1686233D01*
X1733192Y1685233D01*
X1732725Y1684483D01*
X1731885Y1684108D01*
X1729645D01*
G01X1739012Y1688483D02*
Y1680983D01*
G01X1736865Y1688483D02*
X1741159D01*
G01X1744552Y1680983D02*
Y1688483D01*
G01X1748472D02*
Y1680983D01*
G01Y1684733D02*
X1744552D01*
G01X1740718Y635714D02*
Y643214D01*
X1745012Y635714D01*
Y643214D01*
G01X1748498Y635714D02*
Y643214D01*
X1750738D01*
X1751485Y642839D01*
X1752045Y641964D01*
X1752232Y640964D01*
X1752045Y639964D01*
X1751578Y639214D01*
X1750738Y638839D01*
X1748498D01*
G01X1757865Y643214D02*
Y635714D01*
G01X1755718Y643214D02*
X1760012D01*
G01X1763405Y635714D02*
Y643214D01*
G01X1767325D02*
Y635714D01*
G01Y639464D02*
X1763405D01*
G01X1773179Y-377922D02*
X1760679D01*
X1763179Y-379782D01*
G01X1773179D02*
Y-376062D01*
G01Y-365832D02*
X1770471Y-365522D01*
X1768179Y-365057D01*
X1766096Y-364437D01*
X1763804Y-363662D01*
X1760679Y-362422D01*
Y-368622D01*
G01X1767971Y-356067D02*
X1766512Y-354982D01*
X1765679Y-354052D01*
X1765262Y-352812D01*
X1765679Y-351727D01*
X1766512Y-350952D01*
X1767762Y-350332D01*
X1769221Y-350177D01*
X1770471Y-350332D01*
X1771721Y-350952D01*
X1772762Y-351882D01*
X1773179Y-352967D01*
X1772762Y-354207D01*
X1771513Y-355292D01*
X1769637Y-355912D01*
X1767554Y-356067D01*
X1764846Y-355757D01*
X1763387Y-355292D01*
X1761929Y-354517D01*
X1760887Y-353432D01*
X1760679Y-352347D01*
X1761096Y-351262D01*
X1762137Y-350487D01*
G01X1767971Y-343667D02*
X1766512Y-342582D01*
X1765679Y-341652D01*
X1765262Y-340412D01*
X1765679Y-339327D01*
X1766512Y-338552D01*
X1767762Y-337932D01*
X1769221Y-337777D01*
X1770471Y-337932D01*
X1771721Y-338552D01*
X1772762Y-339482D01*
X1773179Y-340567D01*
X1772762Y-341807D01*
X1771513Y-342892D01*
X1769637Y-343512D01*
X1767554Y-343667D01*
X1764846Y-343357D01*
X1763387Y-342892D01*
X1761929Y-342117D01*
X1760887Y-341032D01*
X1760679Y-339947D01*
X1761096Y-338862D01*
X1762137Y-338087D01*
G01X1771721Y-330957D02*
X1772762Y-329872D01*
X1773179Y-328632D01*
X1772762Y-327392D01*
X1771513Y-326307D01*
X1769637Y-325532D01*
X1767762Y-325222D01*
X1765471D01*
X1763596Y-325532D01*
X1761929Y-326307D01*
X1761096Y-327237D01*
X1760679Y-328322D01*
X1761096Y-329562D01*
X1761929Y-330492D01*
X1763179Y-331112D01*
X1764846Y-331422D01*
X1766304Y-331112D01*
X1767762Y-330337D01*
X1768596Y-329407D01*
X1768804Y-328322D01*
X1768388Y-327082D01*
X1767346Y-326152D01*
X1765471Y-325222D01*
G01X1773596Y-315922D02*
X1773387Y-316232D01*
X1772971D01*
X1772762Y-315922D01*
X1772971Y-315612D01*
X1773387D01*
X1773596Y-315922D01*
G01X1762762Y-306467D02*
X1761513Y-305537D01*
X1760887Y-304452D01*
X1760679Y-303212D01*
X1761096Y-301662D01*
X1762137Y-300577D01*
X1763387Y-300267D01*
X1764638Y-300422D01*
X1765679Y-301042D01*
X1767762Y-304142D01*
X1769221Y-305537D01*
X1771304Y-306467D01*
X1773179Y-306777D01*
Y-300267D01*
G01X1771721Y-293757D02*
X1772762Y-292672D01*
X1773179Y-291432D01*
X1772762Y-290192D01*
X1771513Y-289107D01*
X1769637Y-288332D01*
X1767762Y-288022D01*
X1765471D01*
X1763596Y-288332D01*
X1761929Y-289107D01*
X1761096Y-290037D01*
X1760679Y-291122D01*
X1761096Y-292362D01*
X1761929Y-293292D01*
X1763179Y-293912D01*
X1764846Y-294222D01*
X1766304Y-293912D01*
X1767762Y-293137D01*
X1768596Y-292207D01*
X1768804Y-291122D01*
X1768388Y-289882D01*
X1767346Y-288952D01*
X1765471Y-288022D01*
G01X1773179Y-254662D02*
X1760679D01*
X1769637Y-260397D01*
Y-252647D01*
G01X1773179Y-242262D02*
X1760679D01*
X1769637Y-247997D01*
Y-240247D01*
G01X1773179Y-231722D02*
X1772971Y-230637D01*
X1772346Y-229397D01*
X1771304Y-228622D01*
X1769846Y-228312D01*
X1768388Y-228622D01*
X1767137Y-229552D01*
X1766512Y-230947D01*
Y-232497D01*
X1766096Y-233427D01*
X1765054Y-234202D01*
X1763596Y-234512D01*
X1762137Y-234047D01*
X1761096Y-232962D01*
X1760679Y-231722D01*
X1761096Y-230482D01*
X1762137Y-229397D01*
X1763596Y-228932D01*
X1765054Y-229242D01*
X1766096Y-230017D01*
X1766512Y-230947D01*
Y-232497D01*
X1767137Y-233892D01*
X1768388Y-234822D01*
X1769846Y-235132D01*
X1771304Y-234822D01*
X1772346Y-234047D01*
X1772971Y-232807D01*
X1773179Y-231722D01*
G01X1773596Y-219322D02*
X1773387Y-219632D01*
X1772971D01*
X1772762Y-219322D01*
X1772971Y-219012D01*
X1773387D01*
X1773596Y-219322D01*
G01X1773179Y-206922D02*
X1772971Y-205837D01*
X1772346Y-204597D01*
X1771304Y-203822D01*
X1769846Y-203512D01*
X1768388Y-203822D01*
X1767137Y-204752D01*
X1766512Y-206147D01*
Y-207697D01*
X1766096Y-208627D01*
X1765054Y-209402D01*
X1763596Y-209712D01*
X1762137Y-209247D01*
X1761096Y-208162D01*
X1760679Y-206922D01*
X1761096Y-205682D01*
X1762137Y-204597D01*
X1763596Y-204132D01*
X1765054Y-204442D01*
X1766096Y-205217D01*
X1766512Y-206147D01*
Y-207697D01*
X1767137Y-209092D01*
X1768388Y-210022D01*
X1769846Y-210332D01*
X1771304Y-210022D01*
X1772346Y-209247D01*
X1772971Y-208007D01*
X1773179Y-206922D01*
G01X1812549Y-377923D02*
X1800049D01*
X1802549Y-379783D01*
G01X1812549D02*
Y-376063D01*
G01Y-365523D02*
X1812341Y-364438D01*
X1811716Y-363198D01*
X1810674Y-362423D01*
X1809216Y-362113D01*
X1807758Y-362423D01*
X1806507Y-363353D01*
X1805882Y-364748D01*
Y-366298D01*
X1805466Y-367228D01*
X1804424Y-368003D01*
X1802966Y-368313D01*
X1801507Y-367848D01*
X1800466Y-366763D01*
X1800049Y-365523D01*
X1800466Y-364283D01*
X1801507Y-363198D01*
X1802966Y-362733D01*
X1804424Y-363043D01*
X1805466Y-363818D01*
X1805882Y-364748D01*
Y-366298D01*
X1806507Y-367693D01*
X1807758Y-368623D01*
X1809216Y-368933D01*
X1810674Y-368623D01*
X1811716Y-367848D01*
X1812341Y-366608D01*
X1812549Y-365523D01*
G01X1800049Y-353123D02*
X1800466Y-354363D01*
X1801507Y-355293D01*
X1802757Y-355913D01*
X1804424Y-356378D01*
X1806299Y-356533D01*
X1808174Y-356378D01*
X1809841Y-355913D01*
X1811091Y-355293D01*
X1812132Y-354363D01*
X1812549Y-353123D01*
X1812132Y-351883D01*
X1811091Y-350953D01*
X1809841Y-350333D01*
X1808174Y-349868D01*
X1806299Y-349713D01*
X1804424Y-349868D01*
X1802757Y-350333D01*
X1801507Y-350953D01*
X1800466Y-351883D01*
X1800049Y-353123D01*
G01X1807341Y-343668D02*
X1805882Y-342583D01*
X1805049Y-341653D01*
X1804632Y-340413D01*
X1805049Y-339328D01*
X1805882Y-338553D01*
X1807132Y-337933D01*
X1808591Y-337778D01*
X1809841Y-337933D01*
X1811091Y-338553D01*
X1812132Y-339483D01*
X1812549Y-340568D01*
X1812132Y-341808D01*
X1810883Y-342893D01*
X1809007Y-343513D01*
X1806924Y-343668D01*
X1804216Y-343358D01*
X1802757Y-342893D01*
X1801299Y-342118D01*
X1800257Y-341033D01*
X1800049Y-339948D01*
X1800466Y-338863D01*
X1801507Y-338088D01*
G01X1802132Y-331268D02*
X1800883Y-330338D01*
X1800257Y-329253D01*
X1800049Y-328013D01*
X1800466Y-326463D01*
X1801507Y-325378D01*
X1802757Y-325068D01*
X1804008Y-325223D01*
X1805049Y-325843D01*
X1807132Y-328943D01*
X1808591Y-330338D01*
X1810674Y-331268D01*
X1812549Y-331578D01*
Y-325068D01*
G01X1812966Y-315923D02*
X1812757Y-316233D01*
X1812341D01*
X1812132Y-315923D01*
X1812341Y-315613D01*
X1812757D01*
X1812966Y-315923D01*
G01X1811091Y-306158D02*
X1812132Y-305073D01*
X1812549Y-303833D01*
X1812132Y-302593D01*
X1810883Y-301508D01*
X1809007Y-300733D01*
X1807132Y-300423D01*
X1804841D01*
X1802966Y-300733D01*
X1801299Y-301508D01*
X1800466Y-302438D01*
X1800049Y-303523D01*
X1800466Y-304763D01*
X1801299Y-305693D01*
X1802549Y-306313D01*
X1804216Y-306623D01*
X1805674Y-306313D01*
X1807132Y-305538D01*
X1807966Y-304608D01*
X1808174Y-303523D01*
X1807758Y-302283D01*
X1806716Y-301353D01*
X1804841Y-300423D01*
G01X1811091Y-293758D02*
X1812132Y-292673D01*
X1812549Y-291433D01*
X1812132Y-290193D01*
X1810883Y-289108D01*
X1809007Y-288333D01*
X1807132Y-288023D01*
X1804841D01*
X1802966Y-288333D01*
X1801299Y-289108D01*
X1800466Y-290038D01*
X1800049Y-291123D01*
X1800466Y-292363D01*
X1801299Y-293293D01*
X1802549Y-293913D01*
X1804216Y-294223D01*
X1805674Y-293913D01*
X1807132Y-293138D01*
X1807966Y-292208D01*
X1808174Y-291123D01*
X1807758Y-289883D01*
X1806716Y-288953D01*
X1804841Y-288023D01*
G01X1812549Y-254663D02*
X1800049D01*
X1809007Y-260398D01*
Y-252648D01*
G01X1810674Y-247533D02*
X1811716Y-246603D01*
X1812341Y-245518D01*
X1812549Y-244123D01*
X1812132Y-242728D01*
X1811299Y-241643D01*
X1809841Y-240868D01*
X1808174Y-240713D01*
X1806507Y-241023D01*
X1805466Y-241798D01*
X1804632Y-242883D01*
X1804424Y-243968D01*
X1804632Y-245053D01*
X1805466Y-246448D01*
X1800049Y-245983D01*
Y-241798D01*
G01X1812549Y-231723D02*
X1812341Y-230638D01*
X1811716Y-229398D01*
X1810674Y-228623D01*
X1809216Y-228313D01*
X1807758Y-228623D01*
X1806507Y-229553D01*
X1805882Y-230948D01*
Y-232498D01*
X1805466Y-233428D01*
X1804424Y-234203D01*
X1802966Y-234513D01*
X1801507Y-234048D01*
X1800466Y-232963D01*
X1800049Y-231723D01*
X1800466Y-230483D01*
X1801507Y-229398D01*
X1802966Y-228933D01*
X1804424Y-229243D01*
X1805466Y-230018D01*
X1805882Y-230948D01*
Y-232498D01*
X1806507Y-233893D01*
X1807758Y-234823D01*
X1809216Y-235133D01*
X1810674Y-234823D01*
X1811716Y-234048D01*
X1812341Y-232808D01*
X1812549Y-231723D01*
G01X1812966Y-219323D02*
X1812757Y-219633D01*
X1812341D01*
X1812132Y-219323D01*
X1812341Y-219013D01*
X1812757D01*
X1812966Y-219323D01*
G01X1812549Y-206923D02*
X1812341Y-205838D01*
X1811716Y-204598D01*
X1810674Y-203823D01*
X1809216Y-203513D01*
X1807758Y-203823D01*
X1806507Y-204753D01*
X1805882Y-206148D01*
Y-207698D01*
X1805466Y-208628D01*
X1804424Y-209403D01*
X1802966Y-209713D01*
X1801507Y-209248D01*
X1800466Y-208163D01*
X1800049Y-206923D01*
X1800466Y-205683D01*
X1801507Y-204598D01*
X1802966Y-204133D01*
X1804424Y-204443D01*
X1805466Y-205218D01*
X1805882Y-206148D01*
Y-207698D01*
X1806507Y-209093D01*
X1807758Y-210023D01*
X1809216Y-210333D01*
X1810674Y-210023D01*
X1811716Y-209248D01*
X1812341Y-208008D01*
X1812549Y-206923D01*
G01X1820692Y147056D02*
Y140756D01*
G01X1818890Y147056D02*
X1822494D01*
G01X1826992Y140756D02*
X1826365Y140861D01*
X1825817Y141281D01*
X1825347Y141911D01*
X1825034Y142646D01*
X1824877Y143486D01*
Y144326D01*
X1825034Y145166D01*
X1825347Y145901D01*
X1825817Y146531D01*
X1826365Y146951D01*
X1826992Y147056D01*
X1827619Y146951D01*
X1828167Y146531D01*
X1828637Y145901D01*
X1828950Y145166D01*
X1829107Y144326D01*
Y143486D01*
X1828950Y142646D01*
X1828637Y141911D01*
X1828167Y141281D01*
X1827619Y140861D01*
X1826992Y140756D01*
G01X1831725Y147056D02*
Y140756D01*
X1834859D01*
G01X1841159D02*
X1838025D01*
Y147056D01*
X1841159D01*
G01X1839905Y144011D02*
X1838025D01*
G01X1844325Y140756D02*
Y147056D01*
X1846284D01*
X1846910Y146741D01*
X1847302Y146321D01*
X1847459Y145481D01*
X1847302Y144641D01*
X1846832Y144116D01*
X1846284Y143801D01*
X1844325D01*
G01X1846284D02*
X1847459Y140756D01*
G01X1850234D02*
X1852192Y147056D01*
X1854150Y140756D01*
G01X1853445Y142961D02*
X1850939D01*
G01X1856690Y140756D02*
Y147056D01*
X1860294Y140756D01*
Y147056D01*
G01X1866515Y146531D02*
X1866045Y146846D01*
X1865497Y147056D01*
X1864870D01*
X1864165Y146741D01*
X1863617Y146216D01*
X1863225Y145586D01*
X1862912Y144536D01*
X1862834Y143591D01*
X1862990Y142646D01*
X1863225Y142016D01*
X1863695Y141386D01*
X1864244Y140966D01*
X1864792Y140756D01*
X1865340D01*
X1865889Y140966D01*
X1866359Y141281D01*
X1866750Y141701D01*
G01X1872659Y140756D02*
X1869525D01*
Y147056D01*
X1872659D01*
G01X1871405Y144011D02*
X1869525D01*
G01X1877392Y140546D02*
X1877235Y140651D01*
Y140861D01*
X1877392Y140966D01*
X1877549Y140861D01*
Y140651D01*
X1877392Y140546D01*
G01Y143381D02*
X1877235Y143486D01*
Y143696D01*
X1877392Y143801D01*
X1877549Y143696D01*
Y143486D01*
X1877392Y143381D01*
G01X1882830Y142856D02*
X1884710D01*
G01X1883692Y144221D02*
Y141491D01*
G01X1888504Y146006D02*
X1888974Y146636D01*
X1889522Y146951D01*
X1890149Y147056D01*
X1890932Y146846D01*
X1891480Y146321D01*
X1891637Y145691D01*
X1891559Y145061D01*
X1891245Y144536D01*
X1889679Y143486D01*
X1888974Y142751D01*
X1888504Y141701D01*
X1888347Y140756D01*
X1891637D01*
G01X1894882Y140546D02*
X1897702Y147056D01*
G01X1901574Y142856D02*
X1903610D01*
G01X1907404Y146006D02*
X1907874Y146636D01*
X1908422Y146951D01*
X1909049Y147056D01*
X1909832Y146846D01*
X1910380Y146321D01*
X1910537Y145691D01*
X1910459Y145061D01*
X1910145Y144536D01*
X1908579Y143486D01*
X1907874Y142751D01*
X1907404Y141701D01*
X1907247Y140756D01*
X1910537D01*
G01X1919142D02*
Y144956D01*
G01Y143801D02*
X1919377Y144326D01*
X1919769Y144746D01*
X1920317Y144956D01*
X1920865Y144746D01*
X1921257Y144326D01*
X1921492Y143801D01*
Y140756D01*
G01Y143801D02*
X1921727Y144326D01*
X1922119Y144746D01*
X1922667Y144956D01*
X1923215Y144746D01*
X1923607Y144326D01*
X1923842Y143696D01*
Y140756D01*
G01X1927792Y144956D02*
Y140756D01*
G01Y146636D02*
X1927635Y146741D01*
Y146951D01*
X1927792Y147056D01*
X1927949Y146951D01*
Y146741D01*
X1927792Y146636D01*
G01X1934092Y140756D02*
Y147056D01*
G01X1813328Y1449854D02*
Y1457354D01*
X1817622Y1449854D01*
Y1457354D01*
G01X1821108Y1449854D02*
Y1457354D01*
X1823348D01*
X1824095Y1456979D01*
X1824655Y1456104D01*
X1824842Y1455104D01*
X1824655Y1454104D01*
X1824188Y1453354D01*
X1823348Y1452979D01*
X1821108D01*
G01X1830475Y1457354D02*
Y1449854D01*
G01X1828328Y1457354D02*
X1832622D01*
G01X1836015Y1449854D02*
Y1457354D01*
G01X1839935D02*
Y1449854D01*
G01Y1453604D02*
X1836015D01*
G01X1840961Y-389154D02*
X1828461D01*
X1830961Y-391014D01*
G01X1840961D02*
Y-387294D01*
G01Y-376754D02*
X1840753Y-375669D01*
X1840128Y-374429D01*
X1839086Y-373654D01*
X1837628Y-373344D01*
X1836170Y-373654D01*
X1834919Y-374584D01*
X1834294Y-375979D01*
Y-377529D01*
X1833878Y-378459D01*
X1832836Y-379234D01*
X1831378Y-379544D01*
X1829919Y-379079D01*
X1828878Y-377994D01*
X1828461Y-376754D01*
X1828878Y-375514D01*
X1829919Y-374429D01*
X1831378Y-373964D01*
X1832836Y-374274D01*
X1833878Y-375049D01*
X1834294Y-375979D01*
Y-377529D01*
X1834919Y-378924D01*
X1836170Y-379854D01*
X1837628Y-380164D01*
X1839086Y-379854D01*
X1840128Y-379079D01*
X1840753Y-377839D01*
X1840961Y-376754D01*
G01Y-364354D02*
X1828461D01*
X1830961Y-366214D01*
G01X1840961D02*
Y-362494D01*
G01X1835753Y-354899D02*
X1834294Y-353814D01*
X1833461Y-352884D01*
X1833044Y-351644D01*
X1833461Y-350559D01*
X1834294Y-349784D01*
X1835544Y-349164D01*
X1837003Y-349009D01*
X1838253Y-349164D01*
X1839503Y-349784D01*
X1840544Y-350714D01*
X1840961Y-351799D01*
X1840544Y-353039D01*
X1839295Y-354124D01*
X1837419Y-354744D01*
X1835336Y-354899D01*
X1832628Y-354589D01*
X1831169Y-354124D01*
X1829711Y-353349D01*
X1828669Y-352264D01*
X1828461Y-351179D01*
X1828878Y-350094D01*
X1829919Y-349319D01*
G01X1840961Y-339864D02*
X1838253Y-339554D01*
X1835961Y-339089D01*
X1833878Y-338469D01*
X1831586Y-337694D01*
X1828461Y-336454D01*
Y-342654D01*
G01X1841378Y-327154D02*
X1841169Y-327464D01*
X1840753D01*
X1840544Y-327154D01*
X1840753Y-326844D01*
X1841169D01*
X1841378Y-327154D01*
G01X1840961Y-315064D02*
X1838253Y-314754D01*
X1835961Y-314289D01*
X1833878Y-313669D01*
X1831586Y-312894D01*
X1828461Y-311654D01*
Y-317854D01*
G01X1840961Y-302354D02*
X1828461D01*
X1830961Y-304214D01*
G01X1840961D02*
Y-300494D01*
G01Y-265894D02*
X1828461D01*
X1837419Y-271629D01*
Y-263879D01*
G01X1835753Y-258299D02*
X1834294Y-257214D01*
X1833461Y-256284D01*
X1833044Y-255044D01*
X1833461Y-253959D01*
X1834294Y-253184D01*
X1835544Y-252564D01*
X1837003Y-252409D01*
X1838253Y-252564D01*
X1839503Y-253184D01*
X1840544Y-254114D01*
X1840961Y-255199D01*
X1840544Y-256439D01*
X1839295Y-257524D01*
X1837419Y-258144D01*
X1835336Y-258299D01*
X1832628Y-257989D01*
X1831169Y-257524D01*
X1829711Y-256749D01*
X1828669Y-255664D01*
X1828461Y-254579D01*
X1828878Y-253494D01*
X1829919Y-252719D01*
G01X1840961Y-242954D02*
X1828461D01*
X1830961Y-244814D01*
G01X1840961D02*
Y-241094D01*
G01X1841378Y-230554D02*
X1841169Y-230864D01*
X1840753D01*
X1840544Y-230554D01*
X1840753Y-230244D01*
X1841169D01*
X1841378Y-230554D01*
G01X1840961Y-216294D02*
X1828461D01*
X1837419Y-222029D01*
Y-214279D01*
G01X1835753Y-208699D02*
X1834294Y-207614D01*
X1833461Y-206684D01*
X1833044Y-205444D01*
X1833461Y-204359D01*
X1834294Y-203584D01*
X1835544Y-202964D01*
X1837003Y-202809D01*
X1838253Y-202964D01*
X1839503Y-203584D01*
X1840544Y-204514D01*
X1840961Y-205599D01*
X1840544Y-206839D01*
X1839295Y-207924D01*
X1837419Y-208544D01*
X1835336Y-208699D01*
X1832628Y-208389D01*
X1831169Y-207924D01*
X1829711Y-207149D01*
X1828669Y-206064D01*
X1828461Y-204979D01*
X1828878Y-203894D01*
X1829919Y-203119D01*
G01X1821474Y104531D02*
Y112031D01*
X1825768Y104531D01*
Y112031D01*
G01X1829254Y104531D02*
Y112031D01*
X1831494D01*
X1832241Y111656D01*
X1832801Y110781D01*
X1832988Y109781D01*
X1832801Y108781D01*
X1832334Y108031D01*
X1831494Y107656D01*
X1829254D01*
G01X1838621Y112031D02*
Y104531D01*
G01X1836474Y112031D02*
X1840768D01*
G01X1844161Y104531D02*
Y112031D01*
G01X1848081D02*
Y104531D01*
G01Y108281D02*
X1844161D01*
G01X1867029Y-389153D02*
X1854529D01*
X1857029Y-391013D01*
G01X1867029D02*
Y-387293D01*
G01Y-376753D02*
X1866821Y-375668D01*
X1866196Y-374428D01*
X1865154Y-373653D01*
X1863696Y-373343D01*
X1862238Y-373653D01*
X1860987Y-374583D01*
X1860362Y-375978D01*
Y-377528D01*
X1859946Y-378458D01*
X1858904Y-379233D01*
X1857446Y-379543D01*
X1855987Y-379078D01*
X1854946Y-377993D01*
X1854529Y-376753D01*
X1854946Y-375513D01*
X1855987Y-374428D01*
X1857446Y-373963D01*
X1858904Y-374273D01*
X1859946Y-375048D01*
X1860362Y-375978D01*
Y-377528D01*
X1860987Y-378923D01*
X1862238Y-379853D01*
X1863696Y-380163D01*
X1865154Y-379853D01*
X1866196Y-379078D01*
X1866821Y-377838D01*
X1867029Y-376753D01*
G01Y-364353D02*
X1854529D01*
X1857029Y-366213D01*
G01X1867029D02*
Y-362493D01*
G01X1865571Y-354588D02*
X1866612Y-353503D01*
X1867029Y-352263D01*
X1866612Y-351023D01*
X1865363Y-349938D01*
X1863487Y-349163D01*
X1861612Y-348853D01*
X1859321D01*
X1857446Y-349163D01*
X1855779Y-349938D01*
X1854946Y-350868D01*
X1854529Y-351953D01*
X1854946Y-353193D01*
X1855779Y-354123D01*
X1857029Y-354743D01*
X1858696Y-355053D01*
X1860154Y-354743D01*
X1861612Y-353968D01*
X1862446Y-353038D01*
X1862654Y-351953D01*
X1862238Y-350713D01*
X1861196Y-349783D01*
X1859321Y-348853D01*
G01X1856612Y-342498D02*
X1855363Y-341568D01*
X1854737Y-340483D01*
X1854529Y-339243D01*
X1854946Y-337693D01*
X1855987Y-336608D01*
X1857237Y-336298D01*
X1858488Y-336453D01*
X1859529Y-337073D01*
X1861612Y-340173D01*
X1863071Y-341568D01*
X1865154Y-342498D01*
X1867029Y-342808D01*
Y-336298D01*
G01X1867446Y-327153D02*
X1867237Y-327463D01*
X1866821D01*
X1866612Y-327153D01*
X1866821Y-326843D01*
X1867237D01*
X1867446Y-327153D01*
G01X1854529Y-314753D02*
X1854946Y-315993D01*
X1855987Y-316923D01*
X1857237Y-317543D01*
X1858904Y-318008D01*
X1860779Y-318163D01*
X1862654Y-318008D01*
X1864321Y-317543D01*
X1865571Y-316923D01*
X1866612Y-315993D01*
X1867029Y-314753D01*
X1866612Y-313513D01*
X1865571Y-312583D01*
X1864321Y-311963D01*
X1862654Y-311498D01*
X1860779Y-311343D01*
X1858904Y-311498D01*
X1857237Y-311963D01*
X1855987Y-312583D01*
X1854946Y-313513D01*
X1854529Y-314753D01*
G01X1867029Y-302353D02*
X1866821Y-301268D01*
X1866196Y-300028D01*
X1865154Y-299253D01*
X1863696Y-298943D01*
X1862238Y-299253D01*
X1860987Y-300183D01*
X1860362Y-301578D01*
Y-303128D01*
X1859946Y-304058D01*
X1858904Y-304833D01*
X1857446Y-305143D01*
X1855987Y-304678D01*
X1854946Y-303593D01*
X1854529Y-302353D01*
X1854946Y-301113D01*
X1855987Y-300028D01*
X1857446Y-299563D01*
X1858904Y-299873D01*
X1859946Y-300648D01*
X1860362Y-301578D01*
Y-303128D01*
X1860987Y-304523D01*
X1862238Y-305453D01*
X1863696Y-305763D01*
X1865154Y-305453D01*
X1866196Y-304678D01*
X1866821Y-303438D01*
X1867029Y-302353D01*
G01Y-265893D02*
X1854529D01*
X1863487Y-271628D01*
Y-263878D01*
G01X1861821Y-258298D02*
X1860362Y-257213D01*
X1859529Y-256283D01*
X1859112Y-255043D01*
X1859529Y-253958D01*
X1860362Y-253183D01*
X1861612Y-252563D01*
X1863071Y-252408D01*
X1864321Y-252563D01*
X1865571Y-253183D01*
X1866612Y-254113D01*
X1867029Y-255198D01*
X1866612Y-256438D01*
X1865363Y-257523D01*
X1863487Y-258143D01*
X1861404Y-258298D01*
X1858696Y-257988D01*
X1857237Y-257523D01*
X1855779Y-256748D01*
X1854737Y-255663D01*
X1854529Y-254578D01*
X1854946Y-253493D01*
X1855987Y-252718D01*
G01X1856612Y-245898D02*
X1855363Y-244968D01*
X1854737Y-243883D01*
X1854529Y-242643D01*
X1854946Y-241093D01*
X1855987Y-240008D01*
X1857237Y-239698D01*
X1858488Y-239853D01*
X1859529Y-240473D01*
X1861612Y-243573D01*
X1863071Y-244968D01*
X1865154Y-245898D01*
X1867029Y-246208D01*
Y-239698D01*
G01X1867446Y-230553D02*
X1867237Y-230863D01*
X1866821D01*
X1866612Y-230553D01*
X1866821Y-230243D01*
X1867237D01*
X1867446Y-230553D01*
G01X1854529Y-218153D02*
X1854946Y-219393D01*
X1855987Y-220323D01*
X1857237Y-220943D01*
X1858904Y-221408D01*
X1860779Y-221563D01*
X1862654Y-221408D01*
X1864321Y-220943D01*
X1865571Y-220323D01*
X1866612Y-219393D01*
X1867029Y-218153D01*
X1866612Y-216913D01*
X1865571Y-215983D01*
X1864321Y-215363D01*
X1862654Y-214898D01*
X1860779Y-214743D01*
X1858904Y-214898D01*
X1857237Y-215363D01*
X1855987Y-215983D01*
X1854946Y-216913D01*
X1854529Y-218153D01*
G01X1867029Y-205753D02*
X1866821Y-204668D01*
X1866196Y-203428D01*
X1865154Y-202653D01*
X1863696Y-202343D01*
X1862238Y-202653D01*
X1860987Y-203583D01*
X1860362Y-204978D01*
Y-206528D01*
X1859946Y-207458D01*
X1858904Y-208233D01*
X1857446Y-208543D01*
X1855987Y-208078D01*
X1854946Y-206993D01*
X1854529Y-205753D01*
X1854946Y-204513D01*
X1855987Y-203428D01*
X1857446Y-202963D01*
X1858904Y-203273D01*
X1859946Y-204048D01*
X1860362Y-204978D01*
Y-206528D01*
X1860987Y-207923D01*
X1862238Y-208853D01*
X1863696Y-209163D01*
X1865154Y-208853D01*
X1866196Y-208078D01*
X1866821Y-206838D01*
X1867029Y-205753D01*
G01X2078323Y2772457D02*
X2078943Y2773082D01*
X2079408Y2774123D01*
X2079718Y2775582D01*
X2079408Y2776832D01*
X2078788Y2777665D01*
X2077703Y2778290D01*
X2073518D01*
Y2765790D01*
X2078633D01*
X2079718Y2766623D01*
X2080338Y2767873D01*
X2080648Y2769332D01*
X2080338Y2770790D01*
X2079408Y2772040D01*
X2078323Y2772457D01*
X2073518D01*
G01X2085608Y2765790D02*
X2089483Y2778290D01*
X2093358Y2765790D01*
G01X2091963Y2770165D02*
X2087003D01*
G01X2105293Y2777248D02*
X2104363Y2777873D01*
X2103278Y2778290D01*
X2102038D01*
X2100643Y2777665D01*
X2099558Y2776623D01*
X2098783Y2775373D01*
X2098163Y2773290D01*
X2098008Y2771415D01*
X2098318Y2769540D01*
X2098783Y2768290D01*
X2099713Y2767040D01*
X2100798Y2766207D01*
X2101883Y2765790D01*
X2102968D01*
X2104053Y2766207D01*
X2104983Y2766831D01*
X2105758Y2767665D01*
G01X2110873Y2765790D02*
Y2778290D01*
G01X2116763D02*
X2110873Y2770581D01*
G01X2117693Y2765790D02*
X2113508Y2774123D01*
G01X2123273Y2765790D02*
Y2778290D01*
X2126373D01*
X2127613Y2777665D01*
X2128543Y2776832D01*
X2129318Y2775582D01*
X2129938Y2774123D01*
X2130093Y2772040D01*
X2129938Y2769957D01*
X2129318Y2768498D01*
X2128543Y2767248D01*
X2127613Y2766415D01*
X2126373Y2765790D01*
X2123273D01*
G01X2135983D02*
Y2778290D01*
X2139858D01*
X2141098Y2777665D01*
X2141873Y2776832D01*
X2142183Y2775165D01*
X2141873Y2773498D01*
X2140943Y2772457D01*
X2139858Y2771832D01*
X2135983D01*
G01X2139858D02*
X2142183Y2765790D01*
G01X2149623Y2778290D02*
X2153343D01*
G01X2151483D02*
Y2765790D01*
G01X2149623D02*
X2153343D01*
G01X2160783Y2778290D02*
Y2765790D01*
X2166983D01*
G01X2173183Y2778290D02*
Y2765790D01*
X2179383D01*
G01X2197828Y2767456D02*
X2199068Y2766415D01*
X2200463Y2765790D01*
X2201703D01*
X2202943Y2766415D01*
X2203873Y2767456D01*
X2204338Y2768915D01*
X2204028Y2770373D01*
X2203253Y2771623D01*
X2201858Y2772457D01*
X2199998Y2772873D01*
X2198913Y2773707D01*
X2198448Y2775165D01*
X2198758Y2776623D01*
X2199533Y2777665D01*
X2200618Y2778290D01*
X2201703D01*
X2202788Y2777873D01*
X2203718Y2776832D01*
G01X2213483Y2778290D02*
Y2765790D01*
G01X2209918Y2778290D02*
X2217048D01*
G01X2222473D02*
Y2769332D01*
X2223093Y2767456D01*
X2224333Y2766207D01*
X2225883Y2765790D01*
X2227433Y2766207D01*
X2228673Y2767456D01*
X2229293Y2769332D01*
Y2778290D01*
G01X2239523Y2772457D02*
X2240143Y2773082D01*
X2240608Y2774123D01*
X2240918Y2775582D01*
X2240608Y2776832D01*
X2239988Y2777665D01*
X2238903Y2778290D01*
X2234718D01*
Y2765790D01*
X2239833D01*
X2240918Y2766623D01*
X2241538Y2767873D01*
X2241848Y2769332D01*
X2241538Y2770790D01*
X2240608Y2772040D01*
X2239523Y2772457D01*
X2234718D01*
G01X2259983Y2778290D02*
Y2765790D01*
X2266183D01*
G01X2278583D02*
X2272383D01*
Y2778290D01*
X2278583D01*
G01X2276103Y2772248D02*
X2272383D01*
G01X2284318Y2765790D02*
Y2778290D01*
X2291448Y2765790D01*
Y2778290D01*
G01X2301213Y2772040D02*
X2304313D01*
Y2768290D01*
X2303383Y2767040D01*
X2302298Y2766207D01*
X2300748Y2765790D01*
X2299198Y2766207D01*
X2298113Y2767040D01*
X2297183Y2768290D01*
X2296563Y2769748D01*
X2296253Y2771415D01*
Y2772873D01*
X2296563Y2774123D01*
X2297183Y2775582D01*
X2298113Y2776832D01*
X2299043Y2777665D01*
X2300283Y2778290D01*
X2301368D01*
X2302608Y2777873D01*
X2303538Y2777040D01*
G01X2312683Y2778290D02*
Y2765790D01*
G01X2309118Y2778290D02*
X2316248D01*
G01X2321828Y2765790D02*
Y2778290D01*
G01X2328338D02*
Y2765790D01*
G01Y2772040D02*
X2321828D01*
G01X2349883Y2778290D02*
Y2765790D01*
G01X2346318Y2778290D02*
X2353448D01*
G01X2362283Y2765790D02*
X2361043Y2765998D01*
X2359958Y2766831D01*
X2359028Y2768082D01*
X2358408Y2769540D01*
X2358098Y2771207D01*
Y2772873D01*
X2358408Y2774540D01*
X2359028Y2775998D01*
X2359958Y2777248D01*
X2361043Y2778082D01*
X2362283Y2778290D01*
X2363523Y2778082D01*
X2364608Y2777248D01*
X2365538Y2775998D01*
X2366158Y2774540D01*
X2366468Y2772873D01*
Y2771207D01*
X2366158Y2769540D01*
X2365538Y2768082D01*
X2364608Y2766831D01*
X2363523Y2765998D01*
X2362283Y2765790D01*
G01X2371583Y2778290D02*
Y2765790D01*
X2377783D01*
G01X2390183D02*
X2383983D01*
Y2778290D01*
X2390183D01*
G01X2387703Y2772248D02*
X2383983D01*
G01X2396383Y2765790D02*
Y2778290D01*
X2400258D01*
X2401498Y2777665D01*
X2402273Y2776832D01*
X2402583Y2775165D01*
X2402273Y2773498D01*
X2401343Y2772457D01*
X2400258Y2771832D01*
X2396383D01*
G01X2400258D02*
X2402583Y2765790D01*
G01X2408008D02*
X2411883Y2778290D01*
X2415758Y2765790D01*
G01X2414363Y2770165D02*
X2409403D01*
G01X2420718Y2765790D02*
Y2778290D01*
X2427848Y2765790D01*
Y2778290D01*
G01X2440093Y2777248D02*
X2439163Y2777873D01*
X2438078Y2778290D01*
X2436838D01*
X2435443Y2777665D01*
X2434358Y2776623D01*
X2433583Y2775373D01*
X2432963Y2773290D01*
X2432808Y2771415D01*
X2433118Y2769540D01*
X2433583Y2768290D01*
X2434513Y2767040D01*
X2435598Y2766207D01*
X2436683Y2765790D01*
X2437768D01*
X2438853Y2766207D01*
X2439783Y2766831D01*
X2440558Y2767665D01*
G01X2452183Y2765790D02*
X2445983D01*
Y2778290D01*
X2452183D01*
G01X2449703Y2772248D02*
X2445983D01*
G01X2473883Y2778290D02*
Y2765790D01*
G01X2470318Y2778290D02*
X2477448D01*
G01X2486283Y2765790D02*
X2485043Y2765998D01*
X2483958Y2766831D01*
X2483028Y2768082D01*
X2482408Y2769540D01*
X2482098Y2771207D01*
Y2772873D01*
X2482408Y2774540D01*
X2483028Y2775998D01*
X2483958Y2777248D01*
X2485043Y2778082D01*
X2486283Y2778290D01*
X2487523Y2778082D01*
X2488608Y2777248D01*
X2489538Y2775998D01*
X2490158Y2774540D01*
X2490468Y2772873D01*
Y2771207D01*
X2490158Y2769540D01*
X2489538Y2768082D01*
X2488608Y2766831D01*
X2487523Y2765998D01*
X2486283Y2765790D01*
G01X2512323Y2772457D02*
X2512943Y2773082D01*
X2513408Y2774123D01*
X2513718Y2775582D01*
X2513408Y2776832D01*
X2512788Y2777665D01*
X2511703Y2778290D01*
X2507518D01*
Y2765790D01*
X2512633D01*
X2513718Y2766623D01*
X2514338Y2767873D01*
X2514648Y2769332D01*
X2514338Y2770790D01*
X2513408Y2772040D01*
X2512323Y2772457D01*
X2507518D01*
G01X2526583Y2765790D02*
X2520383D01*
Y2778290D01*
X2526583D01*
G01X2524103Y2772248D02*
X2520383D01*
G01X2547973Y2765790D02*
X2548283Y2768498D01*
X2548748Y2770790D01*
X2549368Y2772873D01*
X2550143Y2775165D01*
X2551383Y2778290D01*
X2545183D01*
G01X2571378Y2769957D02*
X2575098D01*
G01X2573083Y2772665D02*
Y2767248D01*
G01X2582693Y2765373D02*
X2588273Y2778290D01*
G01X2595868Y2769957D02*
X2599898D01*
G01X2606873Y2767665D02*
X2607803Y2766623D01*
X2608888Y2765998D01*
X2610283Y2765790D01*
X2611678Y2766207D01*
X2612763Y2767040D01*
X2613538Y2768498D01*
X2613693Y2770165D01*
X2613383Y2771832D01*
X2612608Y2772873D01*
X2611523Y2773707D01*
X2610438Y2773915D01*
X2609353Y2773707D01*
X2607958Y2772873D01*
X2608423Y2778290D01*
X2612608D01*
G01X2631053Y2765790D02*
Y2778290D01*
X2635083Y2767873D01*
X2639113Y2778290D01*
Y2765790D01*
G01X2645623Y2778290D02*
X2649343D01*
G01X2647483D02*
Y2765790D01*
G01X2645623D02*
X2649343D01*
G01X2656783Y2778290D02*
Y2765790D01*
X2662983D01*
G01X2669028Y2767456D02*
X2670268Y2766415D01*
X2671663Y2765790D01*
X2672903D01*
X2674143Y2766415D01*
X2675073Y2767456D01*
X2675538Y2768915D01*
X2675228Y2770373D01*
X2674453Y2771623D01*
X2673058Y2772457D01*
X2671198Y2772873D01*
X2670113Y2773707D01*
X2669648Y2775165D01*
X2669958Y2776623D01*
X2670733Y2777665D01*
X2671818Y2778290D01*
X2672903D01*
X2673988Y2777873D01*
X2674918Y2776832D01*
G01X1913868Y2788707D02*
X1917898D01*
G01X1936653Y2784540D02*
Y2797040D01*
X1940683Y2786623D01*
X1944713Y2797040D01*
Y2784540D01*
G01X1950138D02*
Y2797040D01*
X1956028D01*
G01X1953858Y2790998D02*
X1950138D01*
G01X1966413Y2790790D02*
X1969513D01*
Y2787040D01*
X1968583Y2785790D01*
X1967498Y2784957D01*
X1965948Y2784540D01*
X1964398Y2784957D01*
X1963313Y2785790D01*
X1962383Y2787040D01*
X1961763Y2788498D01*
X1961453Y2790165D01*
Y2791623D01*
X1961763Y2792873D01*
X1962383Y2794332D01*
X1963313Y2795582D01*
X1964243Y2796415D01*
X1965483Y2797040D01*
X1966568D01*
X1967808Y2796623D01*
X1968738Y2795790D01*
G01X1973233Y2780373D02*
X1982533D01*
G01X1987028Y2786206D02*
X1988268Y2785165D01*
X1989663Y2784540D01*
X1990903D01*
X1992143Y2785165D01*
X1993073Y2786206D01*
X1993538Y2787665D01*
X1993228Y2789123D01*
X1992453Y2790373D01*
X1991058Y2791207D01*
X1989198Y2791623D01*
X1988113Y2792457D01*
X1987648Y2793915D01*
X1987958Y2795373D01*
X1988733Y2796415D01*
X1989818Y2797040D01*
X1990903D01*
X1991988Y2796623D01*
X1992918Y2795582D01*
G01X2002683Y2797040D02*
Y2784540D01*
G01X1999118Y2797040D02*
X2006248D01*
G01X2011673D02*
Y2788082D01*
X2012293Y2786206D01*
X2013533Y2784957D01*
X2015083Y2784540D01*
X2016633Y2784957D01*
X2017873Y2786206D01*
X2018493Y2788082D01*
Y2797040D01*
G01X2028723Y2791207D02*
X2029343Y2791832D01*
X2029808Y2792873D01*
X2030118Y2794332D01*
X2029808Y2795582D01*
X2029188Y2796415D01*
X2028103Y2797040D01*
X2023918D01*
Y2784540D01*
X2029033D01*
X2030118Y2785373D01*
X2030738Y2786623D01*
X2031048Y2788082D01*
X2030738Y2789540D01*
X2029808Y2790790D01*
X2028723Y2791207D01*
X2023918D01*
G01X2052283Y2784123D02*
X2051973Y2784332D01*
Y2784748D01*
X2052283Y2784957D01*
X2052593Y2784748D01*
Y2784332D01*
X2052283Y2784123D01*
G01Y2789748D02*
X2051973Y2789957D01*
Y2790373D01*
X2052283Y2790582D01*
X2052593Y2790373D01*
Y2789957D01*
X2052283Y2789748D01*
G01X2073053Y2784540D02*
Y2797040D01*
X2077083Y2786623D01*
X2081113Y2797040D01*
Y2784540D01*
G01X2085608D02*
X2089483Y2797040D01*
X2093358Y2784540D01*
G01X2091963Y2788915D02*
X2087003D01*
G01X2098318Y2784540D02*
Y2797040D01*
X2105448Y2784540D01*
Y2797040D01*
G01X2110873D02*
Y2788082D01*
X2111493Y2786206D01*
X2112733Y2784957D01*
X2114283Y2784540D01*
X2115833Y2784957D01*
X2117073Y2786206D01*
X2117693Y2788082D01*
Y2797040D01*
G01X2123738Y2784540D02*
Y2797040D01*
X2129628D01*
G01X2127458Y2790998D02*
X2123738D01*
G01X2135208Y2784540D02*
X2139083Y2797040D01*
X2142958Y2784540D01*
G01X2141563Y2788915D02*
X2136603D01*
G01X2154893Y2795998D02*
X2153963Y2796623D01*
X2152878Y2797040D01*
X2151638D01*
X2150243Y2796415D01*
X2149158Y2795373D01*
X2148383Y2794123D01*
X2147763Y2792040D01*
X2147608Y2790165D01*
X2147918Y2788290D01*
X2148383Y2787040D01*
X2149313Y2785790D01*
X2150398Y2784957D01*
X2151483Y2784540D01*
X2152568D01*
X2153653Y2784957D01*
X2154583Y2785581D01*
X2155358Y2786415D01*
G01X2163883Y2797040D02*
Y2784540D01*
G01X2160318Y2797040D02*
X2167448D01*
G01X2172873D02*
Y2788082D01*
X2173493Y2786206D01*
X2174733Y2784957D01*
X2176283Y2784540D01*
X2177833Y2784957D01*
X2179073Y2786206D01*
X2179693Y2788082D01*
Y2797040D01*
G01X2185583Y2784540D02*
Y2797040D01*
X2189458D01*
X2190698Y2796415D01*
X2191473Y2795582D01*
X2191783Y2793915D01*
X2191473Y2792248D01*
X2190543Y2791207D01*
X2189458Y2790582D01*
X2185583D01*
G01X2189458D02*
X2191783Y2784540D01*
G01X2199223Y2797040D02*
X2202943D01*
G01X2201083D02*
Y2784540D01*
G01X2199223D02*
X2202943D01*
G01X2209918D02*
Y2797040D01*
X2217048Y2784540D01*
Y2797040D01*
G01X2226813Y2790790D02*
X2229913D01*
Y2787040D01*
X2228983Y2785790D01*
X2227898Y2784957D01*
X2226348Y2784540D01*
X2224798Y2784957D01*
X2223713Y2785790D01*
X2222783Y2787040D01*
X2222163Y2788498D01*
X2221853Y2790165D01*
Y2791623D01*
X2222163Y2792873D01*
X2222783Y2794332D01*
X2223713Y2795582D01*
X2224643Y2796415D01*
X2225883Y2797040D01*
X2226968D01*
X2228208Y2796623D01*
X2229138Y2795790D01*
G01X2247428Y2786206D02*
X2248668Y2785165D01*
X2250063Y2784540D01*
X2251303D01*
X2252543Y2785165D01*
X2253473Y2786206D01*
X2253938Y2787665D01*
X2253628Y2789123D01*
X2252853Y2790373D01*
X2251458Y2791207D01*
X2249598Y2791623D01*
X2248513Y2792457D01*
X2248048Y2793915D01*
X2248358Y2795373D01*
X2249133Y2796415D01*
X2250218Y2797040D01*
X2251303D01*
X2252388Y2796623D01*
X2253318Y2795582D01*
G01X2263083Y2797040D02*
Y2784540D01*
G01X2259518Y2797040D02*
X2266648D01*
G01X2272073D02*
Y2788082D01*
X2272693Y2786206D01*
X2273933Y2784957D01*
X2275483Y2784540D01*
X2277033Y2784957D01*
X2278273Y2786206D01*
X2278893Y2788082D01*
Y2797040D01*
G01X2289123Y2791207D02*
X2289743Y2791832D01*
X2290208Y2792873D01*
X2290518Y2794332D01*
X2290208Y2795582D01*
X2289588Y2796415D01*
X2288503Y2797040D01*
X2284318D01*
Y2784540D01*
X2289433D01*
X2290518Y2785373D01*
X2291138Y2786623D01*
X2291448Y2788082D01*
X2291138Y2789540D01*
X2290208Y2790790D01*
X2289123Y2791207D01*
X2284318D01*
G01X2309583Y2797040D02*
Y2784540D01*
X2315783D01*
G01X2328183D02*
X2321983D01*
Y2797040D01*
X2328183D01*
G01X2325703Y2790998D02*
X2321983D01*
G01X2333918Y2784540D02*
Y2797040D01*
X2341048Y2784540D01*
Y2797040D01*
G01X2350813Y2790790D02*
X2353913D01*
Y2787040D01*
X2352983Y2785790D01*
X2351898Y2784957D01*
X2350348Y2784540D01*
X2348798Y2784957D01*
X2347713Y2785790D01*
X2346783Y2787040D01*
X2346163Y2788498D01*
X2345853Y2790165D01*
Y2791623D01*
X2346163Y2792873D01*
X2346783Y2794332D01*
X2347713Y2795582D01*
X2348643Y2796415D01*
X2349883Y2797040D01*
X2350968D01*
X2352208Y2796623D01*
X2353138Y2795790D01*
G01X2362283Y2797040D02*
Y2784540D01*
G01X2358718Y2797040D02*
X2365848D01*
G01X2371428Y2784540D02*
Y2797040D01*
G01X2377938D02*
Y2784540D01*
G01Y2790790D02*
X2371428D01*
G01X2073828Y2804956D02*
X2075068Y2803915D01*
X2076463Y2803290D01*
X2077703D01*
X2078943Y2803915D01*
X2079873Y2804956D01*
X2080338Y2806415D01*
X2080028Y2807873D01*
X2079253Y2809123D01*
X2077858Y2809957D01*
X2075998Y2810373D01*
X2074913Y2811207D01*
X2074448Y2812665D01*
X2074758Y2814123D01*
X2075533Y2815165D01*
X2076618Y2815790D01*
X2077703D01*
X2078788Y2815373D01*
X2079718Y2814332D01*
G01X2086073Y2815790D02*
Y2806832D01*
X2086693Y2804956D01*
X2087933Y2803707D01*
X2089483Y2803290D01*
X2091033Y2803707D01*
X2092273Y2804956D01*
X2092893Y2806832D01*
Y2815790D01*
G01X2098783Y2803290D02*
Y2815790D01*
X2102658D01*
X2103898Y2815165D01*
X2104673Y2814332D01*
X2104983Y2812665D01*
X2104673Y2810998D01*
X2103743Y2809957D01*
X2102658Y2809332D01*
X2098783D01*
G01X2102658D02*
X2104983Y2803290D01*
G01X2111338D02*
Y2815790D01*
X2117228D01*
G01X2115058Y2809748D02*
X2111338D01*
G01X2122808Y2803290D02*
X2126683Y2815790D01*
X2130558Y2803290D01*
G01X2129163Y2807665D02*
X2124203D01*
G01X2142493Y2814748D02*
X2141563Y2815373D01*
X2140478Y2815790D01*
X2139238D01*
X2137843Y2815165D01*
X2136758Y2814123D01*
X2135983Y2812873D01*
X2135363Y2810790D01*
X2135208Y2808915D01*
X2135518Y2807040D01*
X2135983Y2805790D01*
X2136913Y2804540D01*
X2137998Y2803707D01*
X2139083Y2803290D01*
X2140168D01*
X2141253Y2803707D01*
X2142183Y2804331D01*
X2142958Y2805165D01*
G01X2154583Y2803290D02*
X2148383D01*
Y2815790D01*
X2154583D01*
G01X2152103Y2809748D02*
X2148383D01*
G01X2176283Y2803290D02*
X2175043Y2803498D01*
X2173958Y2804331D01*
X2173028Y2805582D01*
X2172408Y2807040D01*
X2172098Y2808707D01*
Y2810373D01*
X2172408Y2812040D01*
X2173028Y2813498D01*
X2173958Y2814748D01*
X2175043Y2815582D01*
X2176283Y2815790D01*
X2177523Y2815582D01*
X2178608Y2814748D01*
X2179538Y2813498D01*
X2180158Y2812040D01*
X2180468Y2810373D01*
Y2808707D01*
X2180158Y2807040D01*
X2179538Y2805582D01*
X2178608Y2804331D01*
X2177523Y2803498D01*
X2176283Y2803290D01*
G01X2185738D02*
Y2815790D01*
X2191628D01*
G01X2189458Y2809748D02*
X2185738D01*
G01X2209453Y2803290D02*
Y2815790D01*
X2213483Y2805373D01*
X2217513Y2815790D01*
Y2803290D01*
G01X2222473Y2815790D02*
Y2806832D01*
X2223093Y2804956D01*
X2224333Y2803707D01*
X2225883Y2803290D01*
X2227433Y2803707D01*
X2228673Y2804956D01*
X2229293Y2806832D01*
Y2815790D01*
G01X2235028Y2804956D02*
X2236268Y2803915D01*
X2237663Y2803290D01*
X2238903D01*
X2240143Y2803915D01*
X2241073Y2804956D01*
X2241538Y2806415D01*
X2241228Y2807873D01*
X2240453Y2809123D01*
X2239058Y2809957D01*
X2237198Y2810373D01*
X2236113Y2811207D01*
X2235648Y2812665D01*
X2235958Y2814123D01*
X2236733Y2815165D01*
X2237818Y2815790D01*
X2238903D01*
X2239988Y2815373D01*
X2240918Y2814332D01*
G01X2250683Y2815790D02*
Y2803290D01*
G01X2247118Y2815790D02*
X2254248D01*
G01X2261068Y2807457D02*
X2265098D01*
G01X2271918Y2803290D02*
Y2815790D01*
X2279048Y2803290D01*
Y2815790D01*
G01X2287883Y2803290D02*
X2286643Y2803498D01*
X2285558Y2804331D01*
X2284628Y2805582D01*
X2284008Y2807040D01*
X2283698Y2808707D01*
Y2810373D01*
X2284008Y2812040D01*
X2284628Y2813498D01*
X2285558Y2814748D01*
X2286643Y2815582D01*
X2287883Y2815790D01*
X2289123Y2815582D01*
X2290208Y2814748D01*
X2291138Y2813498D01*
X2291758Y2812040D01*
X2292068Y2810373D01*
Y2808707D01*
X2291758Y2807040D01*
X2291138Y2805582D01*
X2290208Y2804331D01*
X2289123Y2803498D01*
X2287883Y2803290D01*
G01X2300283Y2815790D02*
Y2803290D01*
G01X2296718Y2815790D02*
X2303848D01*
G01X2310668Y2807457D02*
X2314698D01*
G01X2328493Y2814748D02*
X2327563Y2815373D01*
X2326478Y2815790D01*
X2325238D01*
X2323843Y2815165D01*
X2322758Y2814123D01*
X2321983Y2812873D01*
X2321363Y2810790D01*
X2321208Y2808915D01*
X2321518Y2807040D01*
X2321983Y2805790D01*
X2322913Y2804540D01*
X2323998Y2803707D01*
X2325083Y2803290D01*
X2326168D01*
X2327253Y2803707D01*
X2328183Y2804331D01*
X2328958Y2805165D01*
G01X2334073Y2815790D02*
Y2806832D01*
X2334693Y2804956D01*
X2335933Y2803707D01*
X2337483Y2803290D01*
X2339033Y2803707D01*
X2340273Y2804956D01*
X2340893Y2806832D01*
Y2815790D01*
G01X2349883D02*
Y2803290D01*
G01X2346318Y2815790D02*
X2353448D01*
G01X2360268Y2807457D02*
X2364298D01*
G01X2371583Y2815790D02*
Y2803290D01*
X2377783D01*
G01X2383208D02*
X2387083Y2815790D01*
X2390958Y2803290D01*
G01X2389563Y2807665D02*
X2384603D01*
G01X2399483Y2803290D02*
Y2808915D01*
X2396383Y2815790D01*
G01X2402583D02*
X2399483Y2808915D01*
G01X2414983Y2803290D02*
X2408783D01*
Y2815790D01*
X2414983D01*
G01X2412503Y2809748D02*
X2408783D01*
G01X2421183Y2803290D02*
Y2815790D01*
X2425058D01*
X2426298Y2815165D01*
X2427073Y2814332D01*
X2427383Y2812665D01*
X2427073Y2810998D01*
X2426143Y2809957D01*
X2425058Y2809332D01*
X2421183D01*
G01X2425058D02*
X2427383Y2803290D01*
G01X1913868Y2826207D02*
X1917898D01*
G01X1936653Y2822040D02*
Y2834540D01*
X1940683Y2824123D01*
X1944713Y2834540D01*
Y2822040D01*
G01X1949208D02*
X1953083Y2834540D01*
X1956958Y2822040D01*
G01X1955563Y2826415D02*
X1950603D01*
G01X1962228Y2822040D02*
X1968738Y2834540D01*
G01X1962228D02*
X1968738Y2822040D01*
G01X1973233Y2817873D02*
X1982533D01*
G01X1986873Y2822040D02*
Y2834540D01*
X1989973D01*
X1991213Y2833915D01*
X1992143Y2833082D01*
X1992918Y2831832D01*
X1993538Y2830373D01*
X1993693Y2828290D01*
X1993538Y2826207D01*
X1992918Y2824748D01*
X1992143Y2823498D01*
X1991213Y2822665D01*
X1989973Y2822040D01*
X1986873D01*
G01X2005783D02*
X1999583D01*
Y2834540D01*
X2005783D01*
G01X2003303Y2828498D02*
X1999583D01*
G01X2011983Y2822040D02*
Y2834540D01*
X2015703D01*
X2016943Y2833915D01*
X2017873Y2832457D01*
X2018183Y2830790D01*
X2017873Y2829123D01*
X2017098Y2827873D01*
X2015703Y2827248D01*
X2011983D01*
G01X2027483Y2834540D02*
Y2822040D01*
G01X2023918Y2834540D02*
X2031048D01*
G01X2036628Y2822040D02*
Y2834540D01*
G01X2043138D02*
Y2822040D01*
G01Y2828290D02*
X2036628D01*
G01X2052283Y2821623D02*
X2051973Y2821832D01*
Y2822248D01*
X2052283Y2822457D01*
X2052593Y2822248D01*
Y2821832D01*
X2052283Y2821623D01*
G01Y2827248D02*
X2051973Y2827457D01*
Y2827873D01*
X2052283Y2828082D01*
X2052593Y2827873D01*
Y2827457D01*
X2052283Y2827248D01*
G01X2073673Y2822040D02*
Y2834540D01*
X2076773D01*
X2078013Y2833915D01*
X2078943Y2833082D01*
X2079718Y2831832D01*
X2080338Y2830373D01*
X2080493Y2828290D01*
X2080338Y2826207D01*
X2079718Y2824748D01*
X2078943Y2823498D01*
X2078013Y2822665D01*
X2076773Y2822040D01*
X2073673D01*
G01X2092583D02*
X2086383D01*
Y2834540D01*
X2092583D01*
G01X2090103Y2828498D02*
X2086383D01*
G01X2098783Y2822040D02*
Y2834540D01*
X2102503D01*
X2103743Y2833915D01*
X2104673Y2832457D01*
X2104983Y2830790D01*
X2104673Y2829123D01*
X2103898Y2827873D01*
X2102503Y2827248D01*
X2098783D01*
G01X2114283Y2834540D02*
Y2822040D01*
G01X2110718Y2834540D02*
X2117848D01*
G01X2123428Y2822040D02*
Y2834540D01*
G01X2129938D02*
Y2822040D01*
G01Y2828290D02*
X2123428D01*
G01X2148538Y2822040D02*
Y2834540D01*
X2154428D01*
G01X2152258Y2828498D02*
X2148538D01*
G01X2160783Y2822040D02*
Y2834540D01*
X2164658D01*
X2165898Y2833915D01*
X2166673Y2833082D01*
X2166983Y2831415D01*
X2166673Y2829748D01*
X2165743Y2828707D01*
X2164658Y2828082D01*
X2160783D01*
G01X2164658D02*
X2166983Y2822040D01*
G01X2176283D02*
X2175043Y2822248D01*
X2173958Y2823081D01*
X2173028Y2824332D01*
X2172408Y2825790D01*
X2172098Y2827457D01*
Y2829123D01*
X2172408Y2830790D01*
X2173028Y2832248D01*
X2173958Y2833498D01*
X2175043Y2834332D01*
X2176283Y2834540D01*
X2177523Y2834332D01*
X2178608Y2833498D01*
X2179538Y2832248D01*
X2180158Y2830790D01*
X2180468Y2829123D01*
Y2827457D01*
X2180158Y2825790D01*
X2179538Y2824332D01*
X2178608Y2823081D01*
X2177523Y2822248D01*
X2176283Y2822040D01*
G01X2184653D02*
Y2834540D01*
X2188683Y2824123D01*
X2192713Y2834540D01*
Y2822040D01*
G01X2210228Y2823706D02*
X2211468Y2822665D01*
X2212863Y2822040D01*
X2214103D01*
X2215343Y2822665D01*
X2216273Y2823706D01*
X2216738Y2825165D01*
X2216428Y2826623D01*
X2215653Y2827873D01*
X2214258Y2828707D01*
X2212398Y2829123D01*
X2211313Y2829957D01*
X2210848Y2831415D01*
X2211158Y2832873D01*
X2211933Y2833915D01*
X2213018Y2834540D01*
X2214103D01*
X2215188Y2834123D01*
X2216118Y2833082D01*
G01X2225883Y2834540D02*
Y2822040D01*
G01X2222318Y2834540D02*
X2229448D01*
G01X2234408Y2822040D02*
X2238283Y2834540D01*
X2242158Y2822040D01*
G01X2240763Y2826415D02*
X2235803D01*
G01X2247583Y2822040D02*
Y2834540D01*
X2251458D01*
X2252698Y2833915D01*
X2253473Y2833082D01*
X2253783Y2831415D01*
X2253473Y2829748D01*
X2252543Y2828707D01*
X2251458Y2828082D01*
X2247583D01*
G01X2251458D02*
X2253783Y2822040D01*
G01X2263083Y2834540D02*
Y2822040D01*
G01X2259518Y2834540D02*
X2266648D01*
G01X2284783D02*
Y2822040D01*
X2290983D01*
G01X2296408D02*
X2300283Y2834540D01*
X2304158Y2822040D01*
G01X2302763Y2826415D02*
X2297803D01*
G01X2312683Y2822040D02*
Y2827665D01*
X2309583Y2834540D01*
G01X2315783D02*
X2312683Y2827665D01*
G01X2328183Y2822040D02*
X2321983D01*
Y2834540D01*
X2328183D01*
G01X2325703Y2828498D02*
X2321983D01*
G01X2334383Y2822040D02*
Y2834540D01*
X2338258D01*
X2339498Y2833915D01*
X2340273Y2833082D01*
X2340583Y2831415D01*
X2340273Y2829748D01*
X2339343Y2828707D01*
X2338258Y2828082D01*
X2334383D01*
G01X2338258D02*
X2340583Y2822040D01*
G01X2362283Y2834540D02*
Y2822040D01*
G01X2358718Y2834540D02*
X2365848D01*
G01X2374683Y2822040D02*
X2373443Y2822248D01*
X2372358Y2823081D01*
X2371428Y2824332D01*
X2370808Y2825790D01*
X2370498Y2827457D01*
Y2829123D01*
X2370808Y2830790D01*
X2371428Y2832248D01*
X2372358Y2833498D01*
X2373443Y2834332D01*
X2374683Y2834540D01*
X2375923Y2834332D01*
X2377008Y2833498D01*
X2377938Y2832248D01*
X2378558Y2830790D01*
X2378868Y2829123D01*
Y2827457D01*
X2378558Y2825790D01*
X2377938Y2824332D01*
X2377008Y2823081D01*
X2375923Y2822248D01*
X2374683Y2822040D01*
G01X2399483Y2834540D02*
Y2822040D01*
G01X2395918Y2834540D02*
X2403048D01*
G01X2408628Y2822040D02*
Y2834540D01*
G01X2415138D02*
Y2822040D01*
G01Y2828290D02*
X2408628D01*
G01X2427383Y2822040D02*
X2421183D01*
Y2834540D01*
X2427383D01*
G01X2424903Y2828498D02*
X2421183D01*
G01X1913868Y2844957D02*
X1917898D01*
G01X1936653Y2840790D02*
Y2853290D01*
X1940683Y2842873D01*
X1944713Y2853290D01*
Y2840790D01*
G01X1949518D02*
Y2853290D01*
X1956648Y2840790D01*
Y2853290D01*
G01X1968893Y2852248D02*
X1967963Y2852873D01*
X1966878Y2853290D01*
X1965638D01*
X1964243Y2852665D01*
X1963158Y2851623D01*
X1962383Y2850373D01*
X1961763Y2848290D01*
X1961608Y2846415D01*
X1961918Y2844540D01*
X1962383Y2843290D01*
X1963313Y2842040D01*
X1964398Y2841207D01*
X1965483Y2840790D01*
X1966568D01*
X1967653Y2841207D01*
X1968583Y2841831D01*
X1969358Y2842665D01*
G01X1973233Y2836623D02*
X1982533D01*
G01X1987183Y2853290D02*
Y2840790D01*
X1993383D01*
G01X1998808D02*
X2002683Y2853290D01*
X2006558Y2840790D01*
G01X2005163Y2845165D02*
X2000203D01*
G01X2015083Y2840790D02*
Y2846415D01*
X2011983Y2853290D01*
G01X2018183D02*
X2015083Y2846415D01*
G01X2030583Y2840790D02*
X2024383D01*
Y2853290D01*
X2030583D01*
G01X2028103Y2847248D02*
X2024383D01*
G01X2036783Y2840790D02*
Y2853290D01*
X2040658D01*
X2041898Y2852665D01*
X2042673Y2851832D01*
X2042983Y2850165D01*
X2042673Y2848498D01*
X2041743Y2847457D01*
X2040658Y2846832D01*
X2036783D01*
G01X2040658D02*
X2042983Y2840790D01*
G01X2052283Y2840373D02*
X2051973Y2840582D01*
Y2840998D01*
X2052283Y2841207D01*
X2052593Y2840998D01*
Y2840582D01*
X2052283Y2840373D01*
G01Y2845998D02*
X2051973Y2846207D01*
Y2846623D01*
X2052283Y2846832D01*
X2052593Y2846623D01*
Y2846207D01*
X2052283Y2845998D01*
G01X2073053Y2840790D02*
Y2853290D01*
X2077083Y2842873D01*
X2081113Y2853290D01*
Y2840790D01*
G01X2086073Y2853290D02*
Y2844332D01*
X2086693Y2842456D01*
X2087933Y2841207D01*
X2089483Y2840790D01*
X2091033Y2841207D01*
X2092273Y2842456D01*
X2092893Y2844332D01*
Y2853290D01*
G01X2098628Y2842456D02*
X2099868Y2841415D01*
X2101263Y2840790D01*
X2102503D01*
X2103743Y2841415D01*
X2104673Y2842456D01*
X2105138Y2843915D01*
X2104828Y2845373D01*
X2104053Y2846623D01*
X2102658Y2847457D01*
X2100798Y2847873D01*
X2099713Y2848707D01*
X2099248Y2850165D01*
X2099558Y2851623D01*
X2100333Y2852665D01*
X2101418Y2853290D01*
X2102503D01*
X2103588Y2852873D01*
X2104518Y2851832D01*
G01X2114283Y2853290D02*
Y2840790D01*
G01X2110718Y2853290D02*
X2117848D01*
G01X2124668Y2844957D02*
X2128698D01*
G01X2135518Y2840790D02*
Y2853290D01*
X2142648Y2840790D01*
Y2853290D01*
G01X2151483Y2840790D02*
X2150243Y2840998D01*
X2149158Y2841831D01*
X2148228Y2843082D01*
X2147608Y2844540D01*
X2147298Y2846207D01*
Y2847873D01*
X2147608Y2849540D01*
X2148228Y2850998D01*
X2149158Y2852248D01*
X2150243Y2853082D01*
X2151483Y2853290D01*
X2152723Y2853082D01*
X2153808Y2852248D01*
X2154738Y2850998D01*
X2155358Y2849540D01*
X2155668Y2847873D01*
Y2846207D01*
X2155358Y2844540D01*
X2154738Y2843082D01*
X2153808Y2841831D01*
X2152723Y2840998D01*
X2151483Y2840790D01*
G01X2163883Y2853290D02*
Y2840790D01*
G01X2160318Y2853290D02*
X2167448D01*
G01X2174268Y2844957D02*
X2178298D01*
G01X2192093Y2852248D02*
X2191163Y2852873D01*
X2190078Y2853290D01*
X2188838D01*
X2187443Y2852665D01*
X2186358Y2851623D01*
X2185583Y2850373D01*
X2184963Y2848290D01*
X2184808Y2846415D01*
X2185118Y2844540D01*
X2185583Y2843290D01*
X2186513Y2842040D01*
X2187598Y2841207D01*
X2188683Y2840790D01*
X2189768D01*
X2190853Y2841207D01*
X2191783Y2841831D01*
X2192558Y2842665D01*
G01X2197673Y2853290D02*
Y2844332D01*
X2198293Y2842456D01*
X2199533Y2841207D01*
X2201083Y2840790D01*
X2202633Y2841207D01*
X2203873Y2842456D01*
X2204493Y2844332D01*
Y2853290D01*
G01X2213483D02*
Y2840790D01*
G01X2209918Y2853290D02*
X2217048D01*
G01X2223868Y2844957D02*
X2227898D01*
G01X2235183Y2853290D02*
Y2840790D01*
X2241383D01*
G01X2246808D02*
X2250683Y2853290D01*
X2254558Y2840790D01*
G01X2253163Y2845165D02*
X2248203D01*
G01X2263083Y2840790D02*
Y2846415D01*
X2259983Y2853290D01*
G01X2266183D02*
X2263083Y2846415D01*
G01X2278583Y2840790D02*
X2272383D01*
Y2853290D01*
X2278583D01*
G01X2276103Y2847248D02*
X2272383D01*
G01X2284783Y2840790D02*
Y2853290D01*
X2288658D01*
X2289898Y2852665D01*
X2290673Y2851832D01*
X2290983Y2850165D01*
X2290673Y2848498D01*
X2289743Y2847457D01*
X2288658Y2846832D01*
X2284783D01*
G01X2288658D02*
X2290983Y2840790D01*
G01X1912318Y2859540D02*
Y2872040D01*
X1919448Y2859540D01*
Y2872040D01*
G01X1928283Y2859540D02*
X1927043Y2859748D01*
X1925958Y2860581D01*
X1925028Y2861832D01*
X1924408Y2863290D01*
X1924098Y2864957D01*
Y2866623D01*
X1924408Y2868290D01*
X1925028Y2869748D01*
X1925958Y2870998D01*
X1927043Y2871832D01*
X1928283Y2872040D01*
X1929523Y2871832D01*
X1930608Y2870998D01*
X1931538Y2869748D01*
X1932158Y2868290D01*
X1932468Y2866623D01*
Y2864957D01*
X1932158Y2863290D01*
X1931538Y2861832D01*
X1930608Y2860581D01*
X1929523Y2859748D01*
X1928283Y2859540D01*
G01X1940683Y2872040D02*
Y2859540D01*
G01X1937118Y2872040D02*
X1944248D01*
G01X1956183Y2859540D02*
X1949983D01*
Y2872040D01*
X1956183D01*
G01X1953703Y2865998D02*
X1949983D01*
G01X1962228Y2861206D02*
X1963468Y2860165D01*
X1964863Y2859540D01*
X1966103D01*
X1967343Y2860165D01*
X1968273Y2861206D01*
X1968738Y2862665D01*
X1968428Y2864123D01*
X1967653Y2865373D01*
X1966258Y2866207D01*
X1964398Y2866623D01*
X1963313Y2867457D01*
X1962848Y2868915D01*
X1963158Y2870373D01*
X1963933Y2871415D01*
X1965018Y2872040D01*
X1966103D01*
X1967188Y2871623D01*
X1968118Y2870582D01*
G01X1977883Y2859123D02*
X1977573Y2859332D01*
Y2859748D01*
X1977883Y2859957D01*
X1978193Y2859748D01*
Y2859332D01*
X1977883Y2859123D01*
G01Y2864748D02*
X1977573Y2864957D01*
Y2865373D01*
X1977883Y2865582D01*
X1978193Y2865373D01*
Y2864957D01*
X1977883Y2864748D01*
G01X2079570Y2988839D02*
X2080190Y2989464D01*
X2080655Y2990505D01*
X2080965Y2991964D01*
X2080655Y2993214D01*
X2080035Y2994047D01*
X2078950Y2994672D01*
X2074765D01*
Y2982172D01*
X2079880D01*
X2080965Y2983005D01*
X2081585Y2984255D01*
X2081895Y2985714D01*
X2081585Y2987172D01*
X2080655Y2988422D01*
X2079570Y2988839D01*
X2074765D01*
G01X2086855Y2982172D02*
X2090730Y2994672D01*
X2094605Y2982172D01*
G01X2093210Y2986547D02*
X2088250D01*
G01X2106540Y2993630D02*
X2105610Y2994255D01*
X2104525Y2994672D01*
X2103285D01*
X2101890Y2994047D01*
X2100805Y2993005D01*
X2100030Y2991755D01*
X2099410Y2989672D01*
X2099255Y2987797D01*
X2099565Y2985922D01*
X2100030Y2984672D01*
X2100960Y2983422D01*
X2102045Y2982589D01*
X2103130Y2982172D01*
X2104215D01*
X2105300Y2982589D01*
X2106230Y2983213D01*
X2107005Y2984047D01*
G01X2112120Y2982172D02*
Y2994672D01*
G01X2118010D02*
X2112120Y2986963D01*
G01X2118940Y2982172D02*
X2114755Y2990505D01*
G01X2124520Y2982172D02*
Y2994672D01*
X2127620D01*
X2128860Y2994047D01*
X2129790Y2993214D01*
X2130565Y2991964D01*
X2131185Y2990505D01*
X2131340Y2988422D01*
X2131185Y2986339D01*
X2130565Y2984880D01*
X2129790Y2983630D01*
X2128860Y2982797D01*
X2127620Y2982172D01*
X2124520D01*
G01X2137230D02*
Y2994672D01*
X2141105D01*
X2142345Y2994047D01*
X2143120Y2993214D01*
X2143430Y2991547D01*
X2143120Y2989880D01*
X2142190Y2988839D01*
X2141105Y2988214D01*
X2137230D01*
G01X2141105D02*
X2143430Y2982172D01*
G01X2150870Y2994672D02*
X2154590D01*
G01X2152730D02*
Y2982172D01*
G01X2150870D02*
X2154590D01*
G01X2162030Y2994672D02*
Y2982172D01*
X2168230D01*
G01X2174430Y2994672D02*
Y2982172D01*
X2180630D01*
G01X2199075Y2983838D02*
X2200315Y2982797D01*
X2201710Y2982172D01*
X2202950D01*
X2204190Y2982797D01*
X2205120Y2983838D01*
X2205585Y2985297D01*
X2205275Y2986755D01*
X2204500Y2988005D01*
X2203105Y2988839D01*
X2201245Y2989255D01*
X2200160Y2990089D01*
X2199695Y2991547D01*
X2200005Y2993005D01*
X2200780Y2994047D01*
X2201865Y2994672D01*
X2202950D01*
X2204035Y2994255D01*
X2204965Y2993214D01*
G01X2214730Y2994672D02*
Y2982172D01*
G01X2211165Y2994672D02*
X2218295D01*
G01X2223720D02*
Y2985714D01*
X2224340Y2983838D01*
X2225580Y2982589D01*
X2227130Y2982172D01*
X2228680Y2982589D01*
X2229920Y2983838D01*
X2230540Y2985714D01*
Y2994672D01*
G01X2240770Y2988839D02*
X2241390Y2989464D01*
X2241855Y2990505D01*
X2242165Y2991964D01*
X2241855Y2993214D01*
X2241235Y2994047D01*
X2240150Y2994672D01*
X2235965D01*
Y2982172D01*
X2241080D01*
X2242165Y2983005D01*
X2242785Y2984255D01*
X2243095Y2985714D01*
X2242785Y2987172D01*
X2241855Y2988422D01*
X2240770Y2988839D01*
X2235965D01*
G01X2261230Y2994672D02*
Y2982172D01*
X2267430D01*
G01X2279830D02*
X2273630D01*
Y2994672D01*
X2279830D01*
G01X2277350Y2988630D02*
X2273630D01*
G01X2285565Y2982172D02*
Y2994672D01*
X2292695Y2982172D01*
Y2994672D01*
G01X2302460Y2988422D02*
X2305560D01*
Y2984672D01*
X2304630Y2983422D01*
X2303545Y2982589D01*
X2301995Y2982172D01*
X2300445Y2982589D01*
X2299360Y2983422D01*
X2298430Y2984672D01*
X2297810Y2986130D01*
X2297500Y2987797D01*
Y2989255D01*
X2297810Y2990505D01*
X2298430Y2991964D01*
X2299360Y2993214D01*
X2300290Y2994047D01*
X2301530Y2994672D01*
X2302615D01*
X2303855Y2994255D01*
X2304785Y2993422D01*
G01X2313930Y2994672D02*
Y2982172D01*
G01X2310365Y2994672D02*
X2317495D01*
G01X2323075Y2982172D02*
Y2994672D01*
G01X2329585D02*
Y2982172D01*
G01Y2988422D02*
X2323075D01*
G01X2351130Y2994672D02*
Y2982172D01*
G01X2347565Y2994672D02*
X2354695D01*
G01X2363530Y2982172D02*
X2362290Y2982380D01*
X2361205Y2983213D01*
X2360275Y2984464D01*
X2359655Y2985922D01*
X2359345Y2987589D01*
Y2989255D01*
X2359655Y2990922D01*
X2360275Y2992380D01*
X2361205Y2993630D01*
X2362290Y2994464D01*
X2363530Y2994672D01*
X2364770Y2994464D01*
X2365855Y2993630D01*
X2366785Y2992380D01*
X2367405Y2990922D01*
X2367715Y2989255D01*
Y2987589D01*
X2367405Y2985922D01*
X2366785Y2984464D01*
X2365855Y2983213D01*
X2364770Y2982380D01*
X2363530Y2982172D01*
G01X2372830Y2994672D02*
Y2982172D01*
X2379030D01*
G01X2391430D02*
X2385230D01*
Y2994672D01*
X2391430D01*
G01X2388950Y2988630D02*
X2385230D01*
G01X2397630Y2982172D02*
Y2994672D01*
X2401505D01*
X2402745Y2994047D01*
X2403520Y2993214D01*
X2403830Y2991547D01*
X2403520Y2989880D01*
X2402590Y2988839D01*
X2401505Y2988214D01*
X2397630D01*
G01X2401505D02*
X2403830Y2982172D01*
G01X2409255D02*
X2413130Y2994672D01*
X2417005Y2982172D01*
G01X2415610Y2986547D02*
X2410650D01*
G01X2421965Y2982172D02*
Y2994672D01*
X2429095Y2982172D01*
Y2994672D01*
G01X2441340Y2993630D02*
X2440410Y2994255D01*
X2439325Y2994672D01*
X2438085D01*
X2436690Y2994047D01*
X2435605Y2993005D01*
X2434830Y2991755D01*
X2434210Y2989672D01*
X2434055Y2987797D01*
X2434365Y2985922D01*
X2434830Y2984672D01*
X2435760Y2983422D01*
X2436845Y2982589D01*
X2437930Y2982172D01*
X2439015D01*
X2440100Y2982589D01*
X2441030Y2983213D01*
X2441805Y2984047D01*
G01X2453430Y2982172D02*
X2447230D01*
Y2994672D01*
X2453430D01*
G01X2450950Y2988630D02*
X2447230D01*
G01X2475130Y2994672D02*
Y2982172D01*
G01X2471565Y2994672D02*
X2478695D01*
G01X2487530Y2982172D02*
X2486290Y2982380D01*
X2485205Y2983213D01*
X2484275Y2984464D01*
X2483655Y2985922D01*
X2483345Y2987589D01*
Y2989255D01*
X2483655Y2990922D01*
X2484275Y2992380D01*
X2485205Y2993630D01*
X2486290Y2994464D01*
X2487530Y2994672D01*
X2488770Y2994464D01*
X2489855Y2993630D01*
X2490785Y2992380D01*
X2491405Y2990922D01*
X2491715Y2989255D01*
Y2987589D01*
X2491405Y2985922D01*
X2490785Y2984464D01*
X2489855Y2983213D01*
X2488770Y2982380D01*
X2487530Y2982172D01*
G01X2513570Y2988839D02*
X2514190Y2989464D01*
X2514655Y2990505D01*
X2514965Y2991964D01*
X2514655Y2993214D01*
X2514035Y2994047D01*
X2512950Y2994672D01*
X2508765D01*
Y2982172D01*
X2513880D01*
X2514965Y2983005D01*
X2515585Y2984255D01*
X2515895Y2985714D01*
X2515585Y2987172D01*
X2514655Y2988422D01*
X2513570Y2988839D01*
X2508765D01*
G01X2527830Y2982172D02*
X2521630D01*
Y2994672D01*
X2527830D01*
G01X2525350Y2988630D02*
X2521630D01*
G01X2549220Y2982172D02*
X2549530Y2984880D01*
X2549995Y2987172D01*
X2550615Y2989255D01*
X2551390Y2991547D01*
X2552630Y2994672D01*
X2546430D01*
G01X2572625Y2986339D02*
X2576345D01*
G01X2574330Y2989047D02*
Y2983630D01*
G01X2583940Y2981755D02*
X2589520Y2994672D01*
G01X2597115Y2986339D02*
X2601145D01*
G01X2608120Y2984047D02*
X2609050Y2983005D01*
X2610135Y2982380D01*
X2611530Y2982172D01*
X2612925Y2982589D01*
X2614010Y2983422D01*
X2614785Y2984880D01*
X2614940Y2986547D01*
X2614630Y2988214D01*
X2613855Y2989255D01*
X2612770Y2990089D01*
X2611685Y2990297D01*
X2610600Y2990089D01*
X2609205Y2989255D01*
X2609670Y2994672D01*
X2613855D01*
G01X2632300Y2982172D02*
Y2994672D01*
X2636330Y2984255D01*
X2640360Y2994672D01*
Y2982172D01*
G01X2646870Y2994672D02*
X2650590D01*
G01X2648730D02*
Y2982172D01*
G01X2646870D02*
X2650590D01*
G01X2658030Y2994672D02*
Y2982172D01*
X2664230D01*
G01X2670275Y2983838D02*
X2671515Y2982797D01*
X2672910Y2982172D01*
X2674150D01*
X2675390Y2982797D01*
X2676320Y2983838D01*
X2676785Y2985297D01*
X2676475Y2986755D01*
X2675700Y2988005D01*
X2674305Y2988839D01*
X2672445Y2989255D01*
X2671360Y2990089D01*
X2670895Y2991547D01*
X2671205Y2993005D01*
X2671980Y2994047D01*
X2673065Y2994672D01*
X2674150D01*
X2675235Y2994255D01*
X2676165Y2993214D01*
G01X1915115Y3005089D02*
X1919145D01*
G01X1937900Y3000922D02*
Y3013422D01*
X1941930Y3003005D01*
X1945960Y3013422D01*
Y3000922D01*
G01X1951385D02*
Y3013422D01*
X1957275D01*
G01X1955105Y3007380D02*
X1951385D01*
G01X1967660Y3007172D02*
X1970760D01*
Y3003422D01*
X1969830Y3002172D01*
X1968745Y3001339D01*
X1967195Y3000922D01*
X1965645Y3001339D01*
X1964560Y3002172D01*
X1963630Y3003422D01*
X1963010Y3004880D01*
X1962700Y3006547D01*
Y3008005D01*
X1963010Y3009255D01*
X1963630Y3010714D01*
X1964560Y3011964D01*
X1965490Y3012797D01*
X1966730Y3013422D01*
X1967815D01*
X1969055Y3013005D01*
X1969985Y3012172D01*
G01X1974480Y2996755D02*
X1983780D01*
G01X1988275Y3002588D02*
X1989515Y3001547D01*
X1990910Y3000922D01*
X1992150D01*
X1993390Y3001547D01*
X1994320Y3002588D01*
X1994785Y3004047D01*
X1994475Y3005505D01*
X1993700Y3006755D01*
X1992305Y3007589D01*
X1990445Y3008005D01*
X1989360Y3008839D01*
X1988895Y3010297D01*
X1989205Y3011755D01*
X1989980Y3012797D01*
X1991065Y3013422D01*
X1992150D01*
X1993235Y3013005D01*
X1994165Y3011964D01*
G01X2003930Y3013422D02*
Y3000922D01*
G01X2000365Y3013422D02*
X2007495D01*
G01X2012920D02*
Y3004464D01*
X2013540Y3002588D01*
X2014780Y3001339D01*
X2016330Y3000922D01*
X2017880Y3001339D01*
X2019120Y3002588D01*
X2019740Y3004464D01*
Y3013422D01*
G01X2029970Y3007589D02*
X2030590Y3008214D01*
X2031055Y3009255D01*
X2031365Y3010714D01*
X2031055Y3011964D01*
X2030435Y3012797D01*
X2029350Y3013422D01*
X2025165D01*
Y3000922D01*
X2030280D01*
X2031365Y3001755D01*
X2031985Y3003005D01*
X2032295Y3004464D01*
X2031985Y3005922D01*
X2031055Y3007172D01*
X2029970Y3007589D01*
X2025165D01*
G01X2053530Y3000505D02*
X2053220Y3000714D01*
Y3001130D01*
X2053530Y3001339D01*
X2053840Y3001130D01*
Y3000714D01*
X2053530Y3000505D01*
G01Y3006130D02*
X2053220Y3006339D01*
Y3006755D01*
X2053530Y3006964D01*
X2053840Y3006755D01*
Y3006339D01*
X2053530Y3006130D01*
G01X2074300Y3000922D02*
Y3013422D01*
X2078330Y3003005D01*
X2082360Y3013422D01*
Y3000922D01*
G01X2086855D02*
X2090730Y3013422D01*
X2094605Y3000922D01*
G01X2093210Y3005297D02*
X2088250D01*
G01X2099565Y3000922D02*
Y3013422D01*
X2106695Y3000922D01*
Y3013422D01*
G01X2112120D02*
Y3004464D01*
X2112740Y3002588D01*
X2113980Y3001339D01*
X2115530Y3000922D01*
X2117080Y3001339D01*
X2118320Y3002588D01*
X2118940Y3004464D01*
Y3013422D01*
G01X2124985Y3000922D02*
Y3013422D01*
X2130875D01*
G01X2128705Y3007380D02*
X2124985D01*
G01X2136455Y3000922D02*
X2140330Y3013422D01*
X2144205Y3000922D01*
G01X2142810Y3005297D02*
X2137850D01*
G01X2156140Y3012380D02*
X2155210Y3013005D01*
X2154125Y3013422D01*
X2152885D01*
X2151490Y3012797D01*
X2150405Y3011755D01*
X2149630Y3010505D01*
X2149010Y3008422D01*
X2148855Y3006547D01*
X2149165Y3004672D01*
X2149630Y3003422D01*
X2150560Y3002172D01*
X2151645Y3001339D01*
X2152730Y3000922D01*
X2153815D01*
X2154900Y3001339D01*
X2155830Y3001963D01*
X2156605Y3002797D01*
G01X2165130Y3013422D02*
Y3000922D01*
G01X2161565Y3013422D02*
X2168695D01*
G01X2174120D02*
Y3004464D01*
X2174740Y3002588D01*
X2175980Y3001339D01*
X2177530Y3000922D01*
X2179080Y3001339D01*
X2180320Y3002588D01*
X2180940Y3004464D01*
Y3013422D01*
G01X2186830Y3000922D02*
Y3013422D01*
X2190705D01*
X2191945Y3012797D01*
X2192720Y3011964D01*
X2193030Y3010297D01*
X2192720Y3008630D01*
X2191790Y3007589D01*
X2190705Y3006964D01*
X2186830D01*
G01X2190705D02*
X2193030Y3000922D01*
G01X2200470Y3013422D02*
X2204190D01*
G01X2202330D02*
Y3000922D01*
G01X2200470D02*
X2204190D01*
G01X2211165D02*
Y3013422D01*
X2218295Y3000922D01*
Y3013422D01*
G01X2228060Y3007172D02*
X2231160D01*
Y3003422D01*
X2230230Y3002172D01*
X2229145Y3001339D01*
X2227595Y3000922D01*
X2226045Y3001339D01*
X2224960Y3002172D01*
X2224030Y3003422D01*
X2223410Y3004880D01*
X2223100Y3006547D01*
Y3008005D01*
X2223410Y3009255D01*
X2224030Y3010714D01*
X2224960Y3011964D01*
X2225890Y3012797D01*
X2227130Y3013422D01*
X2228215D01*
X2229455Y3013005D01*
X2230385Y3012172D01*
G01X2248675Y3002588D02*
X2249915Y3001547D01*
X2251310Y3000922D01*
X2252550D01*
X2253790Y3001547D01*
X2254720Y3002588D01*
X2255185Y3004047D01*
X2254875Y3005505D01*
X2254100Y3006755D01*
X2252705Y3007589D01*
X2250845Y3008005D01*
X2249760Y3008839D01*
X2249295Y3010297D01*
X2249605Y3011755D01*
X2250380Y3012797D01*
X2251465Y3013422D01*
X2252550D01*
X2253635Y3013005D01*
X2254565Y3011964D01*
G01X2264330Y3013422D02*
Y3000922D01*
G01X2260765Y3013422D02*
X2267895D01*
G01X2273320D02*
Y3004464D01*
X2273940Y3002588D01*
X2275180Y3001339D01*
X2276730Y3000922D01*
X2278280Y3001339D01*
X2279520Y3002588D01*
X2280140Y3004464D01*
Y3013422D01*
G01X2290370Y3007589D02*
X2290990Y3008214D01*
X2291455Y3009255D01*
X2291765Y3010714D01*
X2291455Y3011964D01*
X2290835Y3012797D01*
X2289750Y3013422D01*
X2285565D01*
Y3000922D01*
X2290680D01*
X2291765Y3001755D01*
X2292385Y3003005D01*
X2292695Y3004464D01*
X2292385Y3005922D01*
X2291455Y3007172D01*
X2290370Y3007589D01*
X2285565D01*
G01X2310830Y3013422D02*
Y3000922D01*
X2317030D01*
G01X2329430D02*
X2323230D01*
Y3013422D01*
X2329430D01*
G01X2326950Y3007380D02*
X2323230D01*
G01X2335165Y3000922D02*
Y3013422D01*
X2342295Y3000922D01*
Y3013422D01*
G01X2352060Y3007172D02*
X2355160D01*
Y3003422D01*
X2354230Y3002172D01*
X2353145Y3001339D01*
X2351595Y3000922D01*
X2350045Y3001339D01*
X2348960Y3002172D01*
X2348030Y3003422D01*
X2347410Y3004880D01*
X2347100Y3006547D01*
Y3008005D01*
X2347410Y3009255D01*
X2348030Y3010714D01*
X2348960Y3011964D01*
X2349890Y3012797D01*
X2351130Y3013422D01*
X2352215D01*
X2353455Y3013005D01*
X2354385Y3012172D01*
G01X2363530Y3013422D02*
Y3000922D01*
G01X2359965Y3013422D02*
X2367095D01*
G01X2372675Y3000922D02*
Y3013422D01*
G01X2379185D02*
Y3000922D01*
G01Y3007172D02*
X2372675D01*
G01X2075075Y3021338D02*
X2076315Y3020297D01*
X2077710Y3019672D01*
X2078950D01*
X2080190Y3020297D01*
X2081120Y3021338D01*
X2081585Y3022797D01*
X2081275Y3024255D01*
X2080500Y3025505D01*
X2079105Y3026339D01*
X2077245Y3026755D01*
X2076160Y3027589D01*
X2075695Y3029047D01*
X2076005Y3030505D01*
X2076780Y3031547D01*
X2077865Y3032172D01*
X2078950D01*
X2080035Y3031755D01*
X2080965Y3030714D01*
G01X2087320Y3032172D02*
Y3023214D01*
X2087940Y3021338D01*
X2089180Y3020089D01*
X2090730Y3019672D01*
X2092280Y3020089D01*
X2093520Y3021338D01*
X2094140Y3023214D01*
Y3032172D01*
G01X2100030Y3019672D02*
Y3032172D01*
X2103905D01*
X2105145Y3031547D01*
X2105920Y3030714D01*
X2106230Y3029047D01*
X2105920Y3027380D01*
X2104990Y3026339D01*
X2103905Y3025714D01*
X2100030D01*
G01X2103905D02*
X2106230Y3019672D01*
G01X2112585D02*
Y3032172D01*
X2118475D01*
G01X2116305Y3026130D02*
X2112585D01*
G01X2124055Y3019672D02*
X2127930Y3032172D01*
X2131805Y3019672D01*
G01X2130410Y3024047D02*
X2125450D01*
G01X2143740Y3031130D02*
X2142810Y3031755D01*
X2141725Y3032172D01*
X2140485D01*
X2139090Y3031547D01*
X2138005Y3030505D01*
X2137230Y3029255D01*
X2136610Y3027172D01*
X2136455Y3025297D01*
X2136765Y3023422D01*
X2137230Y3022172D01*
X2138160Y3020922D01*
X2139245Y3020089D01*
X2140330Y3019672D01*
X2141415D01*
X2142500Y3020089D01*
X2143430Y3020713D01*
X2144205Y3021547D01*
G01X2155830Y3019672D02*
X2149630D01*
Y3032172D01*
X2155830D01*
G01X2153350Y3026130D02*
X2149630D01*
G01X2177530Y3019672D02*
X2176290Y3019880D01*
X2175205Y3020713D01*
X2174275Y3021964D01*
X2173655Y3023422D01*
X2173345Y3025089D01*
Y3026755D01*
X2173655Y3028422D01*
X2174275Y3029880D01*
X2175205Y3031130D01*
X2176290Y3031964D01*
X2177530Y3032172D01*
X2178770Y3031964D01*
X2179855Y3031130D01*
X2180785Y3029880D01*
X2181405Y3028422D01*
X2181715Y3026755D01*
Y3025089D01*
X2181405Y3023422D01*
X2180785Y3021964D01*
X2179855Y3020713D01*
X2178770Y3019880D01*
X2177530Y3019672D01*
G01X2186985D02*
Y3032172D01*
X2192875D01*
G01X2190705Y3026130D02*
X2186985D01*
G01X2210700Y3019672D02*
Y3032172D01*
X2214730Y3021755D01*
X2218760Y3032172D01*
Y3019672D01*
G01X2223720Y3032172D02*
Y3023214D01*
X2224340Y3021338D01*
X2225580Y3020089D01*
X2227130Y3019672D01*
X2228680Y3020089D01*
X2229920Y3021338D01*
X2230540Y3023214D01*
Y3032172D01*
G01X2236275Y3021338D02*
X2237515Y3020297D01*
X2238910Y3019672D01*
X2240150D01*
X2241390Y3020297D01*
X2242320Y3021338D01*
X2242785Y3022797D01*
X2242475Y3024255D01*
X2241700Y3025505D01*
X2240305Y3026339D01*
X2238445Y3026755D01*
X2237360Y3027589D01*
X2236895Y3029047D01*
X2237205Y3030505D01*
X2237980Y3031547D01*
X2239065Y3032172D01*
X2240150D01*
X2241235Y3031755D01*
X2242165Y3030714D01*
G01X2251930Y3032172D02*
Y3019672D01*
G01X2248365Y3032172D02*
X2255495D01*
G01X2262315Y3023839D02*
X2266345D01*
G01X2273165Y3019672D02*
Y3032172D01*
X2280295Y3019672D01*
Y3032172D01*
G01X2289130Y3019672D02*
X2287890Y3019880D01*
X2286805Y3020713D01*
X2285875Y3021964D01*
X2285255Y3023422D01*
X2284945Y3025089D01*
Y3026755D01*
X2285255Y3028422D01*
X2285875Y3029880D01*
X2286805Y3031130D01*
X2287890Y3031964D01*
X2289130Y3032172D01*
X2290370Y3031964D01*
X2291455Y3031130D01*
X2292385Y3029880D01*
X2293005Y3028422D01*
X2293315Y3026755D01*
Y3025089D01*
X2293005Y3023422D01*
X2292385Y3021964D01*
X2291455Y3020713D01*
X2290370Y3019880D01*
X2289130Y3019672D01*
G01X2301530Y3032172D02*
Y3019672D01*
G01X2297965Y3032172D02*
X2305095D01*
G01X2311915Y3023839D02*
X2315945D01*
G01X2329740Y3031130D02*
X2328810Y3031755D01*
X2327725Y3032172D01*
X2326485D01*
X2325090Y3031547D01*
X2324005Y3030505D01*
X2323230Y3029255D01*
X2322610Y3027172D01*
X2322455Y3025297D01*
X2322765Y3023422D01*
X2323230Y3022172D01*
X2324160Y3020922D01*
X2325245Y3020089D01*
X2326330Y3019672D01*
X2327415D01*
X2328500Y3020089D01*
X2329430Y3020713D01*
X2330205Y3021547D01*
G01X2335320Y3032172D02*
Y3023214D01*
X2335940Y3021338D01*
X2337180Y3020089D01*
X2338730Y3019672D01*
X2340280Y3020089D01*
X2341520Y3021338D01*
X2342140Y3023214D01*
Y3032172D01*
G01X2351130D02*
Y3019672D01*
G01X2347565Y3032172D02*
X2354695D01*
G01X2361515Y3023839D02*
X2365545D01*
G01X2372830Y3032172D02*
Y3019672D01*
X2379030D01*
G01X2384455D02*
X2388330Y3032172D01*
X2392205Y3019672D01*
G01X2390810Y3024047D02*
X2385850D01*
G01X2400730Y3019672D02*
Y3025297D01*
X2397630Y3032172D01*
G01X2403830D02*
X2400730Y3025297D01*
G01X2416230Y3019672D02*
X2410030D01*
Y3032172D01*
X2416230D01*
G01X2413750Y3026130D02*
X2410030D01*
G01X2422430Y3019672D02*
Y3032172D01*
X2426305D01*
X2427545Y3031547D01*
X2428320Y3030714D01*
X2428630Y3029047D01*
X2428320Y3027380D01*
X2427390Y3026339D01*
X2426305Y3025714D01*
X2422430D01*
G01X2426305D02*
X2428630Y3019672D01*
G01X1915115Y3042589D02*
X1919145D01*
G01X1937900Y3038422D02*
Y3050922D01*
X1941930Y3040505D01*
X1945960Y3050922D01*
Y3038422D01*
G01X1950455D02*
X1954330Y3050922D01*
X1958205Y3038422D01*
G01X1956810Y3042797D02*
X1951850D01*
G01X1963475Y3038422D02*
X1969985Y3050922D01*
G01X1963475D02*
X1969985Y3038422D01*
G01X1974480Y3034255D02*
X1983780D01*
G01X1988120Y3038422D02*
Y3050922D01*
X1991220D01*
X1992460Y3050297D01*
X1993390Y3049464D01*
X1994165Y3048214D01*
X1994785Y3046755D01*
X1994940Y3044672D01*
X1994785Y3042589D01*
X1994165Y3041130D01*
X1993390Y3039880D01*
X1992460Y3039047D01*
X1991220Y3038422D01*
X1988120D01*
G01X2007030D02*
X2000830D01*
Y3050922D01*
X2007030D01*
G01X2004550Y3044880D02*
X2000830D01*
G01X2013230Y3038422D02*
Y3050922D01*
X2016950D01*
X2018190Y3050297D01*
X2019120Y3048839D01*
X2019430Y3047172D01*
X2019120Y3045505D01*
X2018345Y3044255D01*
X2016950Y3043630D01*
X2013230D01*
G01X2028730Y3050922D02*
Y3038422D01*
G01X2025165Y3050922D02*
X2032295D01*
G01X2037875Y3038422D02*
Y3050922D01*
G01X2044385D02*
Y3038422D01*
G01Y3044672D02*
X2037875D01*
G01X2053530Y3038005D02*
X2053220Y3038214D01*
Y3038630D01*
X2053530Y3038839D01*
X2053840Y3038630D01*
Y3038214D01*
X2053530Y3038005D01*
G01Y3043630D02*
X2053220Y3043839D01*
Y3044255D01*
X2053530Y3044464D01*
X2053840Y3044255D01*
Y3043839D01*
X2053530Y3043630D01*
G01X2074920Y3038422D02*
Y3050922D01*
X2078020D01*
X2079260Y3050297D01*
X2080190Y3049464D01*
X2080965Y3048214D01*
X2081585Y3046755D01*
X2081740Y3044672D01*
X2081585Y3042589D01*
X2080965Y3041130D01*
X2080190Y3039880D01*
X2079260Y3039047D01*
X2078020Y3038422D01*
X2074920D01*
G01X2093830D02*
X2087630D01*
Y3050922D01*
X2093830D01*
G01X2091350Y3044880D02*
X2087630D01*
G01X2100030Y3038422D02*
Y3050922D01*
X2103750D01*
X2104990Y3050297D01*
X2105920Y3048839D01*
X2106230Y3047172D01*
X2105920Y3045505D01*
X2105145Y3044255D01*
X2103750Y3043630D01*
X2100030D01*
G01X2115530Y3050922D02*
Y3038422D01*
G01X2111965Y3050922D02*
X2119095D01*
G01X2124675Y3038422D02*
Y3050922D01*
G01X2131185D02*
Y3038422D01*
G01Y3044672D02*
X2124675D01*
G01X2149785Y3038422D02*
Y3050922D01*
X2155675D01*
G01X2153505Y3044880D02*
X2149785D01*
G01X2162030Y3038422D02*
Y3050922D01*
X2165905D01*
X2167145Y3050297D01*
X2167920Y3049464D01*
X2168230Y3047797D01*
X2167920Y3046130D01*
X2166990Y3045089D01*
X2165905Y3044464D01*
X2162030D01*
G01X2165905D02*
X2168230Y3038422D01*
G01X2177530D02*
X2176290Y3038630D01*
X2175205Y3039463D01*
X2174275Y3040714D01*
X2173655Y3042172D01*
X2173345Y3043839D01*
Y3045505D01*
X2173655Y3047172D01*
X2174275Y3048630D01*
X2175205Y3049880D01*
X2176290Y3050714D01*
X2177530Y3050922D01*
X2178770Y3050714D01*
X2179855Y3049880D01*
X2180785Y3048630D01*
X2181405Y3047172D01*
X2181715Y3045505D01*
Y3043839D01*
X2181405Y3042172D01*
X2180785Y3040714D01*
X2179855Y3039463D01*
X2178770Y3038630D01*
X2177530Y3038422D01*
G01X2185900D02*
Y3050922D01*
X2189930Y3040505D01*
X2193960Y3050922D01*
Y3038422D01*
G01X2211475Y3040088D02*
X2212715Y3039047D01*
X2214110Y3038422D01*
X2215350D01*
X2216590Y3039047D01*
X2217520Y3040088D01*
X2217985Y3041547D01*
X2217675Y3043005D01*
X2216900Y3044255D01*
X2215505Y3045089D01*
X2213645Y3045505D01*
X2212560Y3046339D01*
X2212095Y3047797D01*
X2212405Y3049255D01*
X2213180Y3050297D01*
X2214265Y3050922D01*
X2215350D01*
X2216435Y3050505D01*
X2217365Y3049464D01*
G01X2227130Y3050922D02*
Y3038422D01*
G01X2223565Y3050922D02*
X2230695D01*
G01X2235655Y3038422D02*
X2239530Y3050922D01*
X2243405Y3038422D01*
G01X2242010Y3042797D02*
X2237050D01*
G01X2248830Y3038422D02*
Y3050922D01*
X2252705D01*
X2253945Y3050297D01*
X2254720Y3049464D01*
X2255030Y3047797D01*
X2254720Y3046130D01*
X2253790Y3045089D01*
X2252705Y3044464D01*
X2248830D01*
G01X2252705D02*
X2255030Y3038422D01*
G01X2264330Y3050922D02*
Y3038422D01*
G01X2260765Y3050922D02*
X2267895D01*
G01X2286030D02*
Y3038422D01*
X2292230D01*
G01X2297655D02*
X2301530Y3050922D01*
X2305405Y3038422D01*
G01X2304010Y3042797D02*
X2299050D01*
G01X2313930Y3038422D02*
Y3044047D01*
X2310830Y3050922D01*
G01X2317030D02*
X2313930Y3044047D01*
G01X2329430Y3038422D02*
X2323230D01*
Y3050922D01*
X2329430D01*
G01X2326950Y3044880D02*
X2323230D01*
G01X2335630Y3038422D02*
Y3050922D01*
X2339505D01*
X2340745Y3050297D01*
X2341520Y3049464D01*
X2341830Y3047797D01*
X2341520Y3046130D01*
X2340590Y3045089D01*
X2339505Y3044464D01*
X2335630D01*
G01X2339505D02*
X2341830Y3038422D01*
G01X2363530Y3050922D02*
Y3038422D01*
G01X2359965Y3050922D02*
X2367095D01*
G01X2375930Y3038422D02*
X2374690Y3038630D01*
X2373605Y3039463D01*
X2372675Y3040714D01*
X2372055Y3042172D01*
X2371745Y3043839D01*
Y3045505D01*
X2372055Y3047172D01*
X2372675Y3048630D01*
X2373605Y3049880D01*
X2374690Y3050714D01*
X2375930Y3050922D01*
X2377170Y3050714D01*
X2378255Y3049880D01*
X2379185Y3048630D01*
X2379805Y3047172D01*
X2380115Y3045505D01*
Y3043839D01*
X2379805Y3042172D01*
X2379185Y3040714D01*
X2378255Y3039463D01*
X2377170Y3038630D01*
X2375930Y3038422D01*
G01X2400730Y3050922D02*
Y3038422D01*
G01X2397165Y3050922D02*
X2404295D01*
G01X2409875Y3038422D02*
Y3050922D01*
G01X2416385D02*
Y3038422D01*
G01Y3044672D02*
X2409875D01*
G01X2428630Y3038422D02*
X2422430D01*
Y3050922D01*
X2428630D01*
G01X2426150Y3044880D02*
X2422430D01*
G01X1915115Y3061339D02*
X1919145D01*
G01X1937900Y3057172D02*
Y3069672D01*
X1941930Y3059255D01*
X1945960Y3069672D01*
Y3057172D01*
G01X1950765D02*
Y3069672D01*
X1957895Y3057172D01*
Y3069672D01*
G01X1970140Y3068630D02*
X1969210Y3069255D01*
X1968125Y3069672D01*
X1966885D01*
X1965490Y3069047D01*
X1964405Y3068005D01*
X1963630Y3066755D01*
X1963010Y3064672D01*
X1962855Y3062797D01*
X1963165Y3060922D01*
X1963630Y3059672D01*
X1964560Y3058422D01*
X1965645Y3057589D01*
X1966730Y3057172D01*
X1967815D01*
X1968900Y3057589D01*
X1969830Y3058213D01*
X1970605Y3059047D01*
G01X1974480Y3053005D02*
X1983780D01*
G01X1988430Y3069672D02*
Y3057172D01*
X1994630D01*
G01X2000055D02*
X2003930Y3069672D01*
X2007805Y3057172D01*
G01X2006410Y3061547D02*
X2001450D01*
G01X2016330Y3057172D02*
Y3062797D01*
X2013230Y3069672D01*
G01X2019430D02*
X2016330Y3062797D01*
G01X2031830Y3057172D02*
X2025630D01*
Y3069672D01*
X2031830D01*
G01X2029350Y3063630D02*
X2025630D01*
G01X2038030Y3057172D02*
Y3069672D01*
X2041905D01*
X2043145Y3069047D01*
X2043920Y3068214D01*
X2044230Y3066547D01*
X2043920Y3064880D01*
X2042990Y3063839D01*
X2041905Y3063214D01*
X2038030D01*
G01X2041905D02*
X2044230Y3057172D01*
G01X2053530Y3056755D02*
X2053220Y3056964D01*
Y3057380D01*
X2053530Y3057589D01*
X2053840Y3057380D01*
Y3056964D01*
X2053530Y3056755D01*
G01Y3062380D02*
X2053220Y3062589D01*
Y3063005D01*
X2053530Y3063214D01*
X2053840Y3063005D01*
Y3062589D01*
X2053530Y3062380D01*
G01X2074300Y3057172D02*
Y3069672D01*
X2078330Y3059255D01*
X2082360Y3069672D01*
Y3057172D01*
G01X2087320Y3069672D02*
Y3060714D01*
X2087940Y3058838D01*
X2089180Y3057589D01*
X2090730Y3057172D01*
X2092280Y3057589D01*
X2093520Y3058838D01*
X2094140Y3060714D01*
Y3069672D01*
G01X2099875Y3058838D02*
X2101115Y3057797D01*
X2102510Y3057172D01*
X2103750D01*
X2104990Y3057797D01*
X2105920Y3058838D01*
X2106385Y3060297D01*
X2106075Y3061755D01*
X2105300Y3063005D01*
X2103905Y3063839D01*
X2102045Y3064255D01*
X2100960Y3065089D01*
X2100495Y3066547D01*
X2100805Y3068005D01*
X2101580Y3069047D01*
X2102665Y3069672D01*
X2103750D01*
X2104835Y3069255D01*
X2105765Y3068214D01*
G01X2115530Y3069672D02*
Y3057172D01*
G01X2111965Y3069672D02*
X2119095D01*
G01X2125915Y3061339D02*
X2129945D01*
G01X2136765Y3057172D02*
Y3069672D01*
X2143895Y3057172D01*
Y3069672D01*
G01X2152730Y3057172D02*
X2151490Y3057380D01*
X2150405Y3058213D01*
X2149475Y3059464D01*
X2148855Y3060922D01*
X2148545Y3062589D01*
Y3064255D01*
X2148855Y3065922D01*
X2149475Y3067380D01*
X2150405Y3068630D01*
X2151490Y3069464D01*
X2152730Y3069672D01*
X2153970Y3069464D01*
X2155055Y3068630D01*
X2155985Y3067380D01*
X2156605Y3065922D01*
X2156915Y3064255D01*
Y3062589D01*
X2156605Y3060922D01*
X2155985Y3059464D01*
X2155055Y3058213D01*
X2153970Y3057380D01*
X2152730Y3057172D01*
G01X2165130Y3069672D02*
Y3057172D01*
G01X2161565Y3069672D02*
X2168695D01*
G01X2175515Y3061339D02*
X2179545D01*
G01X2193340Y3068630D02*
X2192410Y3069255D01*
X2191325Y3069672D01*
X2190085D01*
X2188690Y3069047D01*
X2187605Y3068005D01*
X2186830Y3066755D01*
X2186210Y3064672D01*
X2186055Y3062797D01*
X2186365Y3060922D01*
X2186830Y3059672D01*
X2187760Y3058422D01*
X2188845Y3057589D01*
X2189930Y3057172D01*
X2191015D01*
X2192100Y3057589D01*
X2193030Y3058213D01*
X2193805Y3059047D01*
G01X2198920Y3069672D02*
Y3060714D01*
X2199540Y3058838D01*
X2200780Y3057589D01*
X2202330Y3057172D01*
X2203880Y3057589D01*
X2205120Y3058838D01*
X2205740Y3060714D01*
Y3069672D01*
G01X2214730D02*
Y3057172D01*
G01X2211165Y3069672D02*
X2218295D01*
G01X2225115Y3061339D02*
X2229145D01*
G01X2236430Y3069672D02*
Y3057172D01*
X2242630D01*
G01X2248055D02*
X2251930Y3069672D01*
X2255805Y3057172D01*
G01X2254410Y3061547D02*
X2249450D01*
G01X2264330Y3057172D02*
Y3062797D01*
X2261230Y3069672D01*
G01X2267430D02*
X2264330Y3062797D01*
G01X2279830Y3057172D02*
X2273630D01*
Y3069672D01*
X2279830D01*
G01X2277350Y3063630D02*
X2273630D01*
G01X2286030Y3057172D02*
Y3069672D01*
X2289905D01*
X2291145Y3069047D01*
X2291920Y3068214D01*
X2292230Y3066547D01*
X2291920Y3064880D01*
X2290990Y3063839D01*
X2289905Y3063214D01*
X2286030D01*
G01X2289905D02*
X2292230Y3057172D01*
G01X1913565Y3075922D02*
Y3088422D01*
X1920695Y3075922D01*
Y3088422D01*
G01X1929530Y3075922D02*
X1928290Y3076130D01*
X1927205Y3076963D01*
X1926275Y3078214D01*
X1925655Y3079672D01*
X1925345Y3081339D01*
Y3083005D01*
X1925655Y3084672D01*
X1926275Y3086130D01*
X1927205Y3087380D01*
X1928290Y3088214D01*
X1929530Y3088422D01*
X1930770Y3088214D01*
X1931855Y3087380D01*
X1932785Y3086130D01*
X1933405Y3084672D01*
X1933715Y3083005D01*
Y3081339D01*
X1933405Y3079672D01*
X1932785Y3078214D01*
X1931855Y3076963D01*
X1930770Y3076130D01*
X1929530Y3075922D01*
G01X1941930Y3088422D02*
Y3075922D01*
G01X1938365Y3088422D02*
X1945495D01*
G01X1957430Y3075922D02*
X1951230D01*
Y3088422D01*
X1957430D01*
G01X1954950Y3082380D02*
X1951230D01*
G01X1963475Y3077588D02*
X1964715Y3076547D01*
X1966110Y3075922D01*
X1967350D01*
X1968590Y3076547D01*
X1969520Y3077588D01*
X1969985Y3079047D01*
X1969675Y3080505D01*
X1968900Y3081755D01*
X1967505Y3082589D01*
X1965645Y3083005D01*
X1964560Y3083839D01*
X1964095Y3085297D01*
X1964405Y3086755D01*
X1965180Y3087797D01*
X1966265Y3088422D01*
X1967350D01*
X1968435Y3088005D01*
X1969365Y3086964D01*
G01X1979130Y3075505D02*
X1978820Y3075714D01*
Y3076130D01*
X1979130Y3076339D01*
X1979440Y3076130D01*
Y3075714D01*
X1979130Y3075505D01*
G01Y3081130D02*
X1978820Y3081339D01*
Y3081755D01*
X1979130Y3081964D01*
X1979440Y3081755D01*
Y3081339D01*
X1979130Y3081130D01*
G01X2077640Y3231289D02*
X2078260Y3231914D01*
X2078725Y3232955D01*
X2079035Y3234414D01*
X2078725Y3235664D01*
X2078105Y3236497D01*
X2077020Y3237122D01*
X2072835D01*
Y3224622D01*
X2077950D01*
X2079035Y3225455D01*
X2079655Y3226705D01*
X2079965Y3228164D01*
X2079655Y3229622D01*
X2078725Y3230872D01*
X2077640Y3231289D01*
X2072835D01*
G01X2084925Y3224622D02*
X2088800Y3237122D01*
X2092675Y3224622D01*
G01X2091280Y3228997D02*
X2086320D01*
G01X2104610Y3236080D02*
X2103680Y3236705D01*
X2102595Y3237122D01*
X2101355D01*
X2099960Y3236497D01*
X2098875Y3235455D01*
X2098100Y3234205D01*
X2097480Y3232122D01*
X2097325Y3230247D01*
X2097635Y3228372D01*
X2098100Y3227122D01*
X2099030Y3225872D01*
X2100115Y3225039D01*
X2101200Y3224622D01*
X2102285D01*
X2103370Y3225039D01*
X2104300Y3225663D01*
X2105075Y3226497D01*
G01X2110190Y3224622D02*
Y3237122D01*
G01X2116080D02*
X2110190Y3229413D01*
G01X2117010Y3224622D02*
X2112825Y3232955D01*
G01X2122590Y3224622D02*
Y3237122D01*
X2125690D01*
X2126930Y3236497D01*
X2127860Y3235664D01*
X2128635Y3234414D01*
X2129255Y3232955D01*
X2129410Y3230872D01*
X2129255Y3228789D01*
X2128635Y3227330D01*
X2127860Y3226080D01*
X2126930Y3225247D01*
X2125690Y3224622D01*
X2122590D01*
G01X2135300D02*
Y3237122D01*
X2139175D01*
X2140415Y3236497D01*
X2141190Y3235664D01*
X2141500Y3233997D01*
X2141190Y3232330D01*
X2140260Y3231289D01*
X2139175Y3230664D01*
X2135300D01*
G01X2139175D02*
X2141500Y3224622D01*
G01X2148940Y3237122D02*
X2152660D01*
G01X2150800D02*
Y3224622D01*
G01X2148940D02*
X2152660D01*
G01X2160100Y3237122D02*
Y3224622D01*
X2166300D01*
G01X2172500Y3237122D02*
Y3224622D01*
X2178700D01*
G01X2197145Y3226288D02*
X2198385Y3225247D01*
X2199780Y3224622D01*
X2201020D01*
X2202260Y3225247D01*
X2203190Y3226288D01*
X2203655Y3227747D01*
X2203345Y3229205D01*
X2202570Y3230455D01*
X2201175Y3231289D01*
X2199315Y3231705D01*
X2198230Y3232539D01*
X2197765Y3233997D01*
X2198075Y3235455D01*
X2198850Y3236497D01*
X2199935Y3237122D01*
X2201020D01*
X2202105Y3236705D01*
X2203035Y3235664D01*
G01X2212800Y3237122D02*
Y3224622D01*
G01X2209235Y3237122D02*
X2216365D01*
G01X2221790D02*
Y3228164D01*
X2222410Y3226288D01*
X2223650Y3225039D01*
X2225200Y3224622D01*
X2226750Y3225039D01*
X2227990Y3226288D01*
X2228610Y3228164D01*
Y3237122D01*
G01X2238840Y3231289D02*
X2239460Y3231914D01*
X2239925Y3232955D01*
X2240235Y3234414D01*
X2239925Y3235664D01*
X2239305Y3236497D01*
X2238220Y3237122D01*
X2234035D01*
Y3224622D01*
X2239150D01*
X2240235Y3225455D01*
X2240855Y3226705D01*
X2241165Y3228164D01*
X2240855Y3229622D01*
X2239925Y3230872D01*
X2238840Y3231289D01*
X2234035D01*
G01X2259300Y3237122D02*
Y3224622D01*
X2265500D01*
G01X2277900D02*
X2271700D01*
Y3237122D01*
X2277900D01*
G01X2275420Y3231080D02*
X2271700D01*
G01X2283635Y3224622D02*
Y3237122D01*
X2290765Y3224622D01*
Y3237122D01*
G01X2300530Y3230872D02*
X2303630D01*
Y3227122D01*
X2302700Y3225872D01*
X2301615Y3225039D01*
X2300065Y3224622D01*
X2298515Y3225039D01*
X2297430Y3225872D01*
X2296500Y3227122D01*
X2295880Y3228580D01*
X2295570Y3230247D01*
Y3231705D01*
X2295880Y3232955D01*
X2296500Y3234414D01*
X2297430Y3235664D01*
X2298360Y3236497D01*
X2299600Y3237122D01*
X2300685D01*
X2301925Y3236705D01*
X2302855Y3235872D01*
G01X2312000Y3237122D02*
Y3224622D01*
G01X2308435Y3237122D02*
X2315565D01*
G01X2321145Y3224622D02*
Y3237122D01*
G01X2327655D02*
Y3224622D01*
G01Y3230872D02*
X2321145D01*
G01X2349200Y3237122D02*
Y3224622D01*
G01X2345635Y3237122D02*
X2352765D01*
G01X2361600Y3224622D02*
X2360360Y3224830D01*
X2359275Y3225663D01*
X2358345Y3226914D01*
X2357725Y3228372D01*
X2357415Y3230039D01*
Y3231705D01*
X2357725Y3233372D01*
X2358345Y3234830D01*
X2359275Y3236080D01*
X2360360Y3236914D01*
X2361600Y3237122D01*
X2362840Y3236914D01*
X2363925Y3236080D01*
X2364855Y3234830D01*
X2365475Y3233372D01*
X2365785Y3231705D01*
Y3230039D01*
X2365475Y3228372D01*
X2364855Y3226914D01*
X2363925Y3225663D01*
X2362840Y3224830D01*
X2361600Y3224622D01*
G01X2370900Y3237122D02*
Y3224622D01*
X2377100D01*
G01X2389500D02*
X2383300D01*
Y3237122D01*
X2389500D01*
G01X2387020Y3231080D02*
X2383300D01*
G01X2395700Y3224622D02*
Y3237122D01*
X2399575D01*
X2400815Y3236497D01*
X2401590Y3235664D01*
X2401900Y3233997D01*
X2401590Y3232330D01*
X2400660Y3231289D01*
X2399575Y3230664D01*
X2395700D01*
G01X2399575D02*
X2401900Y3224622D01*
G01X2407325D02*
X2411200Y3237122D01*
X2415075Y3224622D01*
G01X2413680Y3228997D02*
X2408720D01*
G01X2420035Y3224622D02*
Y3237122D01*
X2427165Y3224622D01*
Y3237122D01*
G01X2439410Y3236080D02*
X2438480Y3236705D01*
X2437395Y3237122D01*
X2436155D01*
X2434760Y3236497D01*
X2433675Y3235455D01*
X2432900Y3234205D01*
X2432280Y3232122D01*
X2432125Y3230247D01*
X2432435Y3228372D01*
X2432900Y3227122D01*
X2433830Y3225872D01*
X2434915Y3225039D01*
X2436000Y3224622D01*
X2437085D01*
X2438170Y3225039D01*
X2439100Y3225663D01*
X2439875Y3226497D01*
G01X2451500Y3224622D02*
X2445300D01*
Y3237122D01*
X2451500D01*
G01X2449020Y3231080D02*
X2445300D01*
G01X2473200Y3237122D02*
Y3224622D01*
G01X2469635Y3237122D02*
X2476765D01*
G01X2485600Y3224622D02*
X2484360Y3224830D01*
X2483275Y3225663D01*
X2482345Y3226914D01*
X2481725Y3228372D01*
X2481415Y3230039D01*
Y3231705D01*
X2481725Y3233372D01*
X2482345Y3234830D01*
X2483275Y3236080D01*
X2484360Y3236914D01*
X2485600Y3237122D01*
X2486840Y3236914D01*
X2487925Y3236080D01*
X2488855Y3234830D01*
X2489475Y3233372D01*
X2489785Y3231705D01*
Y3230039D01*
X2489475Y3228372D01*
X2488855Y3226914D01*
X2487925Y3225663D01*
X2486840Y3224830D01*
X2485600Y3224622D01*
G01X2511640Y3231289D02*
X2512260Y3231914D01*
X2512725Y3232955D01*
X2513035Y3234414D01*
X2512725Y3235664D01*
X2512105Y3236497D01*
X2511020Y3237122D01*
X2506835D01*
Y3224622D01*
X2511950D01*
X2513035Y3225455D01*
X2513655Y3226705D01*
X2513965Y3228164D01*
X2513655Y3229622D01*
X2512725Y3230872D01*
X2511640Y3231289D01*
X2506835D01*
G01X2525900Y3224622D02*
X2519700D01*
Y3237122D01*
X2525900D01*
G01X2523420Y3231080D02*
X2519700D01*
G01X2547290Y3224622D02*
X2547600Y3227330D01*
X2548065Y3229622D01*
X2548685Y3231705D01*
X2549460Y3233997D01*
X2550700Y3237122D01*
X2544500D01*
G01X2570695Y3228789D02*
X2574415D01*
G01X2572400Y3231497D02*
Y3226080D01*
G01X2582010Y3224205D02*
X2587590Y3237122D01*
G01X2595185Y3228789D02*
X2599215D01*
G01X2606190Y3226497D02*
X2607120Y3225455D01*
X2608205Y3224830D01*
X2609600Y3224622D01*
X2610995Y3225039D01*
X2612080Y3225872D01*
X2612855Y3227330D01*
X2613010Y3228997D01*
X2612700Y3230664D01*
X2611925Y3231705D01*
X2610840Y3232539D01*
X2609755Y3232747D01*
X2608670Y3232539D01*
X2607275Y3231705D01*
X2607740Y3237122D01*
X2611925D01*
G01X2630370Y3224622D02*
Y3237122D01*
X2634400Y3226705D01*
X2638430Y3237122D01*
Y3224622D01*
G01X2644940Y3237122D02*
X2648660D01*
G01X2646800D02*
Y3224622D01*
G01X2644940D02*
X2648660D01*
G01X2656100Y3237122D02*
Y3224622D01*
X2662300D01*
G01X2668345Y3226288D02*
X2669585Y3225247D01*
X2670980Y3224622D01*
X2672220D01*
X2673460Y3225247D01*
X2674390Y3226288D01*
X2674855Y3227747D01*
X2674545Y3229205D01*
X2673770Y3230455D01*
X2672375Y3231289D01*
X2670515Y3231705D01*
X2669430Y3232539D01*
X2668965Y3233997D01*
X2669275Y3235455D01*
X2670050Y3236497D01*
X2671135Y3237122D01*
X2672220D01*
X2673305Y3236705D01*
X2674235Y3235664D01*
G01X1913185Y3247539D02*
X1917215D01*
G01X1935970Y3243372D02*
Y3255872D01*
X1940000Y3245455D01*
X1944030Y3255872D01*
Y3243372D01*
G01X1949455D02*
Y3255872D01*
X1955345D01*
G01X1953175Y3249830D02*
X1949455D01*
G01X1965730Y3249622D02*
X1968830D01*
Y3245872D01*
X1967900Y3244622D01*
X1966815Y3243789D01*
X1965265Y3243372D01*
X1963715Y3243789D01*
X1962630Y3244622D01*
X1961700Y3245872D01*
X1961080Y3247330D01*
X1960770Y3248997D01*
Y3250455D01*
X1961080Y3251705D01*
X1961700Y3253164D01*
X1962630Y3254414D01*
X1963560Y3255247D01*
X1964800Y3255872D01*
X1965885D01*
X1967125Y3255455D01*
X1968055Y3254622D01*
G01X1972550Y3239205D02*
X1981850D01*
G01X1986345Y3245038D02*
X1987585Y3243997D01*
X1988980Y3243372D01*
X1990220D01*
X1991460Y3243997D01*
X1992390Y3245038D01*
X1992855Y3246497D01*
X1992545Y3247955D01*
X1991770Y3249205D01*
X1990375Y3250039D01*
X1988515Y3250455D01*
X1987430Y3251289D01*
X1986965Y3252747D01*
X1987275Y3254205D01*
X1988050Y3255247D01*
X1989135Y3255872D01*
X1990220D01*
X1991305Y3255455D01*
X1992235Y3254414D01*
G01X2002000Y3255872D02*
Y3243372D01*
G01X1998435Y3255872D02*
X2005565D01*
G01X2010990D02*
Y3246914D01*
X2011610Y3245038D01*
X2012850Y3243789D01*
X2014400Y3243372D01*
X2015950Y3243789D01*
X2017190Y3245038D01*
X2017810Y3246914D01*
Y3255872D01*
G01X2028040Y3250039D02*
X2028660Y3250664D01*
X2029125Y3251705D01*
X2029435Y3253164D01*
X2029125Y3254414D01*
X2028505Y3255247D01*
X2027420Y3255872D01*
X2023235D01*
Y3243372D01*
X2028350D01*
X2029435Y3244205D01*
X2030055Y3245455D01*
X2030365Y3246914D01*
X2030055Y3248372D01*
X2029125Y3249622D01*
X2028040Y3250039D01*
X2023235D01*
G01X2051600Y3242955D02*
X2051290Y3243164D01*
Y3243580D01*
X2051600Y3243789D01*
X2051910Y3243580D01*
Y3243164D01*
X2051600Y3242955D01*
G01Y3248580D02*
X2051290Y3248789D01*
Y3249205D01*
X2051600Y3249414D01*
X2051910Y3249205D01*
Y3248789D01*
X2051600Y3248580D01*
G01X2072370Y3243372D02*
Y3255872D01*
X2076400Y3245455D01*
X2080430Y3255872D01*
Y3243372D01*
G01X2084925D02*
X2088800Y3255872D01*
X2092675Y3243372D01*
G01X2091280Y3247747D02*
X2086320D01*
G01X2097635Y3243372D02*
Y3255872D01*
X2104765Y3243372D01*
Y3255872D01*
G01X2110190D02*
Y3246914D01*
X2110810Y3245038D01*
X2112050Y3243789D01*
X2113600Y3243372D01*
X2115150Y3243789D01*
X2116390Y3245038D01*
X2117010Y3246914D01*
Y3255872D01*
G01X2123055Y3243372D02*
Y3255872D01*
X2128945D01*
G01X2126775Y3249830D02*
X2123055D01*
G01X2134525Y3243372D02*
X2138400Y3255872D01*
X2142275Y3243372D01*
G01X2140880Y3247747D02*
X2135920D01*
G01X2154210Y3254830D02*
X2153280Y3255455D01*
X2152195Y3255872D01*
X2150955D01*
X2149560Y3255247D01*
X2148475Y3254205D01*
X2147700Y3252955D01*
X2147080Y3250872D01*
X2146925Y3248997D01*
X2147235Y3247122D01*
X2147700Y3245872D01*
X2148630Y3244622D01*
X2149715Y3243789D01*
X2150800Y3243372D01*
X2151885D01*
X2152970Y3243789D01*
X2153900Y3244413D01*
X2154675Y3245247D01*
G01X2163200Y3255872D02*
Y3243372D01*
G01X2159635Y3255872D02*
X2166765D01*
G01X2172190D02*
Y3246914D01*
X2172810Y3245038D01*
X2174050Y3243789D01*
X2175600Y3243372D01*
X2177150Y3243789D01*
X2178390Y3245038D01*
X2179010Y3246914D01*
Y3255872D01*
G01X2184900Y3243372D02*
Y3255872D01*
X2188775D01*
X2190015Y3255247D01*
X2190790Y3254414D01*
X2191100Y3252747D01*
X2190790Y3251080D01*
X2189860Y3250039D01*
X2188775Y3249414D01*
X2184900D01*
G01X2188775D02*
X2191100Y3243372D01*
G01X2198540Y3255872D02*
X2202260D01*
G01X2200400D02*
Y3243372D01*
G01X2198540D02*
X2202260D01*
G01X2209235D02*
Y3255872D01*
X2216365Y3243372D01*
Y3255872D01*
G01X2226130Y3249622D02*
X2229230D01*
Y3245872D01*
X2228300Y3244622D01*
X2227215Y3243789D01*
X2225665Y3243372D01*
X2224115Y3243789D01*
X2223030Y3244622D01*
X2222100Y3245872D01*
X2221480Y3247330D01*
X2221170Y3248997D01*
Y3250455D01*
X2221480Y3251705D01*
X2222100Y3253164D01*
X2223030Y3254414D01*
X2223960Y3255247D01*
X2225200Y3255872D01*
X2226285D01*
X2227525Y3255455D01*
X2228455Y3254622D01*
G01X2246745Y3245038D02*
X2247985Y3243997D01*
X2249380Y3243372D01*
X2250620D01*
X2251860Y3243997D01*
X2252790Y3245038D01*
X2253255Y3246497D01*
X2252945Y3247955D01*
X2252170Y3249205D01*
X2250775Y3250039D01*
X2248915Y3250455D01*
X2247830Y3251289D01*
X2247365Y3252747D01*
X2247675Y3254205D01*
X2248450Y3255247D01*
X2249535Y3255872D01*
X2250620D01*
X2251705Y3255455D01*
X2252635Y3254414D01*
G01X2262400Y3255872D02*
Y3243372D01*
G01X2258835Y3255872D02*
X2265965D01*
G01X2271390D02*
Y3246914D01*
X2272010Y3245038D01*
X2273250Y3243789D01*
X2274800Y3243372D01*
X2276350Y3243789D01*
X2277590Y3245038D01*
X2278210Y3246914D01*
Y3255872D01*
G01X2288440Y3250039D02*
X2289060Y3250664D01*
X2289525Y3251705D01*
X2289835Y3253164D01*
X2289525Y3254414D01*
X2288905Y3255247D01*
X2287820Y3255872D01*
X2283635D01*
Y3243372D01*
X2288750D01*
X2289835Y3244205D01*
X2290455Y3245455D01*
X2290765Y3246914D01*
X2290455Y3248372D01*
X2289525Y3249622D01*
X2288440Y3250039D01*
X2283635D01*
G01X2308900Y3255872D02*
Y3243372D01*
X2315100D01*
G01X2327500D02*
X2321300D01*
Y3255872D01*
X2327500D01*
G01X2325020Y3249830D02*
X2321300D01*
G01X2333235Y3243372D02*
Y3255872D01*
X2340365Y3243372D01*
Y3255872D01*
G01X2350130Y3249622D02*
X2353230D01*
Y3245872D01*
X2352300Y3244622D01*
X2351215Y3243789D01*
X2349665Y3243372D01*
X2348115Y3243789D01*
X2347030Y3244622D01*
X2346100Y3245872D01*
X2345480Y3247330D01*
X2345170Y3248997D01*
Y3250455D01*
X2345480Y3251705D01*
X2346100Y3253164D01*
X2347030Y3254414D01*
X2347960Y3255247D01*
X2349200Y3255872D01*
X2350285D01*
X2351525Y3255455D01*
X2352455Y3254622D01*
G01X2361600Y3255872D02*
Y3243372D01*
G01X2358035Y3255872D02*
X2365165D01*
G01X2370745Y3243372D02*
Y3255872D01*
G01X2377255D02*
Y3243372D01*
G01Y3249622D02*
X2370745D01*
G01X2073145Y3263788D02*
X2074385Y3262747D01*
X2075780Y3262122D01*
X2077020D01*
X2078260Y3262747D01*
X2079190Y3263788D01*
X2079655Y3265247D01*
X2079345Y3266705D01*
X2078570Y3267955D01*
X2077175Y3268789D01*
X2075315Y3269205D01*
X2074230Y3270039D01*
X2073765Y3271497D01*
X2074075Y3272955D01*
X2074850Y3273997D01*
X2075935Y3274622D01*
X2077020D01*
X2078105Y3274205D01*
X2079035Y3273164D01*
G01X2085390Y3274622D02*
Y3265664D01*
X2086010Y3263788D01*
X2087250Y3262539D01*
X2088800Y3262122D01*
X2090350Y3262539D01*
X2091590Y3263788D01*
X2092210Y3265664D01*
Y3274622D01*
G01X2098100Y3262122D02*
Y3274622D01*
X2101975D01*
X2103215Y3273997D01*
X2103990Y3273164D01*
X2104300Y3271497D01*
X2103990Y3269830D01*
X2103060Y3268789D01*
X2101975Y3268164D01*
X2098100D01*
G01X2101975D02*
X2104300Y3262122D01*
G01X2110655D02*
Y3274622D01*
X2116545D01*
G01X2114375Y3268580D02*
X2110655D01*
G01X2122125Y3262122D02*
X2126000Y3274622D01*
X2129875Y3262122D01*
G01X2128480Y3266497D02*
X2123520D01*
G01X2141810Y3273580D02*
X2140880Y3274205D01*
X2139795Y3274622D01*
X2138555D01*
X2137160Y3273997D01*
X2136075Y3272955D01*
X2135300Y3271705D01*
X2134680Y3269622D01*
X2134525Y3267747D01*
X2134835Y3265872D01*
X2135300Y3264622D01*
X2136230Y3263372D01*
X2137315Y3262539D01*
X2138400Y3262122D01*
X2139485D01*
X2140570Y3262539D01*
X2141500Y3263163D01*
X2142275Y3263997D01*
G01X2153900Y3262122D02*
X2147700D01*
Y3274622D01*
X2153900D01*
G01X2151420Y3268580D02*
X2147700D01*
G01X2175600Y3262122D02*
X2174360Y3262330D01*
X2173275Y3263163D01*
X2172345Y3264414D01*
X2171725Y3265872D01*
X2171415Y3267539D01*
Y3269205D01*
X2171725Y3270872D01*
X2172345Y3272330D01*
X2173275Y3273580D01*
X2174360Y3274414D01*
X2175600Y3274622D01*
X2176840Y3274414D01*
X2177925Y3273580D01*
X2178855Y3272330D01*
X2179475Y3270872D01*
X2179785Y3269205D01*
Y3267539D01*
X2179475Y3265872D01*
X2178855Y3264414D01*
X2177925Y3263163D01*
X2176840Y3262330D01*
X2175600Y3262122D01*
G01X2185055D02*
Y3274622D01*
X2190945D01*
G01X2188775Y3268580D02*
X2185055D01*
G01X2208770Y3262122D02*
Y3274622D01*
X2212800Y3264205D01*
X2216830Y3274622D01*
Y3262122D01*
G01X2221790Y3274622D02*
Y3265664D01*
X2222410Y3263788D01*
X2223650Y3262539D01*
X2225200Y3262122D01*
X2226750Y3262539D01*
X2227990Y3263788D01*
X2228610Y3265664D01*
Y3274622D01*
G01X2234345Y3263788D02*
X2235585Y3262747D01*
X2236980Y3262122D01*
X2238220D01*
X2239460Y3262747D01*
X2240390Y3263788D01*
X2240855Y3265247D01*
X2240545Y3266705D01*
X2239770Y3267955D01*
X2238375Y3268789D01*
X2236515Y3269205D01*
X2235430Y3270039D01*
X2234965Y3271497D01*
X2235275Y3272955D01*
X2236050Y3273997D01*
X2237135Y3274622D01*
X2238220D01*
X2239305Y3274205D01*
X2240235Y3273164D01*
G01X2250000Y3274622D02*
Y3262122D01*
G01X2246435Y3274622D02*
X2253565D01*
G01X2260385Y3266289D02*
X2264415D01*
G01X2271235Y3262122D02*
Y3274622D01*
X2278365Y3262122D01*
Y3274622D01*
G01X2287200Y3262122D02*
X2285960Y3262330D01*
X2284875Y3263163D01*
X2283945Y3264414D01*
X2283325Y3265872D01*
X2283015Y3267539D01*
Y3269205D01*
X2283325Y3270872D01*
X2283945Y3272330D01*
X2284875Y3273580D01*
X2285960Y3274414D01*
X2287200Y3274622D01*
X2288440Y3274414D01*
X2289525Y3273580D01*
X2290455Y3272330D01*
X2291075Y3270872D01*
X2291385Y3269205D01*
Y3267539D01*
X2291075Y3265872D01*
X2290455Y3264414D01*
X2289525Y3263163D01*
X2288440Y3262330D01*
X2287200Y3262122D01*
G01X2299600Y3274622D02*
Y3262122D01*
G01X2296035Y3274622D02*
X2303165D01*
G01X2309985Y3266289D02*
X2314015D01*
G01X2327810Y3273580D02*
X2326880Y3274205D01*
X2325795Y3274622D01*
X2324555D01*
X2323160Y3273997D01*
X2322075Y3272955D01*
X2321300Y3271705D01*
X2320680Y3269622D01*
X2320525Y3267747D01*
X2320835Y3265872D01*
X2321300Y3264622D01*
X2322230Y3263372D01*
X2323315Y3262539D01*
X2324400Y3262122D01*
X2325485D01*
X2326570Y3262539D01*
X2327500Y3263163D01*
X2328275Y3263997D01*
G01X2333390Y3274622D02*
Y3265664D01*
X2334010Y3263788D01*
X2335250Y3262539D01*
X2336800Y3262122D01*
X2338350Y3262539D01*
X2339590Y3263788D01*
X2340210Y3265664D01*
Y3274622D01*
G01X2349200D02*
Y3262122D01*
G01X2345635Y3274622D02*
X2352765D01*
G01X2359585Y3266289D02*
X2363615D01*
G01X2370900Y3274622D02*
Y3262122D01*
X2377100D01*
G01X2382525D02*
X2386400Y3274622D01*
X2390275Y3262122D01*
G01X2388880Y3266497D02*
X2383920D01*
G01X2398800Y3262122D02*
Y3267747D01*
X2395700Y3274622D01*
G01X2401900D02*
X2398800Y3267747D01*
G01X2414300Y3262122D02*
X2408100D01*
Y3274622D01*
X2414300D01*
G01X2411820Y3268580D02*
X2408100D01*
G01X2420500Y3262122D02*
Y3274622D01*
X2424375D01*
X2425615Y3273997D01*
X2426390Y3273164D01*
X2426700Y3271497D01*
X2426390Y3269830D01*
X2425460Y3268789D01*
X2424375Y3268164D01*
X2420500D01*
G01X2424375D02*
X2426700Y3262122D01*
G01X1913185Y3285039D02*
X1917215D01*
G01X1935970Y3280872D02*
Y3293372D01*
X1940000Y3282955D01*
X1944030Y3293372D01*
Y3280872D01*
G01X1948525D02*
X1952400Y3293372D01*
X1956275Y3280872D01*
G01X1954880Y3285247D02*
X1949920D01*
G01X1961545Y3280872D02*
X1968055Y3293372D01*
G01X1961545D02*
X1968055Y3280872D01*
G01X1972550Y3276705D02*
X1981850D01*
G01X1986190Y3280872D02*
Y3293372D01*
X1989290D01*
X1990530Y3292747D01*
X1991460Y3291914D01*
X1992235Y3290664D01*
X1992855Y3289205D01*
X1993010Y3287122D01*
X1992855Y3285039D01*
X1992235Y3283580D01*
X1991460Y3282330D01*
X1990530Y3281497D01*
X1989290Y3280872D01*
X1986190D01*
G01X2005100D02*
X1998900D01*
Y3293372D01*
X2005100D01*
G01X2002620Y3287330D02*
X1998900D01*
G01X2011300Y3280872D02*
Y3293372D01*
X2015020D01*
X2016260Y3292747D01*
X2017190Y3291289D01*
X2017500Y3289622D01*
X2017190Y3287955D01*
X2016415Y3286705D01*
X2015020Y3286080D01*
X2011300D01*
G01X2026800Y3293372D02*
Y3280872D01*
G01X2023235Y3293372D02*
X2030365D01*
G01X2035945Y3280872D02*
Y3293372D01*
G01X2042455D02*
Y3280872D01*
G01Y3287122D02*
X2035945D01*
G01X2051600Y3280455D02*
X2051290Y3280664D01*
Y3281080D01*
X2051600Y3281289D01*
X2051910Y3281080D01*
Y3280664D01*
X2051600Y3280455D01*
G01Y3286080D02*
X2051290Y3286289D01*
Y3286705D01*
X2051600Y3286914D01*
X2051910Y3286705D01*
Y3286289D01*
X2051600Y3286080D01*
G01X2072990Y3280872D02*
Y3293372D01*
X2076090D01*
X2077330Y3292747D01*
X2078260Y3291914D01*
X2079035Y3290664D01*
X2079655Y3289205D01*
X2079810Y3287122D01*
X2079655Y3285039D01*
X2079035Y3283580D01*
X2078260Y3282330D01*
X2077330Y3281497D01*
X2076090Y3280872D01*
X2072990D01*
G01X2091900D02*
X2085700D01*
Y3293372D01*
X2091900D01*
G01X2089420Y3287330D02*
X2085700D01*
G01X2098100Y3280872D02*
Y3293372D01*
X2101820D01*
X2103060Y3292747D01*
X2103990Y3291289D01*
X2104300Y3289622D01*
X2103990Y3287955D01*
X2103215Y3286705D01*
X2101820Y3286080D01*
X2098100D01*
G01X2113600Y3293372D02*
Y3280872D01*
G01X2110035Y3293372D02*
X2117165D01*
G01X2122745Y3280872D02*
Y3293372D01*
G01X2129255D02*
Y3280872D01*
G01Y3287122D02*
X2122745D01*
G01X2147855Y3280872D02*
Y3293372D01*
X2153745D01*
G01X2151575Y3287330D02*
X2147855D01*
G01X2160100Y3280872D02*
Y3293372D01*
X2163975D01*
X2165215Y3292747D01*
X2165990Y3291914D01*
X2166300Y3290247D01*
X2165990Y3288580D01*
X2165060Y3287539D01*
X2163975Y3286914D01*
X2160100D01*
G01X2163975D02*
X2166300Y3280872D01*
G01X2175600D02*
X2174360Y3281080D01*
X2173275Y3281913D01*
X2172345Y3283164D01*
X2171725Y3284622D01*
X2171415Y3286289D01*
Y3287955D01*
X2171725Y3289622D01*
X2172345Y3291080D01*
X2173275Y3292330D01*
X2174360Y3293164D01*
X2175600Y3293372D01*
X2176840Y3293164D01*
X2177925Y3292330D01*
X2178855Y3291080D01*
X2179475Y3289622D01*
X2179785Y3287955D01*
Y3286289D01*
X2179475Y3284622D01*
X2178855Y3283164D01*
X2177925Y3281913D01*
X2176840Y3281080D01*
X2175600Y3280872D01*
G01X2183970D02*
Y3293372D01*
X2188000Y3282955D01*
X2192030Y3293372D01*
Y3280872D01*
G01X2209545Y3282538D02*
X2210785Y3281497D01*
X2212180Y3280872D01*
X2213420D01*
X2214660Y3281497D01*
X2215590Y3282538D01*
X2216055Y3283997D01*
X2215745Y3285455D01*
X2214970Y3286705D01*
X2213575Y3287539D01*
X2211715Y3287955D01*
X2210630Y3288789D01*
X2210165Y3290247D01*
X2210475Y3291705D01*
X2211250Y3292747D01*
X2212335Y3293372D01*
X2213420D01*
X2214505Y3292955D01*
X2215435Y3291914D01*
G01X2225200Y3293372D02*
Y3280872D01*
G01X2221635Y3293372D02*
X2228765D01*
G01X2233725Y3280872D02*
X2237600Y3293372D01*
X2241475Y3280872D01*
G01X2240080Y3285247D02*
X2235120D01*
G01X2246900Y3280872D02*
Y3293372D01*
X2250775D01*
X2252015Y3292747D01*
X2252790Y3291914D01*
X2253100Y3290247D01*
X2252790Y3288580D01*
X2251860Y3287539D01*
X2250775Y3286914D01*
X2246900D01*
G01X2250775D02*
X2253100Y3280872D01*
G01X2262400Y3293372D02*
Y3280872D01*
G01X2258835Y3293372D02*
X2265965D01*
G01X2284100D02*
Y3280872D01*
X2290300D01*
G01X2295725D02*
X2299600Y3293372D01*
X2303475Y3280872D01*
G01X2302080Y3285247D02*
X2297120D01*
G01X2312000Y3280872D02*
Y3286497D01*
X2308900Y3293372D01*
G01X2315100D02*
X2312000Y3286497D01*
G01X2327500Y3280872D02*
X2321300D01*
Y3293372D01*
X2327500D01*
G01X2325020Y3287330D02*
X2321300D01*
G01X2333700Y3280872D02*
Y3293372D01*
X2337575D01*
X2338815Y3292747D01*
X2339590Y3291914D01*
X2339900Y3290247D01*
X2339590Y3288580D01*
X2338660Y3287539D01*
X2337575Y3286914D01*
X2333700D01*
G01X2337575D02*
X2339900Y3280872D01*
G01X2361600Y3293372D02*
Y3280872D01*
G01X2358035Y3293372D02*
X2365165D01*
G01X2374000Y3280872D02*
X2372760Y3281080D01*
X2371675Y3281913D01*
X2370745Y3283164D01*
X2370125Y3284622D01*
X2369815Y3286289D01*
Y3287955D01*
X2370125Y3289622D01*
X2370745Y3291080D01*
X2371675Y3292330D01*
X2372760Y3293164D01*
X2374000Y3293372D01*
X2375240Y3293164D01*
X2376325Y3292330D01*
X2377255Y3291080D01*
X2377875Y3289622D01*
X2378185Y3287955D01*
Y3286289D01*
X2377875Y3284622D01*
X2377255Y3283164D01*
X2376325Y3281913D01*
X2375240Y3281080D01*
X2374000Y3280872D01*
G01X2398800Y3293372D02*
Y3280872D01*
G01X2395235Y3293372D02*
X2402365D01*
G01X2407945Y3280872D02*
Y3293372D01*
G01X2414455D02*
Y3280872D01*
G01Y3287122D02*
X2407945D01*
G01X2426700Y3280872D02*
X2420500D01*
Y3293372D01*
X2426700D01*
G01X2424220Y3287330D02*
X2420500D01*
G01X1913185Y3303789D02*
X1917215D01*
G01X1935970Y3299622D02*
Y3312122D01*
X1940000Y3301705D01*
X1944030Y3312122D01*
Y3299622D01*
G01X1948835D02*
Y3312122D01*
X1955965Y3299622D01*
Y3312122D01*
G01X1968210Y3311080D02*
X1967280Y3311705D01*
X1966195Y3312122D01*
X1964955D01*
X1963560Y3311497D01*
X1962475Y3310455D01*
X1961700Y3309205D01*
X1961080Y3307122D01*
X1960925Y3305247D01*
X1961235Y3303372D01*
X1961700Y3302122D01*
X1962630Y3300872D01*
X1963715Y3300039D01*
X1964800Y3299622D01*
X1965885D01*
X1966970Y3300039D01*
X1967900Y3300663D01*
X1968675Y3301497D01*
G01X1972550Y3295455D02*
X1981850D01*
G01X1986500Y3312122D02*
Y3299622D01*
X1992700D01*
G01X1998125D02*
X2002000Y3312122D01*
X2005875Y3299622D01*
G01X2004480Y3303997D02*
X1999520D01*
G01X2014400Y3299622D02*
Y3305247D01*
X2011300Y3312122D01*
G01X2017500D02*
X2014400Y3305247D01*
G01X2029900Y3299622D02*
X2023700D01*
Y3312122D01*
X2029900D01*
G01X2027420Y3306080D02*
X2023700D01*
G01X2036100Y3299622D02*
Y3312122D01*
X2039975D01*
X2041215Y3311497D01*
X2041990Y3310664D01*
X2042300Y3308997D01*
X2041990Y3307330D01*
X2041060Y3306289D01*
X2039975Y3305664D01*
X2036100D01*
G01X2039975D02*
X2042300Y3299622D01*
G01X2051600Y3299205D02*
X2051290Y3299414D01*
Y3299830D01*
X2051600Y3300039D01*
X2051910Y3299830D01*
Y3299414D01*
X2051600Y3299205D01*
G01Y3304830D02*
X2051290Y3305039D01*
Y3305455D01*
X2051600Y3305664D01*
X2051910Y3305455D01*
Y3305039D01*
X2051600Y3304830D01*
G01X2072370Y3299622D02*
Y3312122D01*
X2076400Y3301705D01*
X2080430Y3312122D01*
Y3299622D01*
G01X2085390Y3312122D02*
Y3303164D01*
X2086010Y3301288D01*
X2087250Y3300039D01*
X2088800Y3299622D01*
X2090350Y3300039D01*
X2091590Y3301288D01*
X2092210Y3303164D01*
Y3312122D01*
G01X2097945Y3301288D02*
X2099185Y3300247D01*
X2100580Y3299622D01*
X2101820D01*
X2103060Y3300247D01*
X2103990Y3301288D01*
X2104455Y3302747D01*
X2104145Y3304205D01*
X2103370Y3305455D01*
X2101975Y3306289D01*
X2100115Y3306705D01*
X2099030Y3307539D01*
X2098565Y3308997D01*
X2098875Y3310455D01*
X2099650Y3311497D01*
X2100735Y3312122D01*
X2101820D01*
X2102905Y3311705D01*
X2103835Y3310664D01*
G01X2113600Y3312122D02*
Y3299622D01*
G01X2110035Y3312122D02*
X2117165D01*
G01X2123985Y3303789D02*
X2128015D01*
G01X2134835Y3299622D02*
Y3312122D01*
X2141965Y3299622D01*
Y3312122D01*
G01X2150800Y3299622D02*
X2149560Y3299830D01*
X2148475Y3300663D01*
X2147545Y3301914D01*
X2146925Y3303372D01*
X2146615Y3305039D01*
Y3306705D01*
X2146925Y3308372D01*
X2147545Y3309830D01*
X2148475Y3311080D01*
X2149560Y3311914D01*
X2150800Y3312122D01*
X2152040Y3311914D01*
X2153125Y3311080D01*
X2154055Y3309830D01*
X2154675Y3308372D01*
X2154985Y3306705D01*
Y3305039D01*
X2154675Y3303372D01*
X2154055Y3301914D01*
X2153125Y3300663D01*
X2152040Y3299830D01*
X2150800Y3299622D01*
G01X2163200Y3312122D02*
Y3299622D01*
G01X2159635Y3312122D02*
X2166765D01*
G01X2173585Y3303789D02*
X2177615D01*
G01X2191410Y3311080D02*
X2190480Y3311705D01*
X2189395Y3312122D01*
X2188155D01*
X2186760Y3311497D01*
X2185675Y3310455D01*
X2184900Y3309205D01*
X2184280Y3307122D01*
X2184125Y3305247D01*
X2184435Y3303372D01*
X2184900Y3302122D01*
X2185830Y3300872D01*
X2186915Y3300039D01*
X2188000Y3299622D01*
X2189085D01*
X2190170Y3300039D01*
X2191100Y3300663D01*
X2191875Y3301497D01*
G01X2196990Y3312122D02*
Y3303164D01*
X2197610Y3301288D01*
X2198850Y3300039D01*
X2200400Y3299622D01*
X2201950Y3300039D01*
X2203190Y3301288D01*
X2203810Y3303164D01*
Y3312122D01*
G01X2212800D02*
Y3299622D01*
G01X2209235Y3312122D02*
X2216365D01*
G01X2223185Y3303789D02*
X2227215D01*
G01X2234500Y3312122D02*
Y3299622D01*
X2240700D01*
G01X2246125D02*
X2250000Y3312122D01*
X2253875Y3299622D01*
G01X2252480Y3303997D02*
X2247520D01*
G01X2262400Y3299622D02*
Y3305247D01*
X2259300Y3312122D01*
G01X2265500D02*
X2262400Y3305247D01*
G01X2277900Y3299622D02*
X2271700D01*
Y3312122D01*
X2277900D01*
G01X2275420Y3306080D02*
X2271700D01*
G01X2284100Y3299622D02*
Y3312122D01*
X2287975D01*
X2289215Y3311497D01*
X2289990Y3310664D01*
X2290300Y3308997D01*
X2289990Y3307330D01*
X2289060Y3306289D01*
X2287975Y3305664D01*
X2284100D01*
G01X2287975D02*
X2290300Y3299622D01*
G01X1911635Y3318372D02*
Y3330872D01*
X1918765Y3318372D01*
Y3330872D01*
G01X1927600Y3318372D02*
X1926360Y3318580D01*
X1925275Y3319413D01*
X1924345Y3320664D01*
X1923725Y3322122D01*
X1923415Y3323789D01*
Y3325455D01*
X1923725Y3327122D01*
X1924345Y3328580D01*
X1925275Y3329830D01*
X1926360Y3330664D01*
X1927600Y3330872D01*
X1928840Y3330664D01*
X1929925Y3329830D01*
X1930855Y3328580D01*
X1931475Y3327122D01*
X1931785Y3325455D01*
Y3323789D01*
X1931475Y3322122D01*
X1930855Y3320664D01*
X1929925Y3319413D01*
X1928840Y3318580D01*
X1927600Y3318372D01*
G01X1940000Y3330872D02*
Y3318372D01*
G01X1936435Y3330872D02*
X1943565D01*
G01X1955500Y3318372D02*
X1949300D01*
Y3330872D01*
X1955500D01*
G01X1953020Y3324830D02*
X1949300D01*
G01X1961545Y3320038D02*
X1962785Y3318997D01*
X1964180Y3318372D01*
X1965420D01*
X1966660Y3318997D01*
X1967590Y3320038D01*
X1968055Y3321497D01*
X1967745Y3322955D01*
X1966970Y3324205D01*
X1965575Y3325039D01*
X1963715Y3325455D01*
X1962630Y3326289D01*
X1962165Y3327747D01*
X1962475Y3329205D01*
X1963250Y3330247D01*
X1964335Y3330872D01*
X1965420D01*
X1966505Y3330455D01*
X1967435Y3329414D01*
G01X1977200Y3317955D02*
X1976890Y3318164D01*
Y3318580D01*
X1977200Y3318789D01*
X1977510Y3318580D01*
Y3318164D01*
X1977200Y3317955D01*
G01Y3323580D02*
X1976890Y3323789D01*
Y3324205D01*
X1977200Y3324414D01*
X1977510Y3324205D01*
Y3323789D01*
X1977200Y3323580D01*
G01X2077090Y3521029D02*
X2077710Y3521654D01*
X2078175Y3522695D01*
X2078485Y3524154D01*
X2078175Y3525404D01*
X2077555Y3526237D01*
X2076470Y3526862D01*
X2072285D01*
Y3514362D01*
X2077400D01*
X2078485Y3515195D01*
X2079105Y3516445D01*
X2079415Y3517904D01*
X2079105Y3519362D01*
X2078175Y3520612D01*
X2077090Y3521029D01*
X2072285D01*
G01X2084375Y3514362D02*
X2088250Y3526862D01*
X2092125Y3514362D01*
G01X2090730Y3518737D02*
X2085770D01*
G01X2104060Y3525820D02*
X2103130Y3526445D01*
X2102045Y3526862D01*
X2100805D01*
X2099410Y3526237D01*
X2098325Y3525195D01*
X2097550Y3523945D01*
X2096930Y3521862D01*
X2096775Y3519987D01*
X2097085Y3518112D01*
X2097550Y3516862D01*
X2098480Y3515612D01*
X2099565Y3514779D01*
X2100650Y3514362D01*
X2101735D01*
X2102820Y3514779D01*
X2103750Y3515403D01*
X2104525Y3516237D01*
G01X2109640Y3514362D02*
Y3526862D01*
G01X2115530D02*
X2109640Y3519153D01*
G01X2116460Y3514362D02*
X2112275Y3522695D01*
G01X2122040Y3514362D02*
Y3526862D01*
X2125140D01*
X2126380Y3526237D01*
X2127310Y3525404D01*
X2128085Y3524154D01*
X2128705Y3522695D01*
X2128860Y3520612D01*
X2128705Y3518529D01*
X2128085Y3517070D01*
X2127310Y3515820D01*
X2126380Y3514987D01*
X2125140Y3514362D01*
X2122040D01*
G01X2134750D02*
Y3526862D01*
X2138625D01*
X2139865Y3526237D01*
X2140640Y3525404D01*
X2140950Y3523737D01*
X2140640Y3522070D01*
X2139710Y3521029D01*
X2138625Y3520404D01*
X2134750D01*
G01X2138625D02*
X2140950Y3514362D01*
G01X2148390Y3526862D02*
X2152110D01*
G01X2150250D02*
Y3514362D01*
G01X2148390D02*
X2152110D01*
G01X2159550Y3526862D02*
Y3514362D01*
X2165750D01*
G01X2171950Y3526862D02*
Y3514362D01*
X2178150D01*
G01X2196595Y3516028D02*
X2197835Y3514987D01*
X2199230Y3514362D01*
X2200470D01*
X2201710Y3514987D01*
X2202640Y3516028D01*
X2203105Y3517487D01*
X2202795Y3518945D01*
X2202020Y3520195D01*
X2200625Y3521029D01*
X2198765Y3521445D01*
X2197680Y3522279D01*
X2197215Y3523737D01*
X2197525Y3525195D01*
X2198300Y3526237D01*
X2199385Y3526862D01*
X2200470D01*
X2201555Y3526445D01*
X2202485Y3525404D01*
G01X2212250Y3526862D02*
Y3514362D01*
G01X2208685Y3526862D02*
X2215815D01*
G01X2221240D02*
Y3517904D01*
X2221860Y3516028D01*
X2223100Y3514779D01*
X2224650Y3514362D01*
X2226200Y3514779D01*
X2227440Y3516028D01*
X2228060Y3517904D01*
Y3526862D01*
G01X2238290Y3521029D02*
X2238910Y3521654D01*
X2239375Y3522695D01*
X2239685Y3524154D01*
X2239375Y3525404D01*
X2238755Y3526237D01*
X2237670Y3526862D01*
X2233485D01*
Y3514362D01*
X2238600D01*
X2239685Y3515195D01*
X2240305Y3516445D01*
X2240615Y3517904D01*
X2240305Y3519362D01*
X2239375Y3520612D01*
X2238290Y3521029D01*
X2233485D01*
G01X2258750Y3526862D02*
Y3514362D01*
X2264950D01*
G01X2277350D02*
X2271150D01*
Y3526862D01*
X2277350D01*
G01X2274870Y3520820D02*
X2271150D01*
G01X2283085Y3514362D02*
Y3526862D01*
X2290215Y3514362D01*
Y3526862D01*
G01X2299980Y3520612D02*
X2303080D01*
Y3516862D01*
X2302150Y3515612D01*
X2301065Y3514779D01*
X2299515Y3514362D01*
X2297965Y3514779D01*
X2296880Y3515612D01*
X2295950Y3516862D01*
X2295330Y3518320D01*
X2295020Y3519987D01*
Y3521445D01*
X2295330Y3522695D01*
X2295950Y3524154D01*
X2296880Y3525404D01*
X2297810Y3526237D01*
X2299050Y3526862D01*
X2300135D01*
X2301375Y3526445D01*
X2302305Y3525612D01*
G01X2311450Y3526862D02*
Y3514362D01*
G01X2307885Y3526862D02*
X2315015D01*
G01X2320595Y3514362D02*
Y3526862D01*
G01X2327105D02*
Y3514362D01*
G01Y3520612D02*
X2320595D01*
G01X2348650Y3526862D02*
Y3514362D01*
G01X2345085Y3526862D02*
X2352215D01*
G01X2361050Y3514362D02*
X2359810Y3514570D01*
X2358725Y3515403D01*
X2357795Y3516654D01*
X2357175Y3518112D01*
X2356865Y3519779D01*
Y3521445D01*
X2357175Y3523112D01*
X2357795Y3524570D01*
X2358725Y3525820D01*
X2359810Y3526654D01*
X2361050Y3526862D01*
X2362290Y3526654D01*
X2363375Y3525820D01*
X2364305Y3524570D01*
X2364925Y3523112D01*
X2365235Y3521445D01*
Y3519779D01*
X2364925Y3518112D01*
X2364305Y3516654D01*
X2363375Y3515403D01*
X2362290Y3514570D01*
X2361050Y3514362D01*
G01X2370350Y3526862D02*
Y3514362D01*
X2376550D01*
G01X2388950D02*
X2382750D01*
Y3526862D01*
X2388950D01*
G01X2386470Y3520820D02*
X2382750D01*
G01X2395150Y3514362D02*
Y3526862D01*
X2399025D01*
X2400265Y3526237D01*
X2401040Y3525404D01*
X2401350Y3523737D01*
X2401040Y3522070D01*
X2400110Y3521029D01*
X2399025Y3520404D01*
X2395150D01*
G01X2399025D02*
X2401350Y3514362D01*
G01X2406775D02*
X2410650Y3526862D01*
X2414525Y3514362D01*
G01X2413130Y3518737D02*
X2408170D01*
G01X2419485Y3514362D02*
Y3526862D01*
X2426615Y3514362D01*
Y3526862D01*
G01X2438860Y3525820D02*
X2437930Y3526445D01*
X2436845Y3526862D01*
X2435605D01*
X2434210Y3526237D01*
X2433125Y3525195D01*
X2432350Y3523945D01*
X2431730Y3521862D01*
X2431575Y3519987D01*
X2431885Y3518112D01*
X2432350Y3516862D01*
X2433280Y3515612D01*
X2434365Y3514779D01*
X2435450Y3514362D01*
X2436535D01*
X2437620Y3514779D01*
X2438550Y3515403D01*
X2439325Y3516237D01*
G01X2450950Y3514362D02*
X2444750D01*
Y3526862D01*
X2450950D01*
G01X2448470Y3520820D02*
X2444750D01*
G01X2472650Y3526862D02*
Y3514362D01*
G01X2469085Y3526862D02*
X2476215D01*
G01X2485050Y3514362D02*
X2483810Y3514570D01*
X2482725Y3515403D01*
X2481795Y3516654D01*
X2481175Y3518112D01*
X2480865Y3519779D01*
Y3521445D01*
X2481175Y3523112D01*
X2481795Y3524570D01*
X2482725Y3525820D01*
X2483810Y3526654D01*
X2485050Y3526862D01*
X2486290Y3526654D01*
X2487375Y3525820D01*
X2488305Y3524570D01*
X2488925Y3523112D01*
X2489235Y3521445D01*
Y3519779D01*
X2488925Y3518112D01*
X2488305Y3516654D01*
X2487375Y3515403D01*
X2486290Y3514570D01*
X2485050Y3514362D01*
G01X2511090Y3521029D02*
X2511710Y3521654D01*
X2512175Y3522695D01*
X2512485Y3524154D01*
X2512175Y3525404D01*
X2511555Y3526237D01*
X2510470Y3526862D01*
X2506285D01*
Y3514362D01*
X2511400D01*
X2512485Y3515195D01*
X2513105Y3516445D01*
X2513415Y3517904D01*
X2513105Y3519362D01*
X2512175Y3520612D01*
X2511090Y3521029D01*
X2506285D01*
G01X2525350Y3514362D02*
X2519150D01*
Y3526862D01*
X2525350D01*
G01X2522870Y3520820D02*
X2519150D01*
G01X2546740Y3514362D02*
X2547050Y3517070D01*
X2547515Y3519362D01*
X2548135Y3521445D01*
X2548910Y3523737D01*
X2550150Y3526862D01*
X2543950D01*
G01X2570145Y3518529D02*
X2573865D01*
G01X2571850Y3521237D02*
Y3515820D01*
G01X2581460Y3513945D02*
X2587040Y3526862D01*
G01X2594635Y3518529D02*
X2598665D01*
G01X2605640Y3516237D02*
X2606570Y3515195D01*
X2607655Y3514570D01*
X2609050Y3514362D01*
X2610445Y3514779D01*
X2611530Y3515612D01*
X2612305Y3517070D01*
X2612460Y3518737D01*
X2612150Y3520404D01*
X2611375Y3521445D01*
X2610290Y3522279D01*
X2609205Y3522487D01*
X2608120Y3522279D01*
X2606725Y3521445D01*
X2607190Y3526862D01*
X2611375D01*
G01X2629820Y3514362D02*
Y3526862D01*
X2633850Y3516445D01*
X2637880Y3526862D01*
Y3514362D01*
G01X2644390Y3526862D02*
X2648110D01*
G01X2646250D02*
Y3514362D01*
G01X2644390D02*
X2648110D01*
G01X2655550Y3526862D02*
Y3514362D01*
X2661750D01*
G01X2667795Y3516028D02*
X2669035Y3514987D01*
X2670430Y3514362D01*
X2671670D01*
X2672910Y3514987D01*
X2673840Y3516028D01*
X2674305Y3517487D01*
X2673995Y3518945D01*
X2673220Y3520195D01*
X2671825Y3521029D01*
X2669965Y3521445D01*
X2668880Y3522279D01*
X2668415Y3523737D01*
X2668725Y3525195D01*
X2669500Y3526237D01*
X2670585Y3526862D01*
X2671670D01*
X2672755Y3526445D01*
X2673685Y3525404D01*
G01X1912635Y3537279D02*
X1916665D01*
G01X1935420Y3533112D02*
Y3545612D01*
X1939450Y3535195D01*
X1943480Y3545612D01*
Y3533112D01*
G01X1948905D02*
Y3545612D01*
X1954795D01*
G01X1952625Y3539570D02*
X1948905D01*
G01X1965180Y3539362D02*
X1968280D01*
Y3535612D01*
X1967350Y3534362D01*
X1966265Y3533529D01*
X1964715Y3533112D01*
X1963165Y3533529D01*
X1962080Y3534362D01*
X1961150Y3535612D01*
X1960530Y3537070D01*
X1960220Y3538737D01*
Y3540195D01*
X1960530Y3541445D01*
X1961150Y3542904D01*
X1962080Y3544154D01*
X1963010Y3544987D01*
X1964250Y3545612D01*
X1965335D01*
X1966575Y3545195D01*
X1967505Y3544362D01*
G01X1972000Y3528945D02*
X1981300D01*
G01X1985795Y3534778D02*
X1987035Y3533737D01*
X1988430Y3533112D01*
X1989670D01*
X1990910Y3533737D01*
X1991840Y3534778D01*
X1992305Y3536237D01*
X1991995Y3537695D01*
X1991220Y3538945D01*
X1989825Y3539779D01*
X1987965Y3540195D01*
X1986880Y3541029D01*
X1986415Y3542487D01*
X1986725Y3543945D01*
X1987500Y3544987D01*
X1988585Y3545612D01*
X1989670D01*
X1990755Y3545195D01*
X1991685Y3544154D01*
G01X2001450Y3545612D02*
Y3533112D01*
G01X1997885Y3545612D02*
X2005015D01*
G01X2010440D02*
Y3536654D01*
X2011060Y3534778D01*
X2012300Y3533529D01*
X2013850Y3533112D01*
X2015400Y3533529D01*
X2016640Y3534778D01*
X2017260Y3536654D01*
Y3545612D01*
G01X2027490Y3539779D02*
X2028110Y3540404D01*
X2028575Y3541445D01*
X2028885Y3542904D01*
X2028575Y3544154D01*
X2027955Y3544987D01*
X2026870Y3545612D01*
X2022685D01*
Y3533112D01*
X2027800D01*
X2028885Y3533945D01*
X2029505Y3535195D01*
X2029815Y3536654D01*
X2029505Y3538112D01*
X2028575Y3539362D01*
X2027490Y3539779D01*
X2022685D01*
G01X2051050Y3532695D02*
X2050740Y3532904D01*
Y3533320D01*
X2051050Y3533529D01*
X2051360Y3533320D01*
Y3532904D01*
X2051050Y3532695D01*
G01Y3538320D02*
X2050740Y3538529D01*
Y3538945D01*
X2051050Y3539154D01*
X2051360Y3538945D01*
Y3538529D01*
X2051050Y3538320D01*
G01X2071820Y3533112D02*
Y3545612D01*
X2075850Y3535195D01*
X2079880Y3545612D01*
Y3533112D01*
G01X2084375D02*
X2088250Y3545612D01*
X2092125Y3533112D01*
G01X2090730Y3537487D02*
X2085770D01*
G01X2097085Y3533112D02*
Y3545612D01*
X2104215Y3533112D01*
Y3545612D01*
G01X2109640D02*
Y3536654D01*
X2110260Y3534778D01*
X2111500Y3533529D01*
X2113050Y3533112D01*
X2114600Y3533529D01*
X2115840Y3534778D01*
X2116460Y3536654D01*
Y3545612D01*
G01X2122505Y3533112D02*
Y3545612D01*
X2128395D01*
G01X2126225Y3539570D02*
X2122505D01*
G01X2133975Y3533112D02*
X2137850Y3545612D01*
X2141725Y3533112D01*
G01X2140330Y3537487D02*
X2135370D01*
G01X2153660Y3544570D02*
X2152730Y3545195D01*
X2151645Y3545612D01*
X2150405D01*
X2149010Y3544987D01*
X2147925Y3543945D01*
X2147150Y3542695D01*
X2146530Y3540612D01*
X2146375Y3538737D01*
X2146685Y3536862D01*
X2147150Y3535612D01*
X2148080Y3534362D01*
X2149165Y3533529D01*
X2150250Y3533112D01*
X2151335D01*
X2152420Y3533529D01*
X2153350Y3534153D01*
X2154125Y3534987D01*
G01X2162650Y3545612D02*
Y3533112D01*
G01X2159085Y3545612D02*
X2166215D01*
G01X2171640D02*
Y3536654D01*
X2172260Y3534778D01*
X2173500Y3533529D01*
X2175050Y3533112D01*
X2176600Y3533529D01*
X2177840Y3534778D01*
X2178460Y3536654D01*
Y3545612D01*
G01X2184350Y3533112D02*
Y3545612D01*
X2188225D01*
X2189465Y3544987D01*
X2190240Y3544154D01*
X2190550Y3542487D01*
X2190240Y3540820D01*
X2189310Y3539779D01*
X2188225Y3539154D01*
X2184350D01*
G01X2188225D02*
X2190550Y3533112D01*
G01X2197990Y3545612D02*
X2201710D01*
G01X2199850D02*
Y3533112D01*
G01X2197990D02*
X2201710D01*
G01X2208685D02*
Y3545612D01*
X2215815Y3533112D01*
Y3545612D01*
G01X2225580Y3539362D02*
X2228680D01*
Y3535612D01*
X2227750Y3534362D01*
X2226665Y3533529D01*
X2225115Y3533112D01*
X2223565Y3533529D01*
X2222480Y3534362D01*
X2221550Y3535612D01*
X2220930Y3537070D01*
X2220620Y3538737D01*
Y3540195D01*
X2220930Y3541445D01*
X2221550Y3542904D01*
X2222480Y3544154D01*
X2223410Y3544987D01*
X2224650Y3545612D01*
X2225735D01*
X2226975Y3545195D01*
X2227905Y3544362D01*
G01X2246195Y3534778D02*
X2247435Y3533737D01*
X2248830Y3533112D01*
X2250070D01*
X2251310Y3533737D01*
X2252240Y3534778D01*
X2252705Y3536237D01*
X2252395Y3537695D01*
X2251620Y3538945D01*
X2250225Y3539779D01*
X2248365Y3540195D01*
X2247280Y3541029D01*
X2246815Y3542487D01*
X2247125Y3543945D01*
X2247900Y3544987D01*
X2248985Y3545612D01*
X2250070D01*
X2251155Y3545195D01*
X2252085Y3544154D01*
G01X2261850Y3545612D02*
Y3533112D01*
G01X2258285Y3545612D02*
X2265415D01*
G01X2270840D02*
Y3536654D01*
X2271460Y3534778D01*
X2272700Y3533529D01*
X2274250Y3533112D01*
X2275800Y3533529D01*
X2277040Y3534778D01*
X2277660Y3536654D01*
Y3545612D01*
G01X2287890Y3539779D02*
X2288510Y3540404D01*
X2288975Y3541445D01*
X2289285Y3542904D01*
X2288975Y3544154D01*
X2288355Y3544987D01*
X2287270Y3545612D01*
X2283085D01*
Y3533112D01*
X2288200D01*
X2289285Y3533945D01*
X2289905Y3535195D01*
X2290215Y3536654D01*
X2289905Y3538112D01*
X2288975Y3539362D01*
X2287890Y3539779D01*
X2283085D01*
G01X2308350Y3545612D02*
Y3533112D01*
X2314550D01*
G01X2326950D02*
X2320750D01*
Y3545612D01*
X2326950D01*
G01X2324470Y3539570D02*
X2320750D01*
G01X2332685Y3533112D02*
Y3545612D01*
X2339815Y3533112D01*
Y3545612D01*
G01X2349580Y3539362D02*
X2352680D01*
Y3535612D01*
X2351750Y3534362D01*
X2350665Y3533529D01*
X2349115Y3533112D01*
X2347565Y3533529D01*
X2346480Y3534362D01*
X2345550Y3535612D01*
X2344930Y3537070D01*
X2344620Y3538737D01*
Y3540195D01*
X2344930Y3541445D01*
X2345550Y3542904D01*
X2346480Y3544154D01*
X2347410Y3544987D01*
X2348650Y3545612D01*
X2349735D01*
X2350975Y3545195D01*
X2351905Y3544362D01*
G01X2361050Y3545612D02*
Y3533112D01*
G01X2357485Y3545612D02*
X2364615D01*
G01X2370195Y3533112D02*
Y3545612D01*
G01X2376705D02*
Y3533112D01*
G01Y3539362D02*
X2370195D01*
G01X2072595Y3553528D02*
X2073835Y3552487D01*
X2075230Y3551862D01*
X2076470D01*
X2077710Y3552487D01*
X2078640Y3553528D01*
X2079105Y3554987D01*
X2078795Y3556445D01*
X2078020Y3557695D01*
X2076625Y3558529D01*
X2074765Y3558945D01*
X2073680Y3559779D01*
X2073215Y3561237D01*
X2073525Y3562695D01*
X2074300Y3563737D01*
X2075385Y3564362D01*
X2076470D01*
X2077555Y3563945D01*
X2078485Y3562904D01*
G01X2084840Y3564362D02*
Y3555404D01*
X2085460Y3553528D01*
X2086700Y3552279D01*
X2088250Y3551862D01*
X2089800Y3552279D01*
X2091040Y3553528D01*
X2091660Y3555404D01*
Y3564362D01*
G01X2097550Y3551862D02*
Y3564362D01*
X2101425D01*
X2102665Y3563737D01*
X2103440Y3562904D01*
X2103750Y3561237D01*
X2103440Y3559570D01*
X2102510Y3558529D01*
X2101425Y3557904D01*
X2097550D01*
G01X2101425D02*
X2103750Y3551862D01*
G01X2110105D02*
Y3564362D01*
X2115995D01*
G01X2113825Y3558320D02*
X2110105D01*
G01X2121575Y3551862D02*
X2125450Y3564362D01*
X2129325Y3551862D01*
G01X2127930Y3556237D02*
X2122970D01*
G01X2141260Y3563320D02*
X2140330Y3563945D01*
X2139245Y3564362D01*
X2138005D01*
X2136610Y3563737D01*
X2135525Y3562695D01*
X2134750Y3561445D01*
X2134130Y3559362D01*
X2133975Y3557487D01*
X2134285Y3555612D01*
X2134750Y3554362D01*
X2135680Y3553112D01*
X2136765Y3552279D01*
X2137850Y3551862D01*
X2138935D01*
X2140020Y3552279D01*
X2140950Y3552903D01*
X2141725Y3553737D01*
G01X2153350Y3551862D02*
X2147150D01*
Y3564362D01*
X2153350D01*
G01X2150870Y3558320D02*
X2147150D01*
G01X2175050Y3551862D02*
X2173810Y3552070D01*
X2172725Y3552903D01*
X2171795Y3554154D01*
X2171175Y3555612D01*
X2170865Y3557279D01*
Y3558945D01*
X2171175Y3560612D01*
X2171795Y3562070D01*
X2172725Y3563320D01*
X2173810Y3564154D01*
X2175050Y3564362D01*
X2176290Y3564154D01*
X2177375Y3563320D01*
X2178305Y3562070D01*
X2178925Y3560612D01*
X2179235Y3558945D01*
Y3557279D01*
X2178925Y3555612D01*
X2178305Y3554154D01*
X2177375Y3552903D01*
X2176290Y3552070D01*
X2175050Y3551862D01*
G01X2184505D02*
Y3564362D01*
X2190395D01*
G01X2188225Y3558320D02*
X2184505D01*
G01X2208220Y3551862D02*
Y3564362D01*
X2212250Y3553945D01*
X2216280Y3564362D01*
Y3551862D01*
G01X2221240Y3564362D02*
Y3555404D01*
X2221860Y3553528D01*
X2223100Y3552279D01*
X2224650Y3551862D01*
X2226200Y3552279D01*
X2227440Y3553528D01*
X2228060Y3555404D01*
Y3564362D01*
G01X2233795Y3553528D02*
X2235035Y3552487D01*
X2236430Y3551862D01*
X2237670D01*
X2238910Y3552487D01*
X2239840Y3553528D01*
X2240305Y3554987D01*
X2239995Y3556445D01*
X2239220Y3557695D01*
X2237825Y3558529D01*
X2235965Y3558945D01*
X2234880Y3559779D01*
X2234415Y3561237D01*
X2234725Y3562695D01*
X2235500Y3563737D01*
X2236585Y3564362D01*
X2237670D01*
X2238755Y3563945D01*
X2239685Y3562904D01*
G01X2249450Y3564362D02*
Y3551862D01*
G01X2245885Y3564362D02*
X2253015D01*
G01X2259835Y3556029D02*
X2263865D01*
G01X2270685Y3551862D02*
Y3564362D01*
X2277815Y3551862D01*
Y3564362D01*
G01X2286650Y3551862D02*
X2285410Y3552070D01*
X2284325Y3552903D01*
X2283395Y3554154D01*
X2282775Y3555612D01*
X2282465Y3557279D01*
Y3558945D01*
X2282775Y3560612D01*
X2283395Y3562070D01*
X2284325Y3563320D01*
X2285410Y3564154D01*
X2286650Y3564362D01*
X2287890Y3564154D01*
X2288975Y3563320D01*
X2289905Y3562070D01*
X2290525Y3560612D01*
X2290835Y3558945D01*
Y3557279D01*
X2290525Y3555612D01*
X2289905Y3554154D01*
X2288975Y3552903D01*
X2287890Y3552070D01*
X2286650Y3551862D01*
G01X2299050Y3564362D02*
Y3551862D01*
G01X2295485Y3564362D02*
X2302615D01*
G01X2309435Y3556029D02*
X2313465D01*
G01X2327260Y3563320D02*
X2326330Y3563945D01*
X2325245Y3564362D01*
X2324005D01*
X2322610Y3563737D01*
X2321525Y3562695D01*
X2320750Y3561445D01*
X2320130Y3559362D01*
X2319975Y3557487D01*
X2320285Y3555612D01*
X2320750Y3554362D01*
X2321680Y3553112D01*
X2322765Y3552279D01*
X2323850Y3551862D01*
X2324935D01*
X2326020Y3552279D01*
X2326950Y3552903D01*
X2327725Y3553737D01*
G01X2332840Y3564362D02*
Y3555404D01*
X2333460Y3553528D01*
X2334700Y3552279D01*
X2336250Y3551862D01*
X2337800Y3552279D01*
X2339040Y3553528D01*
X2339660Y3555404D01*
Y3564362D01*
G01X2348650D02*
Y3551862D01*
G01X2345085Y3564362D02*
X2352215D01*
G01X2359035Y3556029D02*
X2363065D01*
G01X2370350Y3564362D02*
Y3551862D01*
X2376550D01*
G01X2381975D02*
X2385850Y3564362D01*
X2389725Y3551862D01*
G01X2388330Y3556237D02*
X2383370D01*
G01X2398250Y3551862D02*
Y3557487D01*
X2395150Y3564362D01*
G01X2401350D02*
X2398250Y3557487D01*
G01X2413750Y3551862D02*
X2407550D01*
Y3564362D01*
X2413750D01*
G01X2411270Y3558320D02*
X2407550D01*
G01X2419950Y3551862D02*
Y3564362D01*
X2423825D01*
X2425065Y3563737D01*
X2425840Y3562904D01*
X2426150Y3561237D01*
X2425840Y3559570D01*
X2424910Y3558529D01*
X2423825Y3557904D01*
X2419950D01*
G01X2423825D02*
X2426150Y3551862D01*
G01X1912635Y3574779D02*
X1916665D01*
G01X1935420Y3570612D02*
Y3583112D01*
X1939450Y3572695D01*
X1943480Y3583112D01*
Y3570612D01*
G01X1947975D02*
X1951850Y3583112D01*
X1955725Y3570612D01*
G01X1954330Y3574987D02*
X1949370D01*
G01X1960995Y3570612D02*
X1967505Y3583112D01*
G01X1960995D02*
X1967505Y3570612D01*
G01X1972000Y3566445D02*
X1981300D01*
G01X1985640Y3570612D02*
Y3583112D01*
X1988740D01*
X1989980Y3582487D01*
X1990910Y3581654D01*
X1991685Y3580404D01*
X1992305Y3578945D01*
X1992460Y3576862D01*
X1992305Y3574779D01*
X1991685Y3573320D01*
X1990910Y3572070D01*
X1989980Y3571237D01*
X1988740Y3570612D01*
X1985640D01*
G01X2004550D02*
X1998350D01*
Y3583112D01*
X2004550D01*
G01X2002070Y3577070D02*
X1998350D01*
G01X2010750Y3570612D02*
Y3583112D01*
X2014470D01*
X2015710Y3582487D01*
X2016640Y3581029D01*
X2016950Y3579362D01*
X2016640Y3577695D01*
X2015865Y3576445D01*
X2014470Y3575820D01*
X2010750D01*
G01X2026250Y3583112D02*
Y3570612D01*
G01X2022685Y3583112D02*
X2029815D01*
G01X2035395Y3570612D02*
Y3583112D01*
G01X2041905D02*
Y3570612D01*
G01Y3576862D02*
X2035395D01*
G01X2051050Y3570195D02*
X2050740Y3570404D01*
Y3570820D01*
X2051050Y3571029D01*
X2051360Y3570820D01*
Y3570404D01*
X2051050Y3570195D01*
G01Y3575820D02*
X2050740Y3576029D01*
Y3576445D01*
X2051050Y3576654D01*
X2051360Y3576445D01*
Y3576029D01*
X2051050Y3575820D01*
G01X2072440Y3570612D02*
Y3583112D01*
X2075540D01*
X2076780Y3582487D01*
X2077710Y3581654D01*
X2078485Y3580404D01*
X2079105Y3578945D01*
X2079260Y3576862D01*
X2079105Y3574779D01*
X2078485Y3573320D01*
X2077710Y3572070D01*
X2076780Y3571237D01*
X2075540Y3570612D01*
X2072440D01*
G01X2091350D02*
X2085150D01*
Y3583112D01*
X2091350D01*
G01X2088870Y3577070D02*
X2085150D01*
G01X2097550Y3570612D02*
Y3583112D01*
X2101270D01*
X2102510Y3582487D01*
X2103440Y3581029D01*
X2103750Y3579362D01*
X2103440Y3577695D01*
X2102665Y3576445D01*
X2101270Y3575820D01*
X2097550D01*
G01X2113050Y3583112D02*
Y3570612D01*
G01X2109485Y3583112D02*
X2116615D01*
G01X2122195Y3570612D02*
Y3583112D01*
G01X2128705D02*
Y3570612D01*
G01Y3576862D02*
X2122195D01*
G01X2147305Y3570612D02*
Y3583112D01*
X2153195D01*
G01X2151025Y3577070D02*
X2147305D01*
G01X2159550Y3570612D02*
Y3583112D01*
X2163425D01*
X2164665Y3582487D01*
X2165440Y3581654D01*
X2165750Y3579987D01*
X2165440Y3578320D01*
X2164510Y3577279D01*
X2163425Y3576654D01*
X2159550D01*
G01X2163425D02*
X2165750Y3570612D01*
G01X2175050D02*
X2173810Y3570820D01*
X2172725Y3571653D01*
X2171795Y3572904D01*
X2171175Y3574362D01*
X2170865Y3576029D01*
Y3577695D01*
X2171175Y3579362D01*
X2171795Y3580820D01*
X2172725Y3582070D01*
X2173810Y3582904D01*
X2175050Y3583112D01*
X2176290Y3582904D01*
X2177375Y3582070D01*
X2178305Y3580820D01*
X2178925Y3579362D01*
X2179235Y3577695D01*
Y3576029D01*
X2178925Y3574362D01*
X2178305Y3572904D01*
X2177375Y3571653D01*
X2176290Y3570820D01*
X2175050Y3570612D01*
G01X2183420D02*
Y3583112D01*
X2187450Y3572695D01*
X2191480Y3583112D01*
Y3570612D01*
G01X2208995Y3572278D02*
X2210235Y3571237D01*
X2211630Y3570612D01*
X2212870D01*
X2214110Y3571237D01*
X2215040Y3572278D01*
X2215505Y3573737D01*
X2215195Y3575195D01*
X2214420Y3576445D01*
X2213025Y3577279D01*
X2211165Y3577695D01*
X2210080Y3578529D01*
X2209615Y3579987D01*
X2209925Y3581445D01*
X2210700Y3582487D01*
X2211785Y3583112D01*
X2212870D01*
X2213955Y3582695D01*
X2214885Y3581654D01*
G01X2224650Y3583112D02*
Y3570612D01*
G01X2221085Y3583112D02*
X2228215D01*
G01X2233175Y3570612D02*
X2237050Y3583112D01*
X2240925Y3570612D01*
G01X2239530Y3574987D02*
X2234570D01*
G01X2246350Y3570612D02*
Y3583112D01*
X2250225D01*
X2251465Y3582487D01*
X2252240Y3581654D01*
X2252550Y3579987D01*
X2252240Y3578320D01*
X2251310Y3577279D01*
X2250225Y3576654D01*
X2246350D01*
G01X2250225D02*
X2252550Y3570612D01*
G01X2261850Y3583112D02*
Y3570612D01*
G01X2258285Y3583112D02*
X2265415D01*
G01X2283550D02*
Y3570612D01*
X2289750D01*
G01X2295175D02*
X2299050Y3583112D01*
X2302925Y3570612D01*
G01X2301530Y3574987D02*
X2296570D01*
G01X2311450Y3570612D02*
Y3576237D01*
X2308350Y3583112D01*
G01X2314550D02*
X2311450Y3576237D01*
G01X2326950Y3570612D02*
X2320750D01*
Y3583112D01*
X2326950D01*
G01X2324470Y3577070D02*
X2320750D01*
G01X2333150Y3570612D02*
Y3583112D01*
X2337025D01*
X2338265Y3582487D01*
X2339040Y3581654D01*
X2339350Y3579987D01*
X2339040Y3578320D01*
X2338110Y3577279D01*
X2337025Y3576654D01*
X2333150D01*
G01X2337025D02*
X2339350Y3570612D01*
G01X2361050Y3583112D02*
Y3570612D01*
G01X2357485Y3583112D02*
X2364615D01*
G01X2373450Y3570612D02*
X2372210Y3570820D01*
X2371125Y3571653D01*
X2370195Y3572904D01*
X2369575Y3574362D01*
X2369265Y3576029D01*
Y3577695D01*
X2369575Y3579362D01*
X2370195Y3580820D01*
X2371125Y3582070D01*
X2372210Y3582904D01*
X2373450Y3583112D01*
X2374690Y3582904D01*
X2375775Y3582070D01*
X2376705Y3580820D01*
X2377325Y3579362D01*
X2377635Y3577695D01*
Y3576029D01*
X2377325Y3574362D01*
X2376705Y3572904D01*
X2375775Y3571653D01*
X2374690Y3570820D01*
X2373450Y3570612D01*
G01X2398250Y3583112D02*
Y3570612D01*
G01X2394685Y3583112D02*
X2401815D01*
G01X2407395Y3570612D02*
Y3583112D01*
G01X2413905D02*
Y3570612D01*
G01Y3576862D02*
X2407395D01*
G01X2426150Y3570612D02*
X2419950D01*
Y3583112D01*
X2426150D01*
G01X2423670Y3577070D02*
X2419950D01*
G01X1912635Y3593529D02*
X1916665D01*
G01X1935420Y3589362D02*
Y3601862D01*
X1939450Y3591445D01*
X1943480Y3601862D01*
Y3589362D01*
G01X1948285D02*
Y3601862D01*
X1955415Y3589362D01*
Y3601862D01*
G01X1967660Y3600820D02*
X1966730Y3601445D01*
X1965645Y3601862D01*
X1964405D01*
X1963010Y3601237D01*
X1961925Y3600195D01*
X1961150Y3598945D01*
X1960530Y3596862D01*
X1960375Y3594987D01*
X1960685Y3593112D01*
X1961150Y3591862D01*
X1962080Y3590612D01*
X1963165Y3589779D01*
X1964250Y3589362D01*
X1965335D01*
X1966420Y3589779D01*
X1967350Y3590403D01*
X1968125Y3591237D01*
G01X1972000Y3585195D02*
X1981300D01*
G01X1985950Y3601862D02*
Y3589362D01*
X1992150D01*
G01X1997575D02*
X2001450Y3601862D01*
X2005325Y3589362D01*
G01X2003930Y3593737D02*
X1998970D01*
G01X2013850Y3589362D02*
Y3594987D01*
X2010750Y3601862D01*
G01X2016950D02*
X2013850Y3594987D01*
G01X2029350Y3589362D02*
X2023150D01*
Y3601862D01*
X2029350D01*
G01X2026870Y3595820D02*
X2023150D01*
G01X2035550Y3589362D02*
Y3601862D01*
X2039425D01*
X2040665Y3601237D01*
X2041440Y3600404D01*
X2041750Y3598737D01*
X2041440Y3597070D01*
X2040510Y3596029D01*
X2039425Y3595404D01*
X2035550D01*
G01X2039425D02*
X2041750Y3589362D01*
G01X2051050Y3588945D02*
X2050740Y3589154D01*
Y3589570D01*
X2051050Y3589779D01*
X2051360Y3589570D01*
Y3589154D01*
X2051050Y3588945D01*
G01Y3594570D02*
X2050740Y3594779D01*
Y3595195D01*
X2051050Y3595404D01*
X2051360Y3595195D01*
Y3594779D01*
X2051050Y3594570D01*
G01X2071820Y3589362D02*
Y3601862D01*
X2075850Y3591445D01*
X2079880Y3601862D01*
Y3589362D01*
G01X2084840Y3601862D02*
Y3592904D01*
X2085460Y3591028D01*
X2086700Y3589779D01*
X2088250Y3589362D01*
X2089800Y3589779D01*
X2091040Y3591028D01*
X2091660Y3592904D01*
Y3601862D01*
G01X2097395Y3591028D02*
X2098635Y3589987D01*
X2100030Y3589362D01*
X2101270D01*
X2102510Y3589987D01*
X2103440Y3591028D01*
X2103905Y3592487D01*
X2103595Y3593945D01*
X2102820Y3595195D01*
X2101425Y3596029D01*
X2099565Y3596445D01*
X2098480Y3597279D01*
X2098015Y3598737D01*
X2098325Y3600195D01*
X2099100Y3601237D01*
X2100185Y3601862D01*
X2101270D01*
X2102355Y3601445D01*
X2103285Y3600404D01*
G01X2113050Y3601862D02*
Y3589362D01*
G01X2109485Y3601862D02*
X2116615D01*
G01X2123435Y3593529D02*
X2127465D01*
G01X2134285Y3589362D02*
Y3601862D01*
X2141415Y3589362D01*
Y3601862D01*
G01X2150250Y3589362D02*
X2149010Y3589570D01*
X2147925Y3590403D01*
X2146995Y3591654D01*
X2146375Y3593112D01*
X2146065Y3594779D01*
Y3596445D01*
X2146375Y3598112D01*
X2146995Y3599570D01*
X2147925Y3600820D01*
X2149010Y3601654D01*
X2150250Y3601862D01*
X2151490Y3601654D01*
X2152575Y3600820D01*
X2153505Y3599570D01*
X2154125Y3598112D01*
X2154435Y3596445D01*
Y3594779D01*
X2154125Y3593112D01*
X2153505Y3591654D01*
X2152575Y3590403D01*
X2151490Y3589570D01*
X2150250Y3589362D01*
G01X2162650Y3601862D02*
Y3589362D01*
G01X2159085Y3601862D02*
X2166215D01*
G01X2173035Y3593529D02*
X2177065D01*
G01X2190860Y3600820D02*
X2189930Y3601445D01*
X2188845Y3601862D01*
X2187605D01*
X2186210Y3601237D01*
X2185125Y3600195D01*
X2184350Y3598945D01*
X2183730Y3596862D01*
X2183575Y3594987D01*
X2183885Y3593112D01*
X2184350Y3591862D01*
X2185280Y3590612D01*
X2186365Y3589779D01*
X2187450Y3589362D01*
X2188535D01*
X2189620Y3589779D01*
X2190550Y3590403D01*
X2191325Y3591237D01*
G01X2196440Y3601862D02*
Y3592904D01*
X2197060Y3591028D01*
X2198300Y3589779D01*
X2199850Y3589362D01*
X2201400Y3589779D01*
X2202640Y3591028D01*
X2203260Y3592904D01*
Y3601862D01*
G01X2212250D02*
Y3589362D01*
G01X2208685Y3601862D02*
X2215815D01*
G01X2222635Y3593529D02*
X2226665D01*
G01X2233950Y3601862D02*
Y3589362D01*
X2240150D01*
G01X2245575D02*
X2249450Y3601862D01*
X2253325Y3589362D01*
G01X2251930Y3593737D02*
X2246970D01*
G01X2261850Y3589362D02*
Y3594987D01*
X2258750Y3601862D01*
G01X2264950D02*
X2261850Y3594987D01*
G01X2277350Y3589362D02*
X2271150D01*
Y3601862D01*
X2277350D01*
G01X2274870Y3595820D02*
X2271150D01*
G01X2283550Y3589362D02*
Y3601862D01*
X2287425D01*
X2288665Y3601237D01*
X2289440Y3600404D01*
X2289750Y3598737D01*
X2289440Y3597070D01*
X2288510Y3596029D01*
X2287425Y3595404D01*
X2283550D01*
G01X2287425D02*
X2289750Y3589362D01*
G01X1911085Y3608112D02*
Y3620612D01*
X1918215Y3608112D01*
Y3620612D01*
G01X1927050Y3608112D02*
X1925810Y3608320D01*
X1924725Y3609153D01*
X1923795Y3610404D01*
X1923175Y3611862D01*
X1922865Y3613529D01*
Y3615195D01*
X1923175Y3616862D01*
X1923795Y3618320D01*
X1924725Y3619570D01*
X1925810Y3620404D01*
X1927050Y3620612D01*
X1928290Y3620404D01*
X1929375Y3619570D01*
X1930305Y3618320D01*
X1930925Y3616862D01*
X1931235Y3615195D01*
Y3613529D01*
X1930925Y3611862D01*
X1930305Y3610404D01*
X1929375Y3609153D01*
X1928290Y3608320D01*
X1927050Y3608112D01*
G01X1939450Y3620612D02*
Y3608112D01*
G01X1935885Y3620612D02*
X1943015D01*
G01X1954950Y3608112D02*
X1948750D01*
Y3620612D01*
X1954950D01*
G01X1952470Y3614570D02*
X1948750D01*
G01X1960995Y3609778D02*
X1962235Y3608737D01*
X1963630Y3608112D01*
X1964870D01*
X1966110Y3608737D01*
X1967040Y3609778D01*
X1967505Y3611237D01*
X1967195Y3612695D01*
X1966420Y3613945D01*
X1965025Y3614779D01*
X1963165Y3615195D01*
X1962080Y3616029D01*
X1961615Y3617487D01*
X1961925Y3618945D01*
X1962700Y3619987D01*
X1963785Y3620612D01*
X1964870D01*
X1965955Y3620195D01*
X1966885Y3619154D01*
G01X1976650Y3607695D02*
X1976340Y3607904D01*
Y3608320D01*
X1976650Y3608529D01*
X1976960Y3608320D01*
Y3607904D01*
X1976650Y3607695D01*
G01Y3613320D02*
X1976340Y3613529D01*
Y3613945D01*
X1976650Y3614154D01*
X1976960Y3613945D01*
Y3613529D01*
X1976650Y3613320D01*
G01X1930510Y740460D02*
X1918010D01*
X1920510Y738600D01*
G01X1930510D02*
Y742320D01*
G01Y752550D02*
X1927802Y752860D01*
X1925510Y753325D01*
X1923427Y753945D01*
X1921135Y754720D01*
X1918010Y755960D01*
Y749760D01*
G01X1930510Y767120D02*
X1918010D01*
X1926968Y761385D01*
Y769135D01*
G01X1918010Y777660D02*
X1918427Y776420D01*
X1919468Y775490D01*
X1920718Y774870D01*
X1922385Y774405D01*
X1924260Y774250D01*
X1926135Y774405D01*
X1927802Y774870D01*
X1929052Y775490D01*
X1930093Y776420D01*
X1930510Y777660D01*
X1930093Y778900D01*
X1929052Y779830D01*
X1927802Y780450D01*
X1926135Y780915D01*
X1924260Y781070D01*
X1922385Y780915D01*
X1920718Y780450D01*
X1919468Y779830D01*
X1918427Y778900D01*
X1918010Y777660D01*
G01X1930510Y790060D02*
X1918010D01*
X1920510Y788200D01*
G01X1930510D02*
Y791920D01*
G01X1930927Y802460D02*
X1930718Y802150D01*
X1930302D01*
X1930093Y802460D01*
X1930302Y802770D01*
X1930718D01*
X1930927Y802460D01*
G01X1930510Y814860D02*
X1918010D01*
X1920510Y813000D01*
G01X1930510D02*
Y816720D01*
G01Y827260D02*
X1930302Y828345D01*
X1929677Y829585D01*
X1928635Y830360D01*
X1927177Y830670D01*
X1925719Y830360D01*
X1924468Y829430D01*
X1923843Y828035D01*
Y826485D01*
X1923427Y825555D01*
X1922385Y824780D01*
X1920927Y824470D01*
X1919468Y824935D01*
X1918427Y826020D01*
X1918010Y827260D01*
X1918427Y828500D01*
X1919468Y829585D01*
X1920927Y830050D01*
X1922385Y829740D01*
X1923427Y828965D01*
X1923843Y828035D01*
Y826485D01*
X1924468Y825090D01*
X1925719Y824160D01*
X1927177Y823850D01*
X1928635Y824160D01*
X1929677Y824935D01*
X1930302Y826175D01*
X1930510Y827260D01*
G01X2091170Y2531579D02*
X2091790Y2532204D01*
X2092255Y2533245D01*
X2092565Y2534704D01*
X2092255Y2535954D01*
X2091635Y2536787D01*
X2090550Y2537412D01*
X2086365D01*
Y2524912D01*
X2091480D01*
X2092565Y2525745D01*
X2093185Y2526995D01*
X2093495Y2528454D01*
X2093185Y2529912D01*
X2092255Y2531162D01*
X2091170Y2531579D01*
X2086365D01*
G01X2098455Y2524912D02*
X2102330Y2537412D01*
X2106205Y2524912D01*
G01X2104810Y2529287D02*
X2099850D01*
G01X2118140Y2536370D02*
X2117210Y2536995D01*
X2116125Y2537412D01*
X2114885D01*
X2113490Y2536787D01*
X2112405Y2535745D01*
X2111630Y2534495D01*
X2111010Y2532412D01*
X2110855Y2530537D01*
X2111165Y2528662D01*
X2111630Y2527412D01*
X2112560Y2526162D01*
X2113645Y2525329D01*
X2114730Y2524912D01*
X2115815D01*
X2116900Y2525329D01*
X2117830Y2525953D01*
X2118605Y2526787D01*
G01X2123720Y2524912D02*
Y2537412D01*
G01X2129610D02*
X2123720Y2529703D01*
G01X2130540Y2524912D02*
X2126355Y2533245D01*
G01X2136120Y2524912D02*
Y2537412D01*
X2139220D01*
X2140460Y2536787D01*
X2141390Y2535954D01*
X2142165Y2534704D01*
X2142785Y2533245D01*
X2142940Y2531162D01*
X2142785Y2529079D01*
X2142165Y2527620D01*
X2141390Y2526370D01*
X2140460Y2525537D01*
X2139220Y2524912D01*
X2136120D01*
G01X2148830D02*
Y2537412D01*
X2152705D01*
X2153945Y2536787D01*
X2154720Y2535954D01*
X2155030Y2534287D01*
X2154720Y2532620D01*
X2153790Y2531579D01*
X2152705Y2530954D01*
X2148830D01*
G01X2152705D02*
X2155030Y2524912D01*
G01X2162470Y2537412D02*
X2166190D01*
G01X2164330D02*
Y2524912D01*
G01X2162470D02*
X2166190D01*
G01X2173630Y2537412D02*
Y2524912D01*
X2179830D01*
G01X2186030Y2537412D02*
Y2524912D01*
X2192230D01*
G01X2210675Y2526578D02*
X2211915Y2525537D01*
X2213310Y2524912D01*
X2214550D01*
X2215790Y2525537D01*
X2216720Y2526578D01*
X2217185Y2528037D01*
X2216875Y2529495D01*
X2216100Y2530745D01*
X2214705Y2531579D01*
X2212845Y2531995D01*
X2211760Y2532829D01*
X2211295Y2534287D01*
X2211605Y2535745D01*
X2212380Y2536787D01*
X2213465Y2537412D01*
X2214550D01*
X2215635Y2536995D01*
X2216565Y2535954D01*
G01X2226330Y2537412D02*
Y2524912D01*
G01X2222765Y2537412D02*
X2229895D01*
G01X2235320D02*
Y2528454D01*
X2235940Y2526578D01*
X2237180Y2525329D01*
X2238730Y2524912D01*
X2240280Y2525329D01*
X2241520Y2526578D01*
X2242140Y2528454D01*
Y2537412D01*
G01X2252370Y2531579D02*
X2252990Y2532204D01*
X2253455Y2533245D01*
X2253765Y2534704D01*
X2253455Y2535954D01*
X2252835Y2536787D01*
X2251750Y2537412D01*
X2247565D01*
Y2524912D01*
X2252680D01*
X2253765Y2525745D01*
X2254385Y2526995D01*
X2254695Y2528454D01*
X2254385Y2529912D01*
X2253455Y2531162D01*
X2252370Y2531579D01*
X2247565D01*
G01X2272830Y2537412D02*
Y2524912D01*
X2279030D01*
G01X2291430D02*
X2285230D01*
Y2537412D01*
X2291430D01*
G01X2288950Y2531370D02*
X2285230D01*
G01X2297165Y2524912D02*
Y2537412D01*
X2304295Y2524912D01*
Y2537412D01*
G01X2314060Y2531162D02*
X2317160D01*
Y2527412D01*
X2316230Y2526162D01*
X2315145Y2525329D01*
X2313595Y2524912D01*
X2312045Y2525329D01*
X2310960Y2526162D01*
X2310030Y2527412D01*
X2309410Y2528870D01*
X2309100Y2530537D01*
Y2531995D01*
X2309410Y2533245D01*
X2310030Y2534704D01*
X2310960Y2535954D01*
X2311890Y2536787D01*
X2313130Y2537412D01*
X2314215D01*
X2315455Y2536995D01*
X2316385Y2536162D01*
G01X2325530Y2537412D02*
Y2524912D01*
G01X2321965Y2537412D02*
X2329095D01*
G01X2334675Y2524912D02*
Y2537412D01*
G01X2341185D02*
Y2524912D01*
G01Y2531162D02*
X2334675D01*
G01X2362730Y2537412D02*
Y2524912D01*
G01X2359165Y2537412D02*
X2366295D01*
G01X2375130Y2524912D02*
X2373890Y2525120D01*
X2372805Y2525953D01*
X2371875Y2527204D01*
X2371255Y2528662D01*
X2370945Y2530329D01*
Y2531995D01*
X2371255Y2533662D01*
X2371875Y2535120D01*
X2372805Y2536370D01*
X2373890Y2537204D01*
X2375130Y2537412D01*
X2376370Y2537204D01*
X2377455Y2536370D01*
X2378385Y2535120D01*
X2379005Y2533662D01*
X2379315Y2531995D01*
Y2530329D01*
X2379005Y2528662D01*
X2378385Y2527204D01*
X2377455Y2525953D01*
X2376370Y2525120D01*
X2375130Y2524912D01*
G01X2384430Y2537412D02*
Y2524912D01*
X2390630D01*
G01X2403030D02*
X2396830D01*
Y2537412D01*
X2403030D01*
G01X2400550Y2531370D02*
X2396830D01*
G01X2409230Y2524912D02*
Y2537412D01*
X2413105D01*
X2414345Y2536787D01*
X2415120Y2535954D01*
X2415430Y2534287D01*
X2415120Y2532620D01*
X2414190Y2531579D01*
X2413105Y2530954D01*
X2409230D01*
G01X2413105D02*
X2415430Y2524912D01*
G01X2420855D02*
X2424730Y2537412D01*
X2428605Y2524912D01*
G01X2427210Y2529287D02*
X2422250D01*
G01X2433565Y2524912D02*
Y2537412D01*
X2440695Y2524912D01*
Y2537412D01*
G01X2452940Y2536370D02*
X2452010Y2536995D01*
X2450925Y2537412D01*
X2449685D01*
X2448290Y2536787D01*
X2447205Y2535745D01*
X2446430Y2534495D01*
X2445810Y2532412D01*
X2445655Y2530537D01*
X2445965Y2528662D01*
X2446430Y2527412D01*
X2447360Y2526162D01*
X2448445Y2525329D01*
X2449530Y2524912D01*
X2450615D01*
X2451700Y2525329D01*
X2452630Y2525953D01*
X2453405Y2526787D01*
G01X2465030Y2524912D02*
X2458830D01*
Y2537412D01*
X2465030D01*
G01X2462550Y2531370D02*
X2458830D01*
G01X2486730Y2537412D02*
Y2524912D01*
G01X2483165Y2537412D02*
X2490295D01*
G01X2499130Y2524912D02*
X2497890Y2525120D01*
X2496805Y2525953D01*
X2495875Y2527204D01*
X2495255Y2528662D01*
X2494945Y2530329D01*
Y2531995D01*
X2495255Y2533662D01*
X2495875Y2535120D01*
X2496805Y2536370D01*
X2497890Y2537204D01*
X2499130Y2537412D01*
X2500370Y2537204D01*
X2501455Y2536370D01*
X2502385Y2535120D01*
X2503005Y2533662D01*
X2503315Y2531995D01*
Y2530329D01*
X2503005Y2528662D01*
X2502385Y2527204D01*
X2501455Y2525953D01*
X2500370Y2525120D01*
X2499130Y2524912D01*
G01X2525170Y2531579D02*
X2525790Y2532204D01*
X2526255Y2533245D01*
X2526565Y2534704D01*
X2526255Y2535954D01*
X2525635Y2536787D01*
X2524550Y2537412D01*
X2520365D01*
Y2524912D01*
X2525480D01*
X2526565Y2525745D01*
X2527185Y2526995D01*
X2527495Y2528454D01*
X2527185Y2529912D01*
X2526255Y2531162D01*
X2525170Y2531579D01*
X2520365D01*
G01X2539430Y2524912D02*
X2533230D01*
Y2537412D01*
X2539430D01*
G01X2536950Y2531370D02*
X2533230D01*
G01X2560820Y2524912D02*
X2561130Y2527620D01*
X2561595Y2529912D01*
X2562215Y2531995D01*
X2562990Y2534287D01*
X2564230Y2537412D01*
X2558030D01*
G01X2584225Y2529079D02*
X2587945D01*
G01X2585930Y2531787D02*
Y2526370D01*
G01X2595540Y2524495D02*
X2601120Y2537412D01*
G01X2608715Y2529079D02*
X2612745D01*
G01X2619720Y2526787D02*
X2620650Y2525745D01*
X2621735Y2525120D01*
X2623130Y2524912D01*
X2624525Y2525329D01*
X2625610Y2526162D01*
X2626385Y2527620D01*
X2626540Y2529287D01*
X2626230Y2530954D01*
X2625455Y2531995D01*
X2624370Y2532829D01*
X2623285Y2533037D01*
X2622200Y2532829D01*
X2620805Y2531995D01*
X2621270Y2537412D01*
X2625455D01*
G01X2643900Y2524912D02*
Y2537412D01*
X2647930Y2526995D01*
X2651960Y2537412D01*
Y2524912D01*
G01X2658470Y2537412D02*
X2662190D01*
G01X2660330D02*
Y2524912D01*
G01X2658470D02*
X2662190D01*
G01X2669630Y2537412D02*
Y2524912D01*
X2675830D01*
G01X2681875Y2526578D02*
X2683115Y2525537D01*
X2684510Y2524912D01*
X2685750D01*
X2686990Y2525537D01*
X2687920Y2526578D01*
X2688385Y2528037D01*
X2688075Y2529495D01*
X2687300Y2530745D01*
X2685905Y2531579D01*
X2684045Y2531995D01*
X2682960Y2532829D01*
X2682495Y2534287D01*
X2682805Y2535745D01*
X2683580Y2536787D01*
X2684665Y2537412D01*
X2685750D01*
X2686835Y2536995D01*
X2687765Y2535954D01*
G01X1926715Y2547829D02*
X1930745D01*
G01X1949500Y2543662D02*
Y2556162D01*
X1953530Y2545745D01*
X1957560Y2556162D01*
Y2543662D01*
G01X1962985D02*
Y2556162D01*
X1968875D01*
G01X1966705Y2550120D02*
X1962985D01*
G01X1979260Y2549912D02*
X1982360D01*
Y2546162D01*
X1981430Y2544912D01*
X1980345Y2544079D01*
X1978795Y2543662D01*
X1977245Y2544079D01*
X1976160Y2544912D01*
X1975230Y2546162D01*
X1974610Y2547620D01*
X1974300Y2549287D01*
Y2550745D01*
X1974610Y2551995D01*
X1975230Y2553454D01*
X1976160Y2554704D01*
X1977090Y2555537D01*
X1978330Y2556162D01*
X1979415D01*
X1980655Y2555745D01*
X1981585Y2554912D01*
G01X1986080Y2539495D02*
X1995380D01*
G01X1999875Y2545328D02*
X2001115Y2544287D01*
X2002510Y2543662D01*
X2003750D01*
X2004990Y2544287D01*
X2005920Y2545328D01*
X2006385Y2546787D01*
X2006075Y2548245D01*
X2005300Y2549495D01*
X2003905Y2550329D01*
X2002045Y2550745D01*
X2000960Y2551579D01*
X2000495Y2553037D01*
X2000805Y2554495D01*
X2001580Y2555537D01*
X2002665Y2556162D01*
X2003750D01*
X2004835Y2555745D01*
X2005765Y2554704D01*
G01X2015530Y2556162D02*
Y2543662D01*
G01X2011965Y2556162D02*
X2019095D01*
G01X2024520D02*
Y2547204D01*
X2025140Y2545328D01*
X2026380Y2544079D01*
X2027930Y2543662D01*
X2029480Y2544079D01*
X2030720Y2545328D01*
X2031340Y2547204D01*
Y2556162D01*
G01X2041570Y2550329D02*
X2042190Y2550954D01*
X2042655Y2551995D01*
X2042965Y2553454D01*
X2042655Y2554704D01*
X2042035Y2555537D01*
X2040950Y2556162D01*
X2036765D01*
Y2543662D01*
X2041880D01*
X2042965Y2544495D01*
X2043585Y2545745D01*
X2043895Y2547204D01*
X2043585Y2548662D01*
X2042655Y2549912D01*
X2041570Y2550329D01*
X2036765D01*
G01X2065130Y2543245D02*
X2064820Y2543454D01*
Y2543870D01*
X2065130Y2544079D01*
X2065440Y2543870D01*
Y2543454D01*
X2065130Y2543245D01*
G01Y2548870D02*
X2064820Y2549079D01*
Y2549495D01*
X2065130Y2549704D01*
X2065440Y2549495D01*
Y2549079D01*
X2065130Y2548870D01*
G01X2085900Y2543662D02*
Y2556162D01*
X2089930Y2545745D01*
X2093960Y2556162D01*
Y2543662D01*
G01X2098455D02*
X2102330Y2556162D01*
X2106205Y2543662D01*
G01X2104810Y2548037D02*
X2099850D01*
G01X2111165Y2543662D02*
Y2556162D01*
X2118295Y2543662D01*
Y2556162D01*
G01X2123720D02*
Y2547204D01*
X2124340Y2545328D01*
X2125580Y2544079D01*
X2127130Y2543662D01*
X2128680Y2544079D01*
X2129920Y2545328D01*
X2130540Y2547204D01*
Y2556162D01*
G01X2136585Y2543662D02*
Y2556162D01*
X2142475D01*
G01X2140305Y2550120D02*
X2136585D01*
G01X2148055Y2543662D02*
X2151930Y2556162D01*
X2155805Y2543662D01*
G01X2154410Y2548037D02*
X2149450D01*
G01X2167740Y2555120D02*
X2166810Y2555745D01*
X2165725Y2556162D01*
X2164485D01*
X2163090Y2555537D01*
X2162005Y2554495D01*
X2161230Y2553245D01*
X2160610Y2551162D01*
X2160455Y2549287D01*
X2160765Y2547412D01*
X2161230Y2546162D01*
X2162160Y2544912D01*
X2163245Y2544079D01*
X2164330Y2543662D01*
X2165415D01*
X2166500Y2544079D01*
X2167430Y2544703D01*
X2168205Y2545537D01*
G01X2176730Y2556162D02*
Y2543662D01*
G01X2173165Y2556162D02*
X2180295D01*
G01X2185720D02*
Y2547204D01*
X2186340Y2545328D01*
X2187580Y2544079D01*
X2189130Y2543662D01*
X2190680Y2544079D01*
X2191920Y2545328D01*
X2192540Y2547204D01*
Y2556162D01*
G01X2198430Y2543662D02*
Y2556162D01*
X2202305D01*
X2203545Y2555537D01*
X2204320Y2554704D01*
X2204630Y2553037D01*
X2204320Y2551370D01*
X2203390Y2550329D01*
X2202305Y2549704D01*
X2198430D01*
G01X2202305D02*
X2204630Y2543662D01*
G01X2212070Y2556162D02*
X2215790D01*
G01X2213930D02*
Y2543662D01*
G01X2212070D02*
X2215790D01*
G01X2222765D02*
Y2556162D01*
X2229895Y2543662D01*
Y2556162D01*
G01X2239660Y2549912D02*
X2242760D01*
Y2546162D01*
X2241830Y2544912D01*
X2240745Y2544079D01*
X2239195Y2543662D01*
X2237645Y2544079D01*
X2236560Y2544912D01*
X2235630Y2546162D01*
X2235010Y2547620D01*
X2234700Y2549287D01*
Y2550745D01*
X2235010Y2551995D01*
X2235630Y2553454D01*
X2236560Y2554704D01*
X2237490Y2555537D01*
X2238730Y2556162D01*
X2239815D01*
X2241055Y2555745D01*
X2241985Y2554912D01*
G01X2260275Y2545328D02*
X2261515Y2544287D01*
X2262910Y2543662D01*
X2264150D01*
X2265390Y2544287D01*
X2266320Y2545328D01*
X2266785Y2546787D01*
X2266475Y2548245D01*
X2265700Y2549495D01*
X2264305Y2550329D01*
X2262445Y2550745D01*
X2261360Y2551579D01*
X2260895Y2553037D01*
X2261205Y2554495D01*
X2261980Y2555537D01*
X2263065Y2556162D01*
X2264150D01*
X2265235Y2555745D01*
X2266165Y2554704D01*
G01X2275930Y2556162D02*
Y2543662D01*
G01X2272365Y2556162D02*
X2279495D01*
G01X2284920D02*
Y2547204D01*
X2285540Y2545328D01*
X2286780Y2544079D01*
X2288330Y2543662D01*
X2289880Y2544079D01*
X2291120Y2545328D01*
X2291740Y2547204D01*
Y2556162D01*
G01X2301970Y2550329D02*
X2302590Y2550954D01*
X2303055Y2551995D01*
X2303365Y2553454D01*
X2303055Y2554704D01*
X2302435Y2555537D01*
X2301350Y2556162D01*
X2297165D01*
Y2543662D01*
X2302280D01*
X2303365Y2544495D01*
X2303985Y2545745D01*
X2304295Y2547204D01*
X2303985Y2548662D01*
X2303055Y2549912D01*
X2301970Y2550329D01*
X2297165D01*
G01X2322430Y2556162D02*
Y2543662D01*
X2328630D01*
G01X2341030D02*
X2334830D01*
Y2556162D01*
X2341030D01*
G01X2338550Y2550120D02*
X2334830D01*
G01X2346765Y2543662D02*
Y2556162D01*
X2353895Y2543662D01*
Y2556162D01*
G01X2363660Y2549912D02*
X2366760D01*
Y2546162D01*
X2365830Y2544912D01*
X2364745Y2544079D01*
X2363195Y2543662D01*
X2361645Y2544079D01*
X2360560Y2544912D01*
X2359630Y2546162D01*
X2359010Y2547620D01*
X2358700Y2549287D01*
Y2550745D01*
X2359010Y2551995D01*
X2359630Y2553454D01*
X2360560Y2554704D01*
X2361490Y2555537D01*
X2362730Y2556162D01*
X2363815D01*
X2365055Y2555745D01*
X2365985Y2554912D01*
G01X2375130Y2556162D02*
Y2543662D01*
G01X2371565Y2556162D02*
X2378695D01*
G01X2384275Y2543662D02*
Y2556162D01*
G01X2390785D02*
Y2543662D01*
G01Y2549912D02*
X2384275D01*
G01X2086675Y2564078D02*
X2087915Y2563037D01*
X2089310Y2562412D01*
X2090550D01*
X2091790Y2563037D01*
X2092720Y2564078D01*
X2093185Y2565537D01*
X2092875Y2566995D01*
X2092100Y2568245D01*
X2090705Y2569079D01*
X2088845Y2569495D01*
X2087760Y2570329D01*
X2087295Y2571787D01*
X2087605Y2573245D01*
X2088380Y2574287D01*
X2089465Y2574912D01*
X2090550D01*
X2091635Y2574495D01*
X2092565Y2573454D01*
G01X2098920Y2574912D02*
Y2565954D01*
X2099540Y2564078D01*
X2100780Y2562829D01*
X2102330Y2562412D01*
X2103880Y2562829D01*
X2105120Y2564078D01*
X2105740Y2565954D01*
Y2574912D01*
G01X2111630Y2562412D02*
Y2574912D01*
X2115505D01*
X2116745Y2574287D01*
X2117520Y2573454D01*
X2117830Y2571787D01*
X2117520Y2570120D01*
X2116590Y2569079D01*
X2115505Y2568454D01*
X2111630D01*
G01X2115505D02*
X2117830Y2562412D01*
G01X2124185D02*
Y2574912D01*
X2130075D01*
G01X2127905Y2568870D02*
X2124185D01*
G01X2135655Y2562412D02*
X2139530Y2574912D01*
X2143405Y2562412D01*
G01X2142010Y2566787D02*
X2137050D01*
G01X2155340Y2573870D02*
X2154410Y2574495D01*
X2153325Y2574912D01*
X2152085D01*
X2150690Y2574287D01*
X2149605Y2573245D01*
X2148830Y2571995D01*
X2148210Y2569912D01*
X2148055Y2568037D01*
X2148365Y2566162D01*
X2148830Y2564912D01*
X2149760Y2563662D01*
X2150845Y2562829D01*
X2151930Y2562412D01*
X2153015D01*
X2154100Y2562829D01*
X2155030Y2563453D01*
X2155805Y2564287D01*
G01X2167430Y2562412D02*
X2161230D01*
Y2574912D01*
X2167430D01*
G01X2164950Y2568870D02*
X2161230D01*
G01X2189130Y2562412D02*
X2187890Y2562620D01*
X2186805Y2563453D01*
X2185875Y2564704D01*
X2185255Y2566162D01*
X2184945Y2567829D01*
Y2569495D01*
X2185255Y2571162D01*
X2185875Y2572620D01*
X2186805Y2573870D01*
X2187890Y2574704D01*
X2189130Y2574912D01*
X2190370Y2574704D01*
X2191455Y2573870D01*
X2192385Y2572620D01*
X2193005Y2571162D01*
X2193315Y2569495D01*
Y2567829D01*
X2193005Y2566162D01*
X2192385Y2564704D01*
X2191455Y2563453D01*
X2190370Y2562620D01*
X2189130Y2562412D01*
G01X2198585D02*
Y2574912D01*
X2204475D01*
G01X2202305Y2568870D02*
X2198585D01*
G01X2222300Y2562412D02*
Y2574912D01*
X2226330Y2564495D01*
X2230360Y2574912D01*
Y2562412D01*
G01X2235320Y2574912D02*
Y2565954D01*
X2235940Y2564078D01*
X2237180Y2562829D01*
X2238730Y2562412D01*
X2240280Y2562829D01*
X2241520Y2564078D01*
X2242140Y2565954D01*
Y2574912D01*
G01X2247875Y2564078D02*
X2249115Y2563037D01*
X2250510Y2562412D01*
X2251750D01*
X2252990Y2563037D01*
X2253920Y2564078D01*
X2254385Y2565537D01*
X2254075Y2566995D01*
X2253300Y2568245D01*
X2251905Y2569079D01*
X2250045Y2569495D01*
X2248960Y2570329D01*
X2248495Y2571787D01*
X2248805Y2573245D01*
X2249580Y2574287D01*
X2250665Y2574912D01*
X2251750D01*
X2252835Y2574495D01*
X2253765Y2573454D01*
G01X2263530Y2574912D02*
Y2562412D01*
G01X2259965Y2574912D02*
X2267095D01*
G01X2273915Y2566579D02*
X2277945D01*
G01X2284765Y2562412D02*
Y2574912D01*
X2291895Y2562412D01*
Y2574912D01*
G01X2300730Y2562412D02*
X2299490Y2562620D01*
X2298405Y2563453D01*
X2297475Y2564704D01*
X2296855Y2566162D01*
X2296545Y2567829D01*
Y2569495D01*
X2296855Y2571162D01*
X2297475Y2572620D01*
X2298405Y2573870D01*
X2299490Y2574704D01*
X2300730Y2574912D01*
X2301970Y2574704D01*
X2303055Y2573870D01*
X2303985Y2572620D01*
X2304605Y2571162D01*
X2304915Y2569495D01*
Y2567829D01*
X2304605Y2566162D01*
X2303985Y2564704D01*
X2303055Y2563453D01*
X2301970Y2562620D01*
X2300730Y2562412D01*
G01X2313130Y2574912D02*
Y2562412D01*
G01X2309565Y2574912D02*
X2316695D01*
G01X2323515Y2566579D02*
X2327545D01*
G01X2341340Y2573870D02*
X2340410Y2574495D01*
X2339325Y2574912D01*
X2338085D01*
X2336690Y2574287D01*
X2335605Y2573245D01*
X2334830Y2571995D01*
X2334210Y2569912D01*
X2334055Y2568037D01*
X2334365Y2566162D01*
X2334830Y2564912D01*
X2335760Y2563662D01*
X2336845Y2562829D01*
X2337930Y2562412D01*
X2339015D01*
X2340100Y2562829D01*
X2341030Y2563453D01*
X2341805Y2564287D01*
G01X2346920Y2574912D02*
Y2565954D01*
X2347540Y2564078D01*
X2348780Y2562829D01*
X2350330Y2562412D01*
X2351880Y2562829D01*
X2353120Y2564078D01*
X2353740Y2565954D01*
Y2574912D01*
G01X2362730D02*
Y2562412D01*
G01X2359165Y2574912D02*
X2366295D01*
G01X2373115Y2566579D02*
X2377145D01*
G01X2384430Y2574912D02*
Y2562412D01*
X2390630D01*
G01X2396055D02*
X2399930Y2574912D01*
X2403805Y2562412D01*
G01X2402410Y2566787D02*
X2397450D01*
G01X2412330Y2562412D02*
Y2568037D01*
X2409230Y2574912D01*
G01X2415430D02*
X2412330Y2568037D01*
G01X2427830Y2562412D02*
X2421630D01*
Y2574912D01*
X2427830D01*
G01X2425350Y2568870D02*
X2421630D01*
G01X2434030Y2562412D02*
Y2574912D01*
X2437905D01*
X2439145Y2574287D01*
X2439920Y2573454D01*
X2440230Y2571787D01*
X2439920Y2570120D01*
X2438990Y2569079D01*
X2437905Y2568454D01*
X2434030D01*
G01X2437905D02*
X2440230Y2562412D01*
G01X1926715Y2585329D02*
X1930745D01*
G01X1949500Y2581162D02*
Y2593662D01*
X1953530Y2583245D01*
X1957560Y2593662D01*
Y2581162D01*
G01X1962055D02*
X1965930Y2593662D01*
X1969805Y2581162D01*
G01X1968410Y2585537D02*
X1963450D01*
G01X1975075Y2581162D02*
X1981585Y2593662D01*
G01X1975075D02*
X1981585Y2581162D01*
G01X1986080Y2576995D02*
X1995380D01*
G01X1999720Y2581162D02*
Y2593662D01*
X2002820D01*
X2004060Y2593037D01*
X2004990Y2592204D01*
X2005765Y2590954D01*
X2006385Y2589495D01*
X2006540Y2587412D01*
X2006385Y2585329D01*
X2005765Y2583870D01*
X2004990Y2582620D01*
X2004060Y2581787D01*
X2002820Y2581162D01*
X1999720D01*
G01X2018630D02*
X2012430D01*
Y2593662D01*
X2018630D01*
G01X2016150Y2587620D02*
X2012430D01*
G01X2024830Y2581162D02*
Y2593662D01*
X2028550D01*
X2029790Y2593037D01*
X2030720Y2591579D01*
X2031030Y2589912D01*
X2030720Y2588245D01*
X2029945Y2586995D01*
X2028550Y2586370D01*
X2024830D01*
G01X2040330Y2593662D02*
Y2581162D01*
G01X2036765Y2593662D02*
X2043895D01*
G01X2049475Y2581162D02*
Y2593662D01*
G01X2055985D02*
Y2581162D01*
G01Y2587412D02*
X2049475D01*
G01X2065130Y2580745D02*
X2064820Y2580954D01*
Y2581370D01*
X2065130Y2581579D01*
X2065440Y2581370D01*
Y2580954D01*
X2065130Y2580745D01*
G01Y2586370D02*
X2064820Y2586579D01*
Y2586995D01*
X2065130Y2587204D01*
X2065440Y2586995D01*
Y2586579D01*
X2065130Y2586370D01*
G01X2086520Y2581162D02*
Y2593662D01*
X2089620D01*
X2090860Y2593037D01*
X2091790Y2592204D01*
X2092565Y2590954D01*
X2093185Y2589495D01*
X2093340Y2587412D01*
X2093185Y2585329D01*
X2092565Y2583870D01*
X2091790Y2582620D01*
X2090860Y2581787D01*
X2089620Y2581162D01*
X2086520D01*
G01X2105430D02*
X2099230D01*
Y2593662D01*
X2105430D01*
G01X2102950Y2587620D02*
X2099230D01*
G01X2111630Y2581162D02*
Y2593662D01*
X2115350D01*
X2116590Y2593037D01*
X2117520Y2591579D01*
X2117830Y2589912D01*
X2117520Y2588245D01*
X2116745Y2586995D01*
X2115350Y2586370D01*
X2111630D01*
G01X2127130Y2593662D02*
Y2581162D01*
G01X2123565Y2593662D02*
X2130695D01*
G01X2136275Y2581162D02*
Y2593662D01*
G01X2142785D02*
Y2581162D01*
G01Y2587412D02*
X2136275D01*
G01X2161385Y2581162D02*
Y2593662D01*
X2167275D01*
G01X2165105Y2587620D02*
X2161385D01*
G01X2173630Y2581162D02*
Y2593662D01*
X2177505D01*
X2178745Y2593037D01*
X2179520Y2592204D01*
X2179830Y2590537D01*
X2179520Y2588870D01*
X2178590Y2587829D01*
X2177505Y2587204D01*
X2173630D01*
G01X2177505D02*
X2179830Y2581162D01*
G01X2189130D02*
X2187890Y2581370D01*
X2186805Y2582203D01*
X2185875Y2583454D01*
X2185255Y2584912D01*
X2184945Y2586579D01*
Y2588245D01*
X2185255Y2589912D01*
X2185875Y2591370D01*
X2186805Y2592620D01*
X2187890Y2593454D01*
X2189130Y2593662D01*
X2190370Y2593454D01*
X2191455Y2592620D01*
X2192385Y2591370D01*
X2193005Y2589912D01*
X2193315Y2588245D01*
Y2586579D01*
X2193005Y2584912D01*
X2192385Y2583454D01*
X2191455Y2582203D01*
X2190370Y2581370D01*
X2189130Y2581162D01*
G01X2197500D02*
Y2593662D01*
X2201530Y2583245D01*
X2205560Y2593662D01*
Y2581162D01*
G01X2223075Y2582828D02*
X2224315Y2581787D01*
X2225710Y2581162D01*
X2226950D01*
X2228190Y2581787D01*
X2229120Y2582828D01*
X2229585Y2584287D01*
X2229275Y2585745D01*
X2228500Y2586995D01*
X2227105Y2587829D01*
X2225245Y2588245D01*
X2224160Y2589079D01*
X2223695Y2590537D01*
X2224005Y2591995D01*
X2224780Y2593037D01*
X2225865Y2593662D01*
X2226950D01*
X2228035Y2593245D01*
X2228965Y2592204D01*
G01X2238730Y2593662D02*
Y2581162D01*
G01X2235165Y2593662D02*
X2242295D01*
G01X2247255Y2581162D02*
X2251130Y2593662D01*
X2255005Y2581162D01*
G01X2253610Y2585537D02*
X2248650D01*
G01X2260430Y2581162D02*
Y2593662D01*
X2264305D01*
X2265545Y2593037D01*
X2266320Y2592204D01*
X2266630Y2590537D01*
X2266320Y2588870D01*
X2265390Y2587829D01*
X2264305Y2587204D01*
X2260430D01*
G01X2264305D02*
X2266630Y2581162D01*
G01X2275930Y2593662D02*
Y2581162D01*
G01X2272365Y2593662D02*
X2279495D01*
G01X2297630D02*
Y2581162D01*
X2303830D01*
G01X2309255D02*
X2313130Y2593662D01*
X2317005Y2581162D01*
G01X2315610Y2585537D02*
X2310650D01*
G01X2325530Y2581162D02*
Y2586787D01*
X2322430Y2593662D01*
G01X2328630D02*
X2325530Y2586787D01*
G01X2341030Y2581162D02*
X2334830D01*
Y2593662D01*
X2341030D01*
G01X2338550Y2587620D02*
X2334830D01*
G01X2347230Y2581162D02*
Y2593662D01*
X2351105D01*
X2352345Y2593037D01*
X2353120Y2592204D01*
X2353430Y2590537D01*
X2353120Y2588870D01*
X2352190Y2587829D01*
X2351105Y2587204D01*
X2347230D01*
G01X2351105D02*
X2353430Y2581162D01*
G01X2375130Y2593662D02*
Y2581162D01*
G01X2371565Y2593662D02*
X2378695D01*
G01X2387530Y2581162D02*
X2386290Y2581370D01*
X2385205Y2582203D01*
X2384275Y2583454D01*
X2383655Y2584912D01*
X2383345Y2586579D01*
Y2588245D01*
X2383655Y2589912D01*
X2384275Y2591370D01*
X2385205Y2592620D01*
X2386290Y2593454D01*
X2387530Y2593662D01*
X2388770Y2593454D01*
X2389855Y2592620D01*
X2390785Y2591370D01*
X2391405Y2589912D01*
X2391715Y2588245D01*
Y2586579D01*
X2391405Y2584912D01*
X2390785Y2583454D01*
X2389855Y2582203D01*
X2388770Y2581370D01*
X2387530Y2581162D01*
G01X2412330Y2593662D02*
Y2581162D01*
G01X2408765Y2593662D02*
X2415895D01*
G01X2421475Y2581162D02*
Y2593662D01*
G01X2427985D02*
Y2581162D01*
G01Y2587412D02*
X2421475D01*
G01X2440230Y2581162D02*
X2434030D01*
Y2593662D01*
X2440230D01*
G01X2437750Y2587620D02*
X2434030D01*
G01X1926715Y2604079D02*
X1930745D01*
G01X1949500Y2599912D02*
Y2612412D01*
X1953530Y2601995D01*
X1957560Y2612412D01*
Y2599912D01*
G01X1962365D02*
Y2612412D01*
X1969495Y2599912D01*
Y2612412D01*
G01X1981740Y2611370D02*
X1980810Y2611995D01*
X1979725Y2612412D01*
X1978485D01*
X1977090Y2611787D01*
X1976005Y2610745D01*
X1975230Y2609495D01*
X1974610Y2607412D01*
X1974455Y2605537D01*
X1974765Y2603662D01*
X1975230Y2602412D01*
X1976160Y2601162D01*
X1977245Y2600329D01*
X1978330Y2599912D01*
X1979415D01*
X1980500Y2600329D01*
X1981430Y2600953D01*
X1982205Y2601787D01*
G01X1986080Y2595745D02*
X1995380D01*
G01X2000030Y2612412D02*
Y2599912D01*
X2006230D01*
G01X2011655D02*
X2015530Y2612412D01*
X2019405Y2599912D01*
G01X2018010Y2604287D02*
X2013050D01*
G01X2027930Y2599912D02*
Y2605537D01*
X2024830Y2612412D01*
G01X2031030D02*
X2027930Y2605537D01*
G01X2043430Y2599912D02*
X2037230D01*
Y2612412D01*
X2043430D01*
G01X2040950Y2606370D02*
X2037230D01*
G01X2049630Y2599912D02*
Y2612412D01*
X2053505D01*
X2054745Y2611787D01*
X2055520Y2610954D01*
X2055830Y2609287D01*
X2055520Y2607620D01*
X2054590Y2606579D01*
X2053505Y2605954D01*
X2049630D01*
G01X2053505D02*
X2055830Y2599912D01*
G01X2065130Y2599495D02*
X2064820Y2599704D01*
Y2600120D01*
X2065130Y2600329D01*
X2065440Y2600120D01*
Y2599704D01*
X2065130Y2599495D01*
G01Y2605120D02*
X2064820Y2605329D01*
Y2605745D01*
X2065130Y2605954D01*
X2065440Y2605745D01*
Y2605329D01*
X2065130Y2605120D01*
G01X2085900Y2599912D02*
Y2612412D01*
X2089930Y2601995D01*
X2093960Y2612412D01*
Y2599912D01*
G01X2098920Y2612412D02*
Y2603454D01*
X2099540Y2601578D01*
X2100780Y2600329D01*
X2102330Y2599912D01*
X2103880Y2600329D01*
X2105120Y2601578D01*
X2105740Y2603454D01*
Y2612412D01*
G01X2111475Y2601578D02*
X2112715Y2600537D01*
X2114110Y2599912D01*
X2115350D01*
X2116590Y2600537D01*
X2117520Y2601578D01*
X2117985Y2603037D01*
X2117675Y2604495D01*
X2116900Y2605745D01*
X2115505Y2606579D01*
X2113645Y2606995D01*
X2112560Y2607829D01*
X2112095Y2609287D01*
X2112405Y2610745D01*
X2113180Y2611787D01*
X2114265Y2612412D01*
X2115350D01*
X2116435Y2611995D01*
X2117365Y2610954D01*
G01X2127130Y2612412D02*
Y2599912D01*
G01X2123565Y2612412D02*
X2130695D01*
G01X2137515Y2604079D02*
X2141545D01*
G01X2148365Y2599912D02*
Y2612412D01*
X2155495Y2599912D01*
Y2612412D01*
G01X2164330Y2599912D02*
X2163090Y2600120D01*
X2162005Y2600953D01*
X2161075Y2602204D01*
X2160455Y2603662D01*
X2160145Y2605329D01*
Y2606995D01*
X2160455Y2608662D01*
X2161075Y2610120D01*
X2162005Y2611370D01*
X2163090Y2612204D01*
X2164330Y2612412D01*
X2165570Y2612204D01*
X2166655Y2611370D01*
X2167585Y2610120D01*
X2168205Y2608662D01*
X2168515Y2606995D01*
Y2605329D01*
X2168205Y2603662D01*
X2167585Y2602204D01*
X2166655Y2600953D01*
X2165570Y2600120D01*
X2164330Y2599912D01*
G01X2176730Y2612412D02*
Y2599912D01*
G01X2173165Y2612412D02*
X2180295D01*
G01X2187115Y2604079D02*
X2191145D01*
G01X2204940Y2611370D02*
X2204010Y2611995D01*
X2202925Y2612412D01*
X2201685D01*
X2200290Y2611787D01*
X2199205Y2610745D01*
X2198430Y2609495D01*
X2197810Y2607412D01*
X2197655Y2605537D01*
X2197965Y2603662D01*
X2198430Y2602412D01*
X2199360Y2601162D01*
X2200445Y2600329D01*
X2201530Y2599912D01*
X2202615D01*
X2203700Y2600329D01*
X2204630Y2600953D01*
X2205405Y2601787D01*
G01X2210520Y2612412D02*
Y2603454D01*
X2211140Y2601578D01*
X2212380Y2600329D01*
X2213930Y2599912D01*
X2215480Y2600329D01*
X2216720Y2601578D01*
X2217340Y2603454D01*
Y2612412D01*
G01X2226330D02*
Y2599912D01*
G01X2222765Y2612412D02*
X2229895D01*
G01X2236715Y2604079D02*
X2240745D01*
G01X2248030Y2612412D02*
Y2599912D01*
X2254230D01*
G01X2259655D02*
X2263530Y2612412D01*
X2267405Y2599912D01*
G01X2266010Y2604287D02*
X2261050D01*
G01X2275930Y2599912D02*
Y2605537D01*
X2272830Y2612412D01*
G01X2279030D02*
X2275930Y2605537D01*
G01X2291430Y2599912D02*
X2285230D01*
Y2612412D01*
X2291430D01*
G01X2288950Y2606370D02*
X2285230D01*
G01X2297630Y2599912D02*
Y2612412D01*
X2301505D01*
X2302745Y2611787D01*
X2303520Y2610954D01*
X2303830Y2609287D01*
X2303520Y2607620D01*
X2302590Y2606579D01*
X2301505Y2605954D01*
X2297630D01*
G01X2301505D02*
X2303830Y2599912D01*
G01X1925165Y2618662D02*
Y2631162D01*
X1932295Y2618662D01*
Y2631162D01*
G01X1941130Y2618662D02*
X1939890Y2618870D01*
X1938805Y2619703D01*
X1937875Y2620954D01*
X1937255Y2622412D01*
X1936945Y2624079D01*
Y2625745D01*
X1937255Y2627412D01*
X1937875Y2628870D01*
X1938805Y2630120D01*
X1939890Y2630954D01*
X1941130Y2631162D01*
X1942370Y2630954D01*
X1943455Y2630120D01*
X1944385Y2628870D01*
X1945005Y2627412D01*
X1945315Y2625745D01*
Y2624079D01*
X1945005Y2622412D01*
X1944385Y2620954D01*
X1943455Y2619703D01*
X1942370Y2618870D01*
X1941130Y2618662D01*
G01X1953530Y2631162D02*
Y2618662D01*
G01X1949965Y2631162D02*
X1957095D01*
G01X1969030Y2618662D02*
X1962830D01*
Y2631162D01*
X1969030D01*
G01X1966550Y2625120D02*
X1962830D01*
G01X1975075Y2620328D02*
X1976315Y2619287D01*
X1977710Y2618662D01*
X1978950D01*
X1980190Y2619287D01*
X1981120Y2620328D01*
X1981585Y2621787D01*
X1981275Y2623245D01*
X1980500Y2624495D01*
X1979105Y2625329D01*
X1977245Y2625745D01*
X1976160Y2626579D01*
X1975695Y2628037D01*
X1976005Y2629495D01*
X1976780Y2630537D01*
X1977865Y2631162D01*
X1978950D01*
X1980035Y2630745D01*
X1980965Y2629704D01*
G01X1990730Y2618245D02*
X1990420Y2618454D01*
Y2618870D01*
X1990730Y2619079D01*
X1991040Y2618870D01*
Y2618454D01*
X1990730Y2618245D01*
G01Y2623870D02*
X1990420Y2624079D01*
Y2624495D01*
X1990730Y2624704D01*
X1991040Y2624495D01*
Y2624079D01*
X1990730Y2623870D01*
G01X1922238Y2909540D02*
Y2922040D01*
X1928128D01*
G01X1925958Y2915998D02*
X1922238D01*
G01X1935723Y2922040D02*
X1939443D01*
G01X1937583D02*
Y2909540D01*
G01X1935723D02*
X1939443D01*
G01X1950913Y2915790D02*
X1954013D01*
Y2912040D01*
X1953083Y2910790D01*
X1951998Y2909957D01*
X1950448Y2909540D01*
X1948898Y2909957D01*
X1947813Y2910790D01*
X1946883Y2912040D01*
X1946263Y2913498D01*
X1945953Y2915165D01*
Y2916623D01*
X1946263Y2917873D01*
X1946883Y2919332D01*
X1947813Y2920582D01*
X1948743Y2921415D01*
X1949983Y2922040D01*
X1951068D01*
X1952308Y2921623D01*
X1953238Y2920790D01*
G01X1958973Y2922040D02*
Y2913082D01*
X1959593Y2911206D01*
X1960833Y2909957D01*
X1962383Y2909540D01*
X1963933Y2909957D01*
X1965173Y2911206D01*
X1965793Y2913082D01*
Y2922040D01*
G01X1971683Y2909540D02*
Y2922040D01*
X1975558D01*
X1976798Y2921415D01*
X1977573Y2920582D01*
X1977883Y2918915D01*
X1977573Y2917248D01*
X1976643Y2916207D01*
X1975558Y2915582D01*
X1971683D01*
G01X1975558D02*
X1977883Y2909540D01*
G01X1990283D02*
X1984083D01*
Y2922040D01*
X1990283D01*
G01X1987803Y2915998D02*
X1984083D01*
G01X1923485Y3125922D02*
Y3138422D01*
X1929375D01*
G01X1927205Y3132380D02*
X1923485D01*
G01X1936970Y3138422D02*
X1940690D01*
G01X1938830D02*
Y3125922D01*
G01X1936970D02*
X1940690D01*
G01X1952160Y3132172D02*
X1955260D01*
Y3128422D01*
X1954330Y3127172D01*
X1953245Y3126339D01*
X1951695Y3125922D01*
X1950145Y3126339D01*
X1949060Y3127172D01*
X1948130Y3128422D01*
X1947510Y3129880D01*
X1947200Y3131547D01*
Y3133005D01*
X1947510Y3134255D01*
X1948130Y3135714D01*
X1949060Y3136964D01*
X1949990Y3137797D01*
X1951230Y3138422D01*
X1952315D01*
X1953555Y3138005D01*
X1954485Y3137172D01*
G01X1960220Y3138422D02*
Y3129464D01*
X1960840Y3127588D01*
X1962080Y3126339D01*
X1963630Y3125922D01*
X1965180Y3126339D01*
X1966420Y3127588D01*
X1967040Y3129464D01*
Y3138422D01*
G01X1972930Y3125922D02*
Y3138422D01*
X1976805D01*
X1978045Y3137797D01*
X1978820Y3136964D01*
X1979130Y3135297D01*
X1978820Y3133630D01*
X1977890Y3132589D01*
X1976805Y3131964D01*
X1972930D01*
G01X1976805D02*
X1979130Y3125922D01*
G01X1991530D02*
X1985330D01*
Y3138422D01*
X1991530D01*
G01X1989050Y3132380D02*
X1985330D01*
G01X1921555Y3418372D02*
Y3430872D01*
X1927445D01*
G01X1925275Y3424830D02*
X1921555D01*
G01X1935040Y3430872D02*
X1938760D01*
G01X1936900D02*
Y3418372D01*
G01X1935040D02*
X1938760D01*
G01X1950230Y3424622D02*
X1953330D01*
Y3420872D01*
X1952400Y3419622D01*
X1951315Y3418789D01*
X1949765Y3418372D01*
X1948215Y3418789D01*
X1947130Y3419622D01*
X1946200Y3420872D01*
X1945580Y3422330D01*
X1945270Y3423997D01*
Y3425455D01*
X1945580Y3426705D01*
X1946200Y3428164D01*
X1947130Y3429414D01*
X1948060Y3430247D01*
X1949300Y3430872D01*
X1950385D01*
X1951625Y3430455D01*
X1952555Y3429622D01*
G01X1958290Y3430872D02*
Y3421914D01*
X1958910Y3420038D01*
X1960150Y3418789D01*
X1961700Y3418372D01*
X1963250Y3418789D01*
X1964490Y3420038D01*
X1965110Y3421914D01*
Y3430872D01*
G01X1971000Y3418372D02*
Y3430872D01*
X1974875D01*
X1976115Y3430247D01*
X1976890Y3429414D01*
X1977200Y3427747D01*
X1976890Y3426080D01*
X1975960Y3425039D01*
X1974875Y3424414D01*
X1971000D01*
G01X1974875D02*
X1977200Y3418372D01*
G01X1989600D02*
X1983400D01*
Y3430872D01*
X1989600D01*
G01X1987120Y3424830D02*
X1983400D01*
G01X1921005Y3708112D02*
Y3720612D01*
X1926895D01*
G01X1924725Y3714570D02*
X1921005D01*
G01X1934490Y3720612D02*
X1938210D01*
G01X1936350D02*
Y3708112D01*
G01X1934490D02*
X1938210D01*
G01X1949680Y3714362D02*
X1952780D01*
Y3710612D01*
X1951850Y3709362D01*
X1950765Y3708529D01*
X1949215Y3708112D01*
X1947665Y3708529D01*
X1946580Y3709362D01*
X1945650Y3710612D01*
X1945030Y3712070D01*
X1944720Y3713737D01*
Y3715195D01*
X1945030Y3716445D01*
X1945650Y3717904D01*
X1946580Y3719154D01*
X1947510Y3719987D01*
X1948750Y3720612D01*
X1949835D01*
X1951075Y3720195D01*
X1952005Y3719362D01*
G01X1957740Y3720612D02*
Y3711654D01*
X1958360Y3709778D01*
X1959600Y3708529D01*
X1961150Y3708112D01*
X1962700Y3708529D01*
X1963940Y3709778D01*
X1964560Y3711654D01*
Y3720612D01*
G01X1970450Y3708112D02*
Y3720612D01*
X1974325D01*
X1975565Y3719987D01*
X1976340Y3719154D01*
X1976650Y3717487D01*
X1976340Y3715820D01*
X1975410Y3714779D01*
X1974325Y3714154D01*
X1970450D01*
G01X1974325D02*
X1976650Y3708112D01*
G01X1989050D02*
X1982850D01*
Y3720612D01*
X1989050D01*
G01X1986570Y3714570D02*
X1982850D01*
G01X1955510Y754870D02*
X1943010D01*
X1951968Y749135D01*
Y756885D01*
G01X1955510Y767270D02*
X1943010D01*
X1951968Y761535D01*
Y769285D01*
G01X1955510Y777810D02*
X1943010D01*
X1945510Y775950D01*
G01X1955510D02*
Y779670D01*
G01X1955927Y790210D02*
X1955718Y789900D01*
X1955302D01*
X1955093Y790210D01*
X1955302Y790520D01*
X1955718D01*
X1955927Y790210D01*
G01X1954052Y799975D02*
X1955093Y801060D01*
X1955510Y802300D01*
X1955093Y803540D01*
X1953844Y804625D01*
X1951968Y805400D01*
X1950093Y805710D01*
X1947802D01*
X1945927Y805400D01*
X1944260Y804625D01*
X1943427Y803695D01*
X1943010Y802610D01*
X1943427Y801370D01*
X1944260Y800440D01*
X1945510Y799820D01*
X1947177Y799510D01*
X1948635Y799820D01*
X1950093Y800595D01*
X1950927Y801525D01*
X1951135Y802610D01*
X1950719Y803850D01*
X1949677Y804780D01*
X1947802Y805710D01*
G01X1954052Y812375D02*
X1955093Y813460D01*
X1955510Y814700D01*
X1955093Y815940D01*
X1953844Y817025D01*
X1951968Y817800D01*
X1950093Y818110D01*
X1947802D01*
X1945927Y817800D01*
X1944260Y817025D01*
X1943427Y816095D01*
X1943010Y815010D01*
X1943427Y813770D01*
X1944260Y812840D01*
X1945510Y812220D01*
X1947177Y811910D01*
X1948635Y812220D01*
X1950093Y812995D01*
X1950927Y813925D01*
X1951135Y815010D01*
X1950719Y816250D01*
X1949677Y817180D01*
X1947802Y818110D01*
G01X1935085Y2668662D02*
Y2681162D01*
X1940975D01*
G01X1938805Y2675120D02*
X1935085D01*
G01X1948570Y2681162D02*
X1952290D01*
G01X1950430D02*
Y2668662D01*
G01X1948570D02*
X1952290D01*
G01X1963760Y2674912D02*
X1966860D01*
Y2671162D01*
X1965930Y2669912D01*
X1964845Y2669079D01*
X1963295Y2668662D01*
X1961745Y2669079D01*
X1960660Y2669912D01*
X1959730Y2671162D01*
X1959110Y2672620D01*
X1958800Y2674287D01*
Y2675745D01*
X1959110Y2676995D01*
X1959730Y2678454D01*
X1960660Y2679704D01*
X1961590Y2680537D01*
X1962830Y2681162D01*
X1963915D01*
X1965155Y2680745D01*
X1966085Y2679912D01*
G01X1971820Y2681162D02*
Y2672204D01*
X1972440Y2670328D01*
X1973680Y2669079D01*
X1975230Y2668662D01*
X1976780Y2669079D01*
X1978020Y2670328D01*
X1978640Y2672204D01*
Y2681162D01*
G01X1984530Y2668662D02*
Y2681162D01*
X1988405D01*
X1989645Y2680537D01*
X1990420Y2679704D01*
X1990730Y2678037D01*
X1990420Y2676370D01*
X1989490Y2675329D01*
X1988405Y2674704D01*
X1984530D01*
G01X1988405D02*
X1990730Y2668662D01*
G01X2003130D02*
X1996930D01*
Y2681162D01*
X2003130D01*
G01X2000650Y2675120D02*
X1996930D01*
G01X2028723Y2916207D02*
X2029343Y2916832D01*
X2029808Y2917873D01*
X2030118Y2919332D01*
X2029808Y2920582D01*
X2029188Y2921415D01*
X2028103Y2922040D01*
X2023918D01*
Y2909540D01*
X2029033D01*
X2030118Y2910373D01*
X2030738Y2911623D01*
X2031048Y2913082D01*
X2030738Y2914540D01*
X2029808Y2915790D01*
X2028723Y2916207D01*
X2023918D01*
G01X2036473Y2909540D02*
Y2922040D01*
X2039573D01*
X2040813Y2921415D01*
X2041743Y2920582D01*
X2042518Y2919332D01*
X2043138Y2917873D01*
X2043293Y2915790D01*
X2043138Y2913707D01*
X2042518Y2912248D01*
X2041743Y2910998D01*
X2040813Y2910165D01*
X2039573Y2909540D01*
X2036473D01*
G01X2047633Y2905373D02*
X2056933D01*
G01X2061428Y2911206D02*
X2062668Y2910165D01*
X2064063Y2909540D01*
X2065303D01*
X2066543Y2910165D01*
X2067473Y2911206D01*
X2067938Y2912665D01*
X2067628Y2914123D01*
X2066853Y2915373D01*
X2065458Y2916207D01*
X2063598Y2916623D01*
X2062513Y2917457D01*
X2062048Y2918915D01*
X2062358Y2920373D01*
X2063133Y2921415D01*
X2064218Y2922040D01*
X2065303D01*
X2066388Y2921623D01*
X2067318Y2920582D01*
G01X2075223Y2922040D02*
X2078943D01*
G01X2077083D02*
Y2909540D01*
G01X2075223D02*
X2078943D01*
G01X2086538Y2922040D02*
X2092428D01*
X2086538Y2909540D01*
X2092428D01*
G01X2104983D02*
X2098783D01*
Y2922040D01*
X2104983D01*
G01X2102503Y2915998D02*
X2098783D01*
G01X2029970Y3132589D02*
X2030590Y3133214D01*
X2031055Y3134255D01*
X2031365Y3135714D01*
X2031055Y3136964D01*
X2030435Y3137797D01*
X2029350Y3138422D01*
X2025165D01*
Y3125922D01*
X2030280D01*
X2031365Y3126755D01*
X2031985Y3128005D01*
X2032295Y3129464D01*
X2031985Y3130922D01*
X2031055Y3132172D01*
X2029970Y3132589D01*
X2025165D01*
G01X2037720Y3125922D02*
Y3138422D01*
X2040820D01*
X2042060Y3137797D01*
X2042990Y3136964D01*
X2043765Y3135714D01*
X2044385Y3134255D01*
X2044540Y3132172D01*
X2044385Y3130089D01*
X2043765Y3128630D01*
X2042990Y3127380D01*
X2042060Y3126547D01*
X2040820Y3125922D01*
X2037720D01*
G01X2048880Y3121755D02*
X2058180D01*
G01X2062675Y3127588D02*
X2063915Y3126547D01*
X2065310Y3125922D01*
X2066550D01*
X2067790Y3126547D01*
X2068720Y3127588D01*
X2069185Y3129047D01*
X2068875Y3130505D01*
X2068100Y3131755D01*
X2066705Y3132589D01*
X2064845Y3133005D01*
X2063760Y3133839D01*
X2063295Y3135297D01*
X2063605Y3136755D01*
X2064380Y3137797D01*
X2065465Y3138422D01*
X2066550D01*
X2067635Y3138005D01*
X2068565Y3136964D01*
G01X2076470Y3138422D02*
X2080190D01*
G01X2078330D02*
Y3125922D01*
G01X2076470D02*
X2080190D01*
G01X2087785Y3138422D02*
X2093675D01*
X2087785Y3125922D01*
X2093675D01*
G01X2106230D02*
X2100030D01*
Y3138422D01*
X2106230D01*
G01X2103750Y3132380D02*
X2100030D01*
G01X2028040Y3425039D02*
X2028660Y3425664D01*
X2029125Y3426705D01*
X2029435Y3428164D01*
X2029125Y3429414D01*
X2028505Y3430247D01*
X2027420Y3430872D01*
X2023235D01*
Y3418372D01*
X2028350D01*
X2029435Y3419205D01*
X2030055Y3420455D01*
X2030365Y3421914D01*
X2030055Y3423372D01*
X2029125Y3424622D01*
X2028040Y3425039D01*
X2023235D01*
G01X2035790Y3418372D02*
Y3430872D01*
X2038890D01*
X2040130Y3430247D01*
X2041060Y3429414D01*
X2041835Y3428164D01*
X2042455Y3426705D01*
X2042610Y3424622D01*
X2042455Y3422539D01*
X2041835Y3421080D01*
X2041060Y3419830D01*
X2040130Y3418997D01*
X2038890Y3418372D01*
X2035790D01*
G01X2046950Y3414205D02*
X2056250D01*
G01X2060745Y3420038D02*
X2061985Y3418997D01*
X2063380Y3418372D01*
X2064620D01*
X2065860Y3418997D01*
X2066790Y3420038D01*
X2067255Y3421497D01*
X2066945Y3422955D01*
X2066170Y3424205D01*
X2064775Y3425039D01*
X2062915Y3425455D01*
X2061830Y3426289D01*
X2061365Y3427747D01*
X2061675Y3429205D01*
X2062450Y3430247D01*
X2063535Y3430872D01*
X2064620D01*
X2065705Y3430455D01*
X2066635Y3429414D01*
G01X2074540Y3430872D02*
X2078260D01*
G01X2076400D02*
Y3418372D01*
G01X2074540D02*
X2078260D01*
G01X2085855Y3430872D02*
X2091745D01*
X2085855Y3418372D01*
X2091745D01*
G01X2104300D02*
X2098100D01*
Y3430872D01*
X2104300D01*
G01X2101820Y3424830D02*
X2098100D01*
G01X2027490Y3714779D02*
X2028110Y3715404D01*
X2028575Y3716445D01*
X2028885Y3717904D01*
X2028575Y3719154D01*
X2027955Y3719987D01*
X2026870Y3720612D01*
X2022685D01*
Y3708112D01*
X2027800D01*
X2028885Y3708945D01*
X2029505Y3710195D01*
X2029815Y3711654D01*
X2029505Y3713112D01*
X2028575Y3714362D01*
X2027490Y3714779D01*
X2022685D01*
G01X2035240Y3708112D02*
Y3720612D01*
X2038340D01*
X2039580Y3719987D01*
X2040510Y3719154D01*
X2041285Y3717904D01*
X2041905Y3716445D01*
X2042060Y3714362D01*
X2041905Y3712279D01*
X2041285Y3710820D01*
X2040510Y3709570D01*
X2039580Y3708737D01*
X2038340Y3708112D01*
X2035240D01*
G01X2046400Y3703945D02*
X2055700D01*
G01X2060195Y3709778D02*
X2061435Y3708737D01*
X2062830Y3708112D01*
X2064070D01*
X2065310Y3708737D01*
X2066240Y3709778D01*
X2066705Y3711237D01*
X2066395Y3712695D01*
X2065620Y3713945D01*
X2064225Y3714779D01*
X2062365Y3715195D01*
X2061280Y3716029D01*
X2060815Y3717487D01*
X2061125Y3718945D01*
X2061900Y3719987D01*
X2062985Y3720612D01*
X2064070D01*
X2065155Y3720195D01*
X2066085Y3719154D01*
G01X2073990Y3720612D02*
X2077710D01*
G01X2075850D02*
Y3708112D01*
G01X2073990D02*
X2077710D01*
G01X2085305Y3720612D02*
X2091195D01*
X2085305Y3708112D01*
X2091195D01*
G01X2103750D02*
X2097550D01*
Y3720612D01*
X2103750D01*
G01X2101270Y3714570D02*
X2097550D01*
G01X2041570Y2675329D02*
X2042190Y2675954D01*
X2042655Y2676995D01*
X2042965Y2678454D01*
X2042655Y2679704D01*
X2042035Y2680537D01*
X2040950Y2681162D01*
X2036765D01*
Y2668662D01*
X2041880D01*
X2042965Y2669495D01*
X2043585Y2670745D01*
X2043895Y2672204D01*
X2043585Y2673662D01*
X2042655Y2674912D01*
X2041570Y2675329D01*
X2036765D01*
G01X2049320Y2668662D02*
Y2681162D01*
X2052420D01*
X2053660Y2680537D01*
X2054590Y2679704D01*
X2055365Y2678454D01*
X2055985Y2676995D01*
X2056140Y2674912D01*
X2055985Y2672829D01*
X2055365Y2671370D01*
X2054590Y2670120D01*
X2053660Y2669287D01*
X2052420Y2668662D01*
X2049320D01*
G01X2060480Y2664495D02*
X2069780D01*
G01X2074275Y2670328D02*
X2075515Y2669287D01*
X2076910Y2668662D01*
X2078150D01*
X2079390Y2669287D01*
X2080320Y2670328D01*
X2080785Y2671787D01*
X2080475Y2673245D01*
X2079700Y2674495D01*
X2078305Y2675329D01*
X2076445Y2675745D01*
X2075360Y2676579D01*
X2074895Y2678037D01*
X2075205Y2679495D01*
X2075980Y2680537D01*
X2077065Y2681162D01*
X2078150D01*
X2079235Y2680745D01*
X2080165Y2679704D01*
G01X2088070Y2681162D02*
X2091790D01*
G01X2089930D02*
Y2668662D01*
G01X2088070D02*
X2091790D01*
G01X2099385Y2681162D02*
X2105275D01*
X2099385Y2668662D01*
X2105275D01*
G01X2117830D02*
X2111630D01*
Y2681162D01*
X2117830D01*
G01X2115350Y2675120D02*
X2111630D01*
G01X2036938Y2894957D02*
X2037868Y2896206D01*
X2038953Y2896832D01*
X2040193Y2897040D01*
X2041743Y2896623D01*
X2042828Y2895582D01*
X2043138Y2894332D01*
X2042983Y2893081D01*
X2042363Y2892040D01*
X2039263Y2889957D01*
X2037868Y2888498D01*
X2036938Y2886415D01*
X2036628Y2884540D01*
X2043138D01*
G01X2052283D02*
Y2897040D01*
X2050423Y2894540D01*
G01Y2884540D02*
X2054143D01*
G01X2064683Y2884123D02*
X2064373Y2884332D01*
Y2884748D01*
X2064683Y2884957D01*
X2064993Y2884748D01*
Y2884332D01*
X2064683Y2884123D01*
G01X2077083Y2884540D02*
X2078168Y2884748D01*
X2079408Y2885373D01*
X2080183Y2886415D01*
X2080493Y2887873D01*
X2080183Y2889331D01*
X2079253Y2890582D01*
X2077858Y2891207D01*
X2076308D01*
X2075378Y2891623D01*
X2074603Y2892665D01*
X2074293Y2894123D01*
X2074758Y2895582D01*
X2075843Y2896623D01*
X2077083Y2897040D01*
X2078323Y2896623D01*
X2079408Y2895582D01*
X2079873Y2894123D01*
X2079563Y2892665D01*
X2078788Y2891623D01*
X2077858Y2891207D01*
X2076308D01*
X2074913Y2890582D01*
X2073983Y2889331D01*
X2073673Y2887873D01*
X2073983Y2886415D01*
X2074758Y2885373D01*
X2075998Y2884748D01*
X2077083Y2884540D01*
G01X2089173D02*
X2089483Y2887248D01*
X2089948Y2889540D01*
X2090568Y2891623D01*
X2091343Y2893915D01*
X2092583Y2897040D01*
X2086383D01*
G01X2047330Y3100922D02*
Y3113422D01*
X2045470Y3110922D01*
G01Y3100922D02*
X2049190D01*
G01X2059420D02*
X2059730Y3103630D01*
X2060195Y3105922D01*
X2060815Y3108005D01*
X2061590Y3110297D01*
X2062830Y3113422D01*
X2056630D01*
G01X2072130Y3100505D02*
X2071820Y3100714D01*
Y3101130D01*
X2072130Y3101339D01*
X2072440Y3101130D01*
Y3100714D01*
X2072130Y3100505D01*
G01X2084220Y3100922D02*
X2084530Y3103630D01*
X2084995Y3105922D01*
X2085615Y3108005D01*
X2086390Y3110297D01*
X2087630Y3113422D01*
X2081430D01*
G01X2036255Y3353789D02*
X2037185Y3355038D01*
X2038270Y3355664D01*
X2039510Y3355872D01*
X2041060Y3355455D01*
X2042145Y3354414D01*
X2042455Y3353164D01*
X2042300Y3351913D01*
X2041680Y3350872D01*
X2038580Y3348789D01*
X2037185Y3347330D01*
X2036255Y3345247D01*
X2035945Y3343372D01*
X2042455D01*
G01X2051600D02*
Y3355872D01*
X2049740Y3353372D01*
G01Y3343372D02*
X2053460D01*
G01X2064000Y3342955D02*
X2063690Y3343164D01*
Y3343580D01*
X2064000Y3343789D01*
X2064310Y3343580D01*
Y3343164D01*
X2064000Y3342955D01*
G01X2076400Y3343372D02*
X2077485Y3343580D01*
X2078725Y3344205D01*
X2079500Y3345247D01*
X2079810Y3346705D01*
X2079500Y3348163D01*
X2078570Y3349414D01*
X2077175Y3350039D01*
X2075625D01*
X2074695Y3350455D01*
X2073920Y3351497D01*
X2073610Y3352955D01*
X2074075Y3354414D01*
X2075160Y3355455D01*
X2076400Y3355872D01*
X2077640Y3355455D01*
X2078725Y3354414D01*
X2079190Y3352955D01*
X2078880Y3351497D01*
X2078105Y3350455D01*
X2077175Y3350039D01*
X2075625D01*
X2074230Y3349414D01*
X2073300Y3348163D01*
X2072990Y3346705D01*
X2073300Y3345247D01*
X2074075Y3344205D01*
X2075315Y3343580D01*
X2076400Y3343372D01*
G01X2088490D02*
X2088800Y3346080D01*
X2089265Y3348372D01*
X2089885Y3350455D01*
X2090660Y3352747D01*
X2091900Y3355872D01*
X2085700D01*
G01X2045400Y3368372D02*
Y3380872D01*
X2043540Y3378372D01*
G01Y3368372D02*
X2047260D01*
G01X2057490D02*
X2057800Y3371080D01*
X2058265Y3373372D01*
X2058885Y3375455D01*
X2059660Y3377747D01*
X2060900Y3380872D01*
X2054700D01*
G01X2070200Y3367955D02*
X2069890Y3368164D01*
Y3368580D01*
X2070200Y3368789D01*
X2070510Y3368580D01*
Y3368164D01*
X2070200Y3367955D01*
G01X2082290Y3368372D02*
X2082600Y3371080D01*
X2083065Y3373372D01*
X2083685Y3375455D01*
X2084460Y3377747D01*
X2085700Y3380872D01*
X2079500D01*
G01X2045400Y3393372D02*
Y3405872D01*
X2043540Y3403372D01*
G01Y3393372D02*
X2047260D01*
G01X2054390Y3395247D02*
X2055320Y3394205D01*
X2056405Y3393580D01*
X2057800Y3393372D01*
X2059195Y3393789D01*
X2060280Y3394622D01*
X2061055Y3396080D01*
X2061210Y3397747D01*
X2060900Y3399414D01*
X2060125Y3400455D01*
X2059040Y3401289D01*
X2057955Y3401497D01*
X2056870Y3401289D01*
X2055475Y3400455D01*
X2055940Y3405872D01*
X2060125D01*
G01X2070200Y3392955D02*
X2069890Y3393164D01*
Y3393580D01*
X2070200Y3393789D01*
X2070510Y3393580D01*
Y3393164D01*
X2070200Y3392955D01*
G01X2082290Y3393372D02*
X2082600Y3396080D01*
X2083065Y3398372D01*
X2083685Y3400455D01*
X2084460Y3402747D01*
X2085700Y3405872D01*
X2079500D01*
G01X2035705Y3643529D02*
X2036635Y3644778D01*
X2037720Y3645404D01*
X2038960Y3645612D01*
X2040510Y3645195D01*
X2041595Y3644154D01*
X2041905Y3642904D01*
X2041750Y3641653D01*
X2041130Y3640612D01*
X2038030Y3638529D01*
X2036635Y3637070D01*
X2035705Y3634987D01*
X2035395Y3633112D01*
X2041905D01*
G01X2051050D02*
Y3645612D01*
X2049190Y3643112D01*
G01Y3633112D02*
X2052910D01*
G01X2063450Y3632695D02*
X2063140Y3632904D01*
Y3633320D01*
X2063450Y3633529D01*
X2063760Y3633320D01*
Y3632904D01*
X2063450Y3632695D01*
G01X2075850Y3633112D02*
X2076935Y3633320D01*
X2078175Y3633945D01*
X2078950Y3634987D01*
X2079260Y3636445D01*
X2078950Y3637903D01*
X2078020Y3639154D01*
X2076625Y3639779D01*
X2075075D01*
X2074145Y3640195D01*
X2073370Y3641237D01*
X2073060Y3642695D01*
X2073525Y3644154D01*
X2074610Y3645195D01*
X2075850Y3645612D01*
X2077090Y3645195D01*
X2078175Y3644154D01*
X2078640Y3642695D01*
X2078330Y3641237D01*
X2077555Y3640195D01*
X2076625Y3639779D01*
X2075075D01*
X2073680Y3639154D01*
X2072750Y3637903D01*
X2072440Y3636445D01*
X2072750Y3634987D01*
X2073525Y3633945D01*
X2074765Y3633320D01*
X2075850Y3633112D01*
G01X2087940D02*
X2088250Y3635820D01*
X2088715Y3638112D01*
X2089335Y3640195D01*
X2090110Y3642487D01*
X2091350Y3645612D01*
X2085150D01*
G01X2044850Y3658112D02*
Y3670612D01*
X2042990Y3668112D01*
G01Y3658112D02*
X2046710D01*
G01X2056940D02*
X2057250Y3660820D01*
X2057715Y3663112D01*
X2058335Y3665195D01*
X2059110Y3667487D01*
X2060350Y3670612D01*
X2054150D01*
G01X2069650Y3657695D02*
X2069340Y3657904D01*
Y3658320D01*
X2069650Y3658529D01*
X2069960Y3658320D01*
Y3657904D01*
X2069650Y3657695D01*
G01X2081740Y3658112D02*
X2082050Y3660820D01*
X2082515Y3663112D01*
X2083135Y3665195D01*
X2083910Y3667487D01*
X2085150Y3670612D01*
X2078950D01*
G01X2044850Y3683112D02*
Y3695612D01*
X2042990Y3693112D01*
G01Y3683112D02*
X2046710D01*
G01X2053840Y3684987D02*
X2054770Y3683945D01*
X2055855Y3683320D01*
X2057250Y3683112D01*
X2058645Y3683529D01*
X2059730Y3684362D01*
X2060505Y3685820D01*
X2060660Y3687487D01*
X2060350Y3689154D01*
X2059575Y3690195D01*
X2058490Y3691029D01*
X2057405Y3691237D01*
X2056320Y3691029D01*
X2054925Y3690195D01*
X2055390Y3695612D01*
X2059575D01*
G01X2069650Y3682695D02*
X2069340Y3682904D01*
Y3683320D01*
X2069650Y3683529D01*
X2069960Y3683320D01*
Y3682904D01*
X2069650Y3682695D01*
G01X2081740Y3683112D02*
X2082050Y3685820D01*
X2082515Y3688112D01*
X2083135Y3690195D01*
X2083910Y3692487D01*
X2085150Y3695612D01*
X2078950D01*
G01X2064574Y1635711D02*
X2061474D01*
Y1636631D01*
X2061629Y1636938D01*
X2061991Y1637168D01*
X2062404Y1637245D01*
X2062817Y1637168D01*
X2063127Y1636976D01*
X2063282Y1636631D01*
Y1635711D01*
G01X2061732Y1640421D02*
X2061577Y1640191D01*
X2061474Y1639923D01*
Y1639616D01*
X2061629Y1639271D01*
X2061887Y1639003D01*
X2062197Y1638811D01*
X2062714Y1638658D01*
X2063179Y1638620D01*
X2063644Y1638696D01*
X2063954Y1638811D01*
X2064264Y1639041D01*
X2064471Y1639310D01*
X2064574Y1639578D01*
Y1639846D01*
X2064471Y1640115D01*
X2064316Y1640345D01*
X2064109Y1640536D01*
G01X2062921Y1642985D02*
X2062766Y1643138D01*
X2062507Y1643253D01*
X2062146Y1643330D01*
X2061836Y1643253D01*
X2061629Y1643100D01*
X2061474Y1642831D01*
Y1641796D01*
X2064574D01*
Y1643061D01*
X2064367Y1643330D01*
X2064057Y1643483D01*
X2063696Y1643560D01*
X2063334Y1643483D01*
X2063024Y1643253D01*
X2062921Y1642985D01*
Y1641796D01*
G01X2061474Y1647920D02*
X2064574Y1648878D01*
X2061474Y1649836D01*
G01X2064574Y1652745D02*
Y1651211D01*
X2061474D01*
Y1652745D01*
G01X2062972Y1652131D02*
Y1651211D01*
G01X2064574Y1654196D02*
X2061474D01*
X2064574Y1655960D01*
X2061474D01*
G01X2064574Y1657335D02*
X2061474D01*
Y1658101D01*
X2061629Y1658408D01*
X2061836Y1658638D01*
X2062146Y1658830D01*
X2062507Y1658983D01*
X2063024Y1659021D01*
X2063541Y1658983D01*
X2063902Y1658830D01*
X2064212Y1658638D01*
X2064419Y1658408D01*
X2064574Y1658101D01*
Y1657335D01*
G01Y1661278D02*
X2064522Y1660971D01*
X2064316Y1660703D01*
X2064006Y1660473D01*
X2063644Y1660320D01*
X2063231Y1660243D01*
X2062817D01*
X2062404Y1660320D01*
X2062042Y1660473D01*
X2061732Y1660703D01*
X2061526Y1660971D01*
X2061474Y1661278D01*
X2061526Y1661585D01*
X2061732Y1661853D01*
X2062042Y1662083D01*
X2062404Y1662236D01*
X2062817Y1662313D01*
X2063231D01*
X2063644Y1662236D01*
X2064006Y1662083D01*
X2064316Y1661853D01*
X2064522Y1661585D01*
X2064574Y1661278D01*
G01Y1663611D02*
X2061474D01*
Y1664570D01*
X2061629Y1664876D01*
X2061836Y1665068D01*
X2062249Y1665145D01*
X2062662Y1665068D01*
X2062921Y1664838D01*
X2063076Y1664570D01*
Y1663611D01*
G01Y1664570D02*
X2064574Y1665145D01*
G01X2058930Y2643662D02*
Y2656162D01*
X2057070Y2653662D01*
G01Y2643662D02*
X2060790D01*
G01X2071020D02*
X2071330Y2646370D01*
X2071795Y2648662D01*
X2072415Y2650745D01*
X2073190Y2653037D01*
X2074430Y2656162D01*
X2068230D01*
G01X2083730Y2643245D02*
X2083420Y2643454D01*
Y2643870D01*
X2083730Y2644079D01*
X2084040Y2643870D01*
Y2643454D01*
X2083730Y2643245D01*
G01X2095820Y2643662D02*
X2096130Y2646370D01*
X2096595Y2648662D01*
X2097215Y2650745D01*
X2097990Y2653037D01*
X2099230Y2656162D01*
X2093030D01*
G01X2069474Y1644211D02*
X2072574D01*
Y1645745D01*
G01Y1648078D02*
X2072522Y1647771D01*
X2072316Y1647503D01*
X2072006Y1647273D01*
X2071644Y1647120D01*
X2071231Y1647043D01*
X2070817D01*
X2070404Y1647120D01*
X2070042Y1647273D01*
X2069732Y1647503D01*
X2069526Y1647771D01*
X2069474Y1648078D01*
X2069526Y1648385D01*
X2069732Y1648653D01*
X2070042Y1648883D01*
X2070404Y1649036D01*
X2070817Y1649113D01*
X2071231D01*
X2071644Y1649036D01*
X2072006Y1648883D01*
X2072316Y1648653D01*
X2072522Y1648385D01*
X2072574Y1648078D01*
G01X2071024Y1651408D02*
Y1652175D01*
X2071954D01*
X2072264Y1651945D01*
X2072471Y1651676D01*
X2072574Y1651293D01*
X2072471Y1650910D01*
X2072264Y1650641D01*
X2071954Y1650411D01*
X2071592Y1650258D01*
X2071179Y1650181D01*
X2070817D01*
X2070507Y1650258D01*
X2070146Y1650411D01*
X2069836Y1650641D01*
X2069629Y1650871D01*
X2069474Y1651178D01*
Y1651446D01*
X2069577Y1651753D01*
X2069784Y1651983D01*
G01X2072574Y1654278D02*
X2072522Y1653971D01*
X2072316Y1653703D01*
X2072006Y1653473D01*
X2071644Y1653320D01*
X2071231Y1653243D01*
X2070817D01*
X2070404Y1653320D01*
X2070042Y1653473D01*
X2069732Y1653703D01*
X2069526Y1653971D01*
X2069474Y1654278D01*
X2069526Y1654585D01*
X2069732Y1654853D01*
X2070042Y1655083D01*
X2070404Y1655236D01*
X2070817Y1655313D01*
X2071231D01*
X2071644Y1655236D01*
X2072006Y1655083D01*
X2072316Y1654853D01*
X2072522Y1654585D01*
X2072574Y1654278D01*
G01X2144973Y2966207D02*
X2145593Y2966832D01*
X2146058Y2967873D01*
X2146368Y2969332D01*
X2146058Y2970582D01*
X2145438Y2971415D01*
X2144353Y2972040D01*
X2140168D01*
Y2959540D01*
X2145283D01*
X2146368Y2960373D01*
X2146988Y2961623D01*
X2147298Y2963082D01*
X2146988Y2964540D01*
X2146058Y2965790D01*
X2144973Y2966207D01*
X2140168D01*
G01X2152258Y2959540D02*
X2156133Y2972040D01*
X2160008Y2959540D01*
G01X2158613Y2963915D02*
X2153653D01*
G01X2171943Y2970998D02*
X2171013Y2971623D01*
X2169928Y2972040D01*
X2168688D01*
X2167293Y2971415D01*
X2166208Y2970373D01*
X2165433Y2969123D01*
X2164813Y2967040D01*
X2164658Y2965165D01*
X2164968Y2963290D01*
X2165433Y2962040D01*
X2166363Y2960790D01*
X2167448Y2959957D01*
X2168533Y2959540D01*
X2169618D01*
X2170703Y2959957D01*
X2171633Y2960581D01*
X2172408Y2961415D01*
G01X2177523Y2959540D02*
Y2972040D01*
G01X2183413D02*
X2177523Y2964331D01*
G01X2184343Y2959540D02*
X2180158Y2967873D01*
G01X2189923Y2959540D02*
Y2972040D01*
X2193023D01*
X2194263Y2971415D01*
X2195193Y2970582D01*
X2195968Y2969332D01*
X2196588Y2967873D01*
X2196743Y2965790D01*
X2196588Y2963707D01*
X2195968Y2962248D01*
X2195193Y2960998D01*
X2194263Y2960165D01*
X2193023Y2959540D01*
X2189923D01*
G01X2202633D02*
Y2972040D01*
X2206508D01*
X2207748Y2971415D01*
X2208523Y2970582D01*
X2208833Y2968915D01*
X2208523Y2967248D01*
X2207593Y2966207D01*
X2206508Y2965582D01*
X2202633D01*
G01X2206508D02*
X2208833Y2959540D01*
G01X2216273Y2972040D02*
X2219993D01*
G01X2218133D02*
Y2959540D01*
G01X2216273D02*
X2219993D01*
G01X2227433Y2972040D02*
Y2959540D01*
X2233633D01*
G01X2239833Y2972040D02*
Y2959540D01*
X2246033D01*
G01X2255333Y2959123D02*
X2255023Y2959332D01*
Y2959748D01*
X2255333Y2959957D01*
X2255643Y2959748D01*
Y2959332D01*
X2255333Y2959123D01*
G01Y2964748D02*
X2255023Y2964957D01*
Y2965373D01*
X2255333Y2965582D01*
X2255643Y2965373D01*
Y2964957D01*
X2255333Y2964748D01*
G01X2281373Y2966207D02*
X2281993Y2966832D01*
X2282458Y2967873D01*
X2282768Y2969332D01*
X2282458Y2970582D01*
X2281838Y2971415D01*
X2280753Y2972040D01*
X2276568D01*
Y2959540D01*
X2281683D01*
X2282768Y2960373D01*
X2283388Y2961623D01*
X2283698Y2963082D01*
X2283388Y2964540D01*
X2282458Y2965790D01*
X2281373Y2966207D01*
X2276568D01*
G01X2292533Y2959540D02*
X2291293Y2959748D01*
X2290208Y2960581D01*
X2289278Y2961832D01*
X2288658Y2963290D01*
X2288348Y2964957D01*
Y2966623D01*
X2288658Y2968290D01*
X2289278Y2969748D01*
X2290208Y2970998D01*
X2291293Y2971832D01*
X2292533Y2972040D01*
X2293773Y2971832D01*
X2294858Y2970998D01*
X2295788Y2969748D01*
X2296408Y2968290D01*
X2296718Y2966623D01*
Y2964957D01*
X2296408Y2963290D01*
X2295788Y2961832D01*
X2294858Y2960581D01*
X2293773Y2959748D01*
X2292533Y2959540D01*
G01X2304933Y2972040D02*
Y2959540D01*
G01X2301368Y2972040D02*
X2308498D01*
G01X2317333D02*
Y2959540D01*
G01X2313768Y2972040D02*
X2320898D01*
G01X2329733Y2959540D02*
X2328493Y2959748D01*
X2327408Y2960581D01*
X2326478Y2961832D01*
X2325858Y2963290D01*
X2325548Y2964957D01*
Y2966623D01*
X2325858Y2968290D01*
X2326478Y2969748D01*
X2327408Y2970998D01*
X2328493Y2971832D01*
X2329733Y2972040D01*
X2330973Y2971832D01*
X2332058Y2970998D01*
X2332988Y2969748D01*
X2333608Y2968290D01*
X2333918Y2966623D01*
Y2964957D01*
X2333608Y2963290D01*
X2332988Y2961832D01*
X2332058Y2960581D01*
X2330973Y2959748D01*
X2329733Y2959540D01*
G01X2338103D02*
Y2972040D01*
X2342133Y2961623D01*
X2346163Y2972040D01*
Y2959540D01*
G01X2366933Y2972040D02*
Y2959540D01*
G01X2364763Y2967873D02*
X2369103D01*
G01X2379333Y2959540D02*
X2378403Y2959748D01*
X2377473Y2960581D01*
X2376853Y2962040D01*
X2376543Y2963707D01*
X2376853Y2965373D01*
X2377473Y2966832D01*
X2378403Y2967665D01*
X2379333Y2967873D01*
X2380263Y2967665D01*
X2381193Y2966832D01*
X2381813Y2965373D01*
X2381968Y2963707D01*
X2381813Y2962040D01*
X2381193Y2960581D01*
X2380263Y2959748D01*
X2379333Y2959540D01*
G01X2400258Y2972040D02*
X2404133Y2959540D01*
X2408008Y2972040D01*
G01X2419943Y2970998D02*
X2419013Y2971623D01*
X2417928Y2972040D01*
X2416688D01*
X2415293Y2971415D01*
X2414208Y2970373D01*
X2413433Y2969123D01*
X2412813Y2967040D01*
X2412658Y2965165D01*
X2412968Y2963290D01*
X2413433Y2962040D01*
X2414363Y2960790D01*
X2415448Y2959957D01*
X2416533Y2959540D01*
X2417618D01*
X2418703Y2959957D01*
X2419633Y2960581D01*
X2420408Y2961415D01*
G01X2432343Y2970998D02*
X2431413Y2971623D01*
X2430328Y2972040D01*
X2429088D01*
X2427693Y2971415D01*
X2426608Y2970373D01*
X2425833Y2969123D01*
X2425213Y2967040D01*
X2425058Y2965165D01*
X2425368Y2963290D01*
X2425833Y2962040D01*
X2426763Y2960790D01*
X2427848Y2959957D01*
X2428933Y2959540D01*
X2430018D01*
X2431103Y2959957D01*
X2432033Y2960581D01*
X2432808Y2961415D01*
G01X2138090Y3475039D02*
X2138710Y3475664D01*
X2139175Y3476705D01*
X2139485Y3478164D01*
X2139175Y3479414D01*
X2138555Y3480247D01*
X2137470Y3480872D01*
X2133285D01*
Y3468372D01*
X2138400D01*
X2139485Y3469205D01*
X2140105Y3470455D01*
X2140415Y3471914D01*
X2140105Y3473372D01*
X2139175Y3474622D01*
X2138090Y3475039D01*
X2133285D01*
G01X2145375Y3468372D02*
X2149250Y3480872D01*
X2153125Y3468372D01*
G01X2151730Y3472747D02*
X2146770D01*
G01X2165060Y3479830D02*
X2164130Y3480455D01*
X2163045Y3480872D01*
X2161805D01*
X2160410Y3480247D01*
X2159325Y3479205D01*
X2158550Y3477955D01*
X2157930Y3475872D01*
X2157775Y3473997D01*
X2158085Y3472122D01*
X2158550Y3470872D01*
X2159480Y3469622D01*
X2160565Y3468789D01*
X2161650Y3468372D01*
X2162735D01*
X2163820Y3468789D01*
X2164750Y3469413D01*
X2165525Y3470247D01*
G01X2170640Y3468372D02*
Y3480872D01*
G01X2176530D02*
X2170640Y3473163D01*
G01X2177460Y3468372D02*
X2173275Y3476705D01*
G01X2183040Y3468372D02*
Y3480872D01*
X2186140D01*
X2187380Y3480247D01*
X2188310Y3479414D01*
X2189085Y3478164D01*
X2189705Y3476705D01*
X2189860Y3474622D01*
X2189705Y3472539D01*
X2189085Y3471080D01*
X2188310Y3469830D01*
X2187380Y3468997D01*
X2186140Y3468372D01*
X2183040D01*
G01X2195750D02*
Y3480872D01*
X2199625D01*
X2200865Y3480247D01*
X2201640Y3479414D01*
X2201950Y3477747D01*
X2201640Y3476080D01*
X2200710Y3475039D01*
X2199625Y3474414D01*
X2195750D01*
G01X2199625D02*
X2201950Y3468372D01*
G01X2209390Y3480872D02*
X2213110D01*
G01X2211250D02*
Y3468372D01*
G01X2209390D02*
X2213110D01*
G01X2220550Y3480872D02*
Y3468372D01*
X2226750D01*
G01X2232950Y3480872D02*
Y3468372D01*
X2239150D01*
G01X2248450Y3467955D02*
X2248140Y3468164D01*
Y3468580D01*
X2248450Y3468789D01*
X2248760Y3468580D01*
Y3468164D01*
X2248450Y3467955D01*
G01Y3473580D02*
X2248140Y3473789D01*
Y3474205D01*
X2248450Y3474414D01*
X2248760Y3474205D01*
Y3473789D01*
X2248450Y3473580D01*
G01X2274490Y3475039D02*
X2275110Y3475664D01*
X2275575Y3476705D01*
X2275885Y3478164D01*
X2275575Y3479414D01*
X2274955Y3480247D01*
X2273870Y3480872D01*
X2269685D01*
Y3468372D01*
X2274800D01*
X2275885Y3469205D01*
X2276505Y3470455D01*
X2276815Y3471914D01*
X2276505Y3473372D01*
X2275575Y3474622D01*
X2274490Y3475039D01*
X2269685D01*
G01X2285650Y3468372D02*
X2284410Y3468580D01*
X2283325Y3469413D01*
X2282395Y3470664D01*
X2281775Y3472122D01*
X2281465Y3473789D01*
Y3475455D01*
X2281775Y3477122D01*
X2282395Y3478580D01*
X2283325Y3479830D01*
X2284410Y3480664D01*
X2285650Y3480872D01*
X2286890Y3480664D01*
X2287975Y3479830D01*
X2288905Y3478580D01*
X2289525Y3477122D01*
X2289835Y3475455D01*
Y3473789D01*
X2289525Y3472122D01*
X2288905Y3470664D01*
X2287975Y3469413D01*
X2286890Y3468580D01*
X2285650Y3468372D01*
G01X2298050Y3480872D02*
Y3468372D01*
G01X2294485Y3480872D02*
X2301615D01*
G01X2310450D02*
Y3468372D01*
G01X2306885Y3480872D02*
X2314015D01*
G01X2322850Y3468372D02*
X2321610Y3468580D01*
X2320525Y3469413D01*
X2319595Y3470664D01*
X2318975Y3472122D01*
X2318665Y3473789D01*
Y3475455D01*
X2318975Y3477122D01*
X2319595Y3478580D01*
X2320525Y3479830D01*
X2321610Y3480664D01*
X2322850Y3480872D01*
X2324090Y3480664D01*
X2325175Y3479830D01*
X2326105Y3478580D01*
X2326725Y3477122D01*
X2327035Y3475455D01*
Y3473789D01*
X2326725Y3472122D01*
X2326105Y3470664D01*
X2325175Y3469413D01*
X2324090Y3468580D01*
X2322850Y3468372D01*
G01X2331220D02*
Y3480872D01*
X2335250Y3470455D01*
X2339280Y3480872D01*
Y3468372D01*
G01X2360050Y3480872D02*
Y3468372D01*
G01X2357880Y3476705D02*
X2362220D01*
G01X2372450Y3468372D02*
X2371520Y3468580D01*
X2370590Y3469413D01*
X2369970Y3470872D01*
X2369660Y3472539D01*
X2369970Y3474205D01*
X2370590Y3475664D01*
X2371520Y3476497D01*
X2372450Y3476705D01*
X2373380Y3476497D01*
X2374310Y3475664D01*
X2374930Y3474205D01*
X2375085Y3472539D01*
X2374930Y3470872D01*
X2374310Y3469413D01*
X2373380Y3468580D01*
X2372450Y3468372D01*
G01X2398180Y3474622D02*
X2401280D01*
Y3470872D01*
X2400350Y3469622D01*
X2399265Y3468789D01*
X2397715Y3468372D01*
X2396165Y3468789D01*
X2395080Y3469622D01*
X2394150Y3470872D01*
X2393530Y3472330D01*
X2393220Y3473997D01*
Y3475455D01*
X2393530Y3476705D01*
X2394150Y3478164D01*
X2395080Y3479414D01*
X2396010Y3480247D01*
X2397250Y3480872D01*
X2398335D01*
X2399575Y3480455D01*
X2400505Y3479622D01*
G01X2406085Y3468372D02*
Y3480872D01*
X2413215Y3468372D01*
Y3480872D01*
G01X2418640Y3468372D02*
Y3480872D01*
X2421740D01*
X2422980Y3480247D01*
X2423910Y3479414D01*
X2424685Y3478164D01*
X2425305Y3476705D01*
X2425460Y3474622D01*
X2425305Y3472539D01*
X2424685Y3471080D01*
X2423910Y3469830D01*
X2422980Y3468997D01*
X2421740Y3468372D01*
X2418640D01*
G01X2434140D02*
X2434450Y3471080D01*
X2434915Y3473372D01*
X2435535Y3475455D01*
X2436310Y3477747D01*
X2437550Y3480872D01*
X2431350D01*
G01X2137540Y3764779D02*
X2138160Y3765404D01*
X2138625Y3766445D01*
X2138935Y3767904D01*
X2138625Y3769154D01*
X2138005Y3769987D01*
X2136920Y3770612D01*
X2132735D01*
Y3758112D01*
X2137850D01*
X2138935Y3758945D01*
X2139555Y3760195D01*
X2139865Y3761654D01*
X2139555Y3763112D01*
X2138625Y3764362D01*
X2137540Y3764779D01*
X2132735D01*
G01X2144825Y3758112D02*
X2148700Y3770612D01*
X2152575Y3758112D01*
G01X2151180Y3762487D02*
X2146220D01*
G01X2164510Y3769570D02*
X2163580Y3770195D01*
X2162495Y3770612D01*
X2161255D01*
X2159860Y3769987D01*
X2158775Y3768945D01*
X2158000Y3767695D01*
X2157380Y3765612D01*
X2157225Y3763737D01*
X2157535Y3761862D01*
X2158000Y3760612D01*
X2158930Y3759362D01*
X2160015Y3758529D01*
X2161100Y3758112D01*
X2162185D01*
X2163270Y3758529D01*
X2164200Y3759153D01*
X2164975Y3759987D01*
G01X2170090Y3758112D02*
Y3770612D01*
G01X2175980D02*
X2170090Y3762903D01*
G01X2176910Y3758112D02*
X2172725Y3766445D01*
G01X2182490Y3758112D02*
Y3770612D01*
X2185590D01*
X2186830Y3769987D01*
X2187760Y3769154D01*
X2188535Y3767904D01*
X2189155Y3766445D01*
X2189310Y3764362D01*
X2189155Y3762279D01*
X2188535Y3760820D01*
X2187760Y3759570D01*
X2186830Y3758737D01*
X2185590Y3758112D01*
X2182490D01*
G01X2195200D02*
Y3770612D01*
X2199075D01*
X2200315Y3769987D01*
X2201090Y3769154D01*
X2201400Y3767487D01*
X2201090Y3765820D01*
X2200160Y3764779D01*
X2199075Y3764154D01*
X2195200D01*
G01X2199075D02*
X2201400Y3758112D01*
G01X2208840Y3770612D02*
X2212560D01*
G01X2210700D02*
Y3758112D01*
G01X2208840D02*
X2212560D01*
G01X2220000Y3770612D02*
Y3758112D01*
X2226200D01*
G01X2232400Y3770612D02*
Y3758112D01*
X2238600D01*
G01X2247900Y3757695D02*
X2247590Y3757904D01*
Y3758320D01*
X2247900Y3758529D01*
X2248210Y3758320D01*
Y3757904D01*
X2247900Y3757695D01*
G01Y3763320D02*
X2247590Y3763529D01*
Y3763945D01*
X2247900Y3764154D01*
X2248210Y3763945D01*
Y3763529D01*
X2247900Y3763320D01*
G01X2273940Y3764779D02*
X2274560Y3765404D01*
X2275025Y3766445D01*
X2275335Y3767904D01*
X2275025Y3769154D01*
X2274405Y3769987D01*
X2273320Y3770612D01*
X2269135D01*
Y3758112D01*
X2274250D01*
X2275335Y3758945D01*
X2275955Y3760195D01*
X2276265Y3761654D01*
X2275955Y3763112D01*
X2275025Y3764362D01*
X2273940Y3764779D01*
X2269135D01*
G01X2285100Y3758112D02*
X2283860Y3758320D01*
X2282775Y3759153D01*
X2281845Y3760404D01*
X2281225Y3761862D01*
X2280915Y3763529D01*
Y3765195D01*
X2281225Y3766862D01*
X2281845Y3768320D01*
X2282775Y3769570D01*
X2283860Y3770404D01*
X2285100Y3770612D01*
X2286340Y3770404D01*
X2287425Y3769570D01*
X2288355Y3768320D01*
X2288975Y3766862D01*
X2289285Y3765195D01*
Y3763529D01*
X2288975Y3761862D01*
X2288355Y3760404D01*
X2287425Y3759153D01*
X2286340Y3758320D01*
X2285100Y3758112D01*
G01X2297500Y3770612D02*
Y3758112D01*
G01X2293935Y3770612D02*
X2301065D01*
G01X2309900D02*
Y3758112D01*
G01X2306335Y3770612D02*
X2313465D01*
G01X2322300Y3758112D02*
X2321060Y3758320D01*
X2319975Y3759153D01*
X2319045Y3760404D01*
X2318425Y3761862D01*
X2318115Y3763529D01*
Y3765195D01*
X2318425Y3766862D01*
X2319045Y3768320D01*
X2319975Y3769570D01*
X2321060Y3770404D01*
X2322300Y3770612D01*
X2323540Y3770404D01*
X2324625Y3769570D01*
X2325555Y3768320D01*
X2326175Y3766862D01*
X2326485Y3765195D01*
Y3763529D01*
X2326175Y3761862D01*
X2325555Y3760404D01*
X2324625Y3759153D01*
X2323540Y3758320D01*
X2322300Y3758112D01*
G01X2330670D02*
Y3770612D01*
X2334700Y3760195D01*
X2338730Y3770612D01*
Y3758112D01*
G01X2359500Y3770612D02*
Y3758112D01*
G01X2357330Y3766445D02*
X2361670D01*
G01X2371900Y3758112D02*
X2370970Y3758320D01*
X2370040Y3759153D01*
X2369420Y3760612D01*
X2369110Y3762279D01*
X2369420Y3763945D01*
X2370040Y3765404D01*
X2370970Y3766237D01*
X2371900Y3766445D01*
X2372830Y3766237D01*
X2373760Y3765404D01*
X2374380Y3763945D01*
X2374535Y3762279D01*
X2374380Y3760612D01*
X2373760Y3759153D01*
X2372830Y3758320D01*
X2371900Y3758112D01*
G01X2397630Y3764362D02*
X2400730D01*
Y3760612D01*
X2399800Y3759362D01*
X2398715Y3758529D01*
X2397165Y3758112D01*
X2395615Y3758529D01*
X2394530Y3759362D01*
X2393600Y3760612D01*
X2392980Y3762070D01*
X2392670Y3763737D01*
Y3765195D01*
X2392980Y3766445D01*
X2393600Y3767904D01*
X2394530Y3769154D01*
X2395460Y3769987D01*
X2396700Y3770612D01*
X2397785D01*
X2399025Y3770195D01*
X2399955Y3769362D01*
G01X2405535Y3758112D02*
Y3770612D01*
X2412665Y3758112D01*
Y3770612D01*
G01X2418090Y3758112D02*
Y3770612D01*
X2421190D01*
X2422430Y3769987D01*
X2423360Y3769154D01*
X2424135Y3767904D01*
X2424755Y3766445D01*
X2424910Y3764362D01*
X2424755Y3762279D01*
X2424135Y3760820D01*
X2423360Y3759570D01*
X2422430Y3758737D01*
X2421190Y3758112D01*
X2418090D01*
G01X2430955Y3763320D02*
X2432040Y3764779D01*
X2432970Y3765612D01*
X2434210Y3766029D01*
X2435295Y3765612D01*
X2436070Y3764779D01*
X2436690Y3763529D01*
X2436845Y3762070D01*
X2436690Y3760820D01*
X2436070Y3759570D01*
X2435140Y3758529D01*
X2434055Y3758112D01*
X2432815Y3758529D01*
X2431730Y3759778D01*
X2431110Y3761654D01*
X2430955Y3763737D01*
X2431265Y3766445D01*
X2431730Y3767904D01*
X2432505Y3769362D01*
X2433590Y3770404D01*
X2434675Y3770612D01*
X2435760Y3770195D01*
X2436535Y3769154D01*
G01X2158458Y2934540D02*
X2162333Y2947040D01*
X2166208Y2934540D01*
G01X2164813Y2938915D02*
X2159853D01*
G01X2171633Y2947040D02*
Y2934540D01*
X2177833D01*
G01X2184033Y2947040D02*
Y2934540D01*
X2190233D01*
G01X2208523Y2947040D02*
Y2938082D01*
X2209143Y2936206D01*
X2210383Y2934957D01*
X2211933Y2934540D01*
X2213483Y2934957D01*
X2214723Y2936206D01*
X2215343Y2938082D01*
Y2947040D01*
G01X2220768Y2934540D02*
Y2947040D01*
X2227898Y2934540D01*
Y2947040D01*
G01X2234873D02*
X2238593D01*
G01X2236733D02*
Y2934540D01*
G01X2234873D02*
X2238593D01*
G01X2249133Y2947040D02*
Y2934540D01*
G01X2245568Y2947040D02*
X2252698D01*
G01X2258278Y2936206D02*
X2259518Y2935165D01*
X2260913Y2934540D01*
X2262153D01*
X2263393Y2935165D01*
X2264323Y2936206D01*
X2264788Y2937665D01*
X2264478Y2939123D01*
X2263703Y2940373D01*
X2262308Y2941207D01*
X2260448Y2941623D01*
X2259363Y2942457D01*
X2258898Y2943915D01*
X2259208Y2945373D01*
X2259983Y2946415D01*
X2261068Y2947040D01*
X2262153D01*
X2263238Y2946623D01*
X2264168Y2945582D01*
G01X2282458Y2934540D02*
X2286333Y2947040D01*
X2290208Y2934540D01*
G01X2288813Y2938915D02*
X2283853D01*
G01X2295633Y2934540D02*
Y2947040D01*
X2299508D01*
X2300748Y2946415D01*
X2301523Y2945582D01*
X2301833Y2943915D01*
X2301523Y2942248D01*
X2300593Y2941207D01*
X2299508Y2940582D01*
X2295633D01*
G01X2299508D02*
X2301833Y2934540D01*
G01X2314233D02*
X2308033D01*
Y2947040D01*
X2314233D01*
G01X2311753Y2940998D02*
X2308033D01*
G01X2334073Y2947040D02*
X2337793D01*
G01X2335933D02*
Y2934540D01*
G01X2334073D02*
X2337793D01*
G01X2344768D02*
Y2947040D01*
X2351898Y2934540D01*
Y2947040D01*
G01X2369103Y2934540D02*
Y2947040D01*
X2373133Y2936623D01*
X2377163Y2947040D01*
Y2934540D01*
G01X2383673Y2947040D02*
X2387393D01*
G01X2385533D02*
Y2934540D01*
G01X2383673D02*
X2387393D01*
G01X2394833Y2947040D02*
Y2934540D01*
X2401033D01*
G01X2407078Y2936206D02*
X2408318Y2935165D01*
X2409713Y2934540D01*
X2410953D01*
X2412193Y2935165D01*
X2413123Y2936206D01*
X2413588Y2937665D01*
X2413278Y2939123D01*
X2412503Y2940373D01*
X2411108Y2941207D01*
X2409248Y2941623D01*
X2408163Y2942457D01*
X2407698Y2943915D01*
X2408008Y2945373D01*
X2408783Y2946415D01*
X2409868Y2947040D01*
X2410953D01*
X2412038Y2946623D01*
X2412968Y2945582D01*
G01X2159705Y3150922D02*
X2163580Y3163422D01*
X2167455Y3150922D01*
G01X2166060Y3155297D02*
X2161100D01*
G01X2172880Y3163422D02*
Y3150922D01*
X2179080D01*
G01X2185280Y3163422D02*
Y3150922D01*
X2191480D01*
G01X2209770Y3163422D02*
Y3154464D01*
X2210390Y3152588D01*
X2211630Y3151339D01*
X2213180Y3150922D01*
X2214730Y3151339D01*
X2215970Y3152588D01*
X2216590Y3154464D01*
Y3163422D01*
G01X2222015Y3150922D02*
Y3163422D01*
X2229145Y3150922D01*
Y3163422D01*
G01X2236120D02*
X2239840D01*
G01X2237980D02*
Y3150922D01*
G01X2236120D02*
X2239840D01*
G01X2250380Y3163422D02*
Y3150922D01*
G01X2246815Y3163422D02*
X2253945D01*
G01X2259525Y3152588D02*
X2260765Y3151547D01*
X2262160Y3150922D01*
X2263400D01*
X2264640Y3151547D01*
X2265570Y3152588D01*
X2266035Y3154047D01*
X2265725Y3155505D01*
X2264950Y3156755D01*
X2263555Y3157589D01*
X2261695Y3158005D01*
X2260610Y3158839D01*
X2260145Y3160297D01*
X2260455Y3161755D01*
X2261230Y3162797D01*
X2262315Y3163422D01*
X2263400D01*
X2264485Y3163005D01*
X2265415Y3161964D01*
G01X2283705Y3150922D02*
X2287580Y3163422D01*
X2291455Y3150922D01*
G01X2290060Y3155297D02*
X2285100D01*
G01X2296880Y3150922D02*
Y3163422D01*
X2300755D01*
X2301995Y3162797D01*
X2302770Y3161964D01*
X2303080Y3160297D01*
X2302770Y3158630D01*
X2301840Y3157589D01*
X2300755Y3156964D01*
X2296880D01*
G01X2300755D02*
X2303080Y3150922D01*
G01X2315480D02*
X2309280D01*
Y3163422D01*
X2315480D01*
G01X2313000Y3157380D02*
X2309280D01*
G01X2335320Y3163422D02*
X2339040D01*
G01X2337180D02*
Y3150922D01*
G01X2335320D02*
X2339040D01*
G01X2346015D02*
Y3163422D01*
X2353145Y3150922D01*
Y3163422D01*
G01X2370350Y3150922D02*
Y3163422D01*
X2374380Y3153005D01*
X2378410Y3163422D01*
Y3150922D01*
G01X2384920Y3163422D02*
X2388640D01*
G01X2386780D02*
Y3150922D01*
G01X2384920D02*
X2388640D01*
G01X2396080Y3163422D02*
Y3150922D01*
X2402280D01*
G01X2408325Y3152588D02*
X2409565Y3151547D01*
X2410960Y3150922D01*
X2412200D01*
X2413440Y3151547D01*
X2414370Y3152588D01*
X2414835Y3154047D01*
X2414525Y3155505D01*
X2413750Y3156755D01*
X2412355Y3157589D01*
X2410495Y3158005D01*
X2409410Y3158839D01*
X2408945Y3160297D01*
X2409255Y3161755D01*
X2410030Y3162797D01*
X2411115Y3163422D01*
X2412200D01*
X2413285Y3163005D01*
X2414215Y3161964D01*
G01X2158620Y3182589D02*
X2159240Y3183214D01*
X2159705Y3184255D01*
X2160015Y3185714D01*
X2159705Y3186964D01*
X2159085Y3187797D01*
X2158000Y3188422D01*
X2153815D01*
Y3175922D01*
X2158930D01*
X2160015Y3176755D01*
X2160635Y3178005D01*
X2160945Y3179464D01*
X2160635Y3180922D01*
X2159705Y3182172D01*
X2158620Y3182589D01*
X2153815D01*
G01X2165905Y3175922D02*
X2169780Y3188422D01*
X2173655Y3175922D01*
G01X2172260Y3180297D02*
X2167300D01*
G01X2185590Y3187380D02*
X2184660Y3188005D01*
X2183575Y3188422D01*
X2182335D01*
X2180940Y3187797D01*
X2179855Y3186755D01*
X2179080Y3185505D01*
X2178460Y3183422D01*
X2178305Y3181547D01*
X2178615Y3179672D01*
X2179080Y3178422D01*
X2180010Y3177172D01*
X2181095Y3176339D01*
X2182180Y3175922D01*
X2183265D01*
X2184350Y3176339D01*
X2185280Y3176963D01*
X2186055Y3177797D01*
G01X2191170Y3175922D02*
Y3188422D01*
G01X2197060D02*
X2191170Y3180713D01*
G01X2197990Y3175922D02*
X2193805Y3184255D01*
G01X2203570Y3175922D02*
Y3188422D01*
X2206670D01*
X2207910Y3187797D01*
X2208840Y3186964D01*
X2209615Y3185714D01*
X2210235Y3184255D01*
X2210390Y3182172D01*
X2210235Y3180089D01*
X2209615Y3178630D01*
X2208840Y3177380D01*
X2207910Y3176547D01*
X2206670Y3175922D01*
X2203570D01*
G01X2216280D02*
Y3188422D01*
X2220155D01*
X2221395Y3187797D01*
X2222170Y3186964D01*
X2222480Y3185297D01*
X2222170Y3183630D01*
X2221240Y3182589D01*
X2220155Y3181964D01*
X2216280D01*
G01X2220155D02*
X2222480Y3175922D01*
G01X2229920Y3188422D02*
X2233640D01*
G01X2231780D02*
Y3175922D01*
G01X2229920D02*
X2233640D01*
G01X2241080Y3188422D02*
Y3175922D01*
X2247280D01*
G01X2253480Y3188422D02*
Y3175922D01*
X2259680D01*
G01X2268980Y3175505D02*
X2268670Y3175714D01*
Y3176130D01*
X2268980Y3176339D01*
X2269290Y3176130D01*
Y3175714D01*
X2268980Y3175505D01*
G01Y3181130D02*
X2268670Y3181339D01*
Y3181755D01*
X2268980Y3181964D01*
X2269290Y3181755D01*
Y3181339D01*
X2268980Y3181130D01*
G01X2293780Y3188422D02*
Y3175922D01*
G01X2290215Y3188422D02*
X2297345D01*
G01X2306180Y3175922D02*
X2304940Y3176130D01*
X2303855Y3176963D01*
X2302925Y3178214D01*
X2302305Y3179672D01*
X2301995Y3181339D01*
Y3183005D01*
X2302305Y3184672D01*
X2302925Y3186130D01*
X2303855Y3187380D01*
X2304940Y3188214D01*
X2306180Y3188422D01*
X2307420Y3188214D01*
X2308505Y3187380D01*
X2309435Y3186130D01*
X2310055Y3184672D01*
X2310365Y3183005D01*
Y3181339D01*
X2310055Y3179672D01*
X2309435Y3178214D01*
X2308505Y3176963D01*
X2307420Y3176130D01*
X2306180Y3175922D01*
G01X2315480D02*
Y3188422D01*
X2319200D01*
X2320440Y3187797D01*
X2321370Y3186339D01*
X2321680Y3184672D01*
X2321370Y3183005D01*
X2320595Y3181755D01*
X2319200Y3181130D01*
X2315480D01*
G01X2343380Y3188422D02*
Y3175922D01*
G01X2341210Y3184255D02*
X2345550D01*
G01X2355780Y3175922D02*
X2354850Y3176130D01*
X2353920Y3176963D01*
X2353300Y3178422D01*
X2352990Y3180089D01*
X2353300Y3181755D01*
X2353920Y3183214D01*
X2354850Y3184047D01*
X2355780Y3184255D01*
X2356710Y3184047D01*
X2357640Y3183214D01*
X2358260Y3181755D01*
X2358415Y3180089D01*
X2358260Y3178422D01*
X2357640Y3176963D01*
X2356710Y3176130D01*
X2355780Y3175922D01*
G01X2381510Y3182172D02*
X2384610D01*
Y3178422D01*
X2383680Y3177172D01*
X2382595Y3176339D01*
X2381045Y3175922D01*
X2379495Y3176339D01*
X2378410Y3177172D01*
X2377480Y3178422D01*
X2376860Y3179880D01*
X2376550Y3181547D01*
Y3183005D01*
X2376860Y3184255D01*
X2377480Y3185714D01*
X2378410Y3186964D01*
X2379340Y3187797D01*
X2380580Y3188422D01*
X2381665D01*
X2382905Y3188005D01*
X2383835Y3187172D01*
G01X2389415Y3175922D02*
Y3188422D01*
X2396545Y3175922D01*
Y3188422D01*
G01X2401970Y3175922D02*
Y3188422D01*
X2405070D01*
X2406310Y3187797D01*
X2407240Y3186964D01*
X2408015Y3185714D01*
X2408635Y3184255D01*
X2408790Y3182172D01*
X2408635Y3180089D01*
X2408015Y3178630D01*
X2407240Y3177380D01*
X2406310Y3176547D01*
X2405070Y3175922D01*
X2401970D01*
G01X2414835Y3186339D02*
X2415765Y3187588D01*
X2416850Y3188214D01*
X2418090Y3188422D01*
X2419640Y3188005D01*
X2420725Y3186964D01*
X2421035Y3185714D01*
X2420880Y3184463D01*
X2420260Y3183422D01*
X2417160Y3181339D01*
X2415765Y3179880D01*
X2414835Y3177797D01*
X2414525Y3175922D01*
X2421035D01*
G01X2157775Y3443372D02*
X2161650Y3455872D01*
X2165525Y3443372D01*
G01X2164130Y3447747D02*
X2159170D01*
G01X2170950Y3455872D02*
Y3443372D01*
X2177150D01*
G01X2183350Y3455872D02*
Y3443372D01*
X2189550D01*
G01X2207840Y3455872D02*
Y3446914D01*
X2208460Y3445038D01*
X2209700Y3443789D01*
X2211250Y3443372D01*
X2212800Y3443789D01*
X2214040Y3445038D01*
X2214660Y3446914D01*
Y3455872D01*
G01X2220085Y3443372D02*
Y3455872D01*
X2227215Y3443372D01*
Y3455872D01*
G01X2234190D02*
X2237910D01*
G01X2236050D02*
Y3443372D01*
G01X2234190D02*
X2237910D01*
G01X2248450Y3455872D02*
Y3443372D01*
G01X2244885Y3455872D02*
X2252015D01*
G01X2257595Y3445038D02*
X2258835Y3443997D01*
X2260230Y3443372D01*
X2261470D01*
X2262710Y3443997D01*
X2263640Y3445038D01*
X2264105Y3446497D01*
X2263795Y3447955D01*
X2263020Y3449205D01*
X2261625Y3450039D01*
X2259765Y3450455D01*
X2258680Y3451289D01*
X2258215Y3452747D01*
X2258525Y3454205D01*
X2259300Y3455247D01*
X2260385Y3455872D01*
X2261470D01*
X2262555Y3455455D01*
X2263485Y3454414D01*
G01X2281775Y3443372D02*
X2285650Y3455872D01*
X2289525Y3443372D01*
G01X2288130Y3447747D02*
X2283170D01*
G01X2294950Y3443372D02*
Y3455872D01*
X2298825D01*
X2300065Y3455247D01*
X2300840Y3454414D01*
X2301150Y3452747D01*
X2300840Y3451080D01*
X2299910Y3450039D01*
X2298825Y3449414D01*
X2294950D01*
G01X2298825D02*
X2301150Y3443372D01*
G01X2313550D02*
X2307350D01*
Y3455872D01*
X2313550D01*
G01X2311070Y3449830D02*
X2307350D01*
G01X2333390Y3455872D02*
X2337110D01*
G01X2335250D02*
Y3443372D01*
G01X2333390D02*
X2337110D01*
G01X2344085D02*
Y3455872D01*
X2351215Y3443372D01*
Y3455872D01*
G01X2368420Y3443372D02*
Y3455872D01*
X2372450Y3445455D01*
X2376480Y3455872D01*
Y3443372D01*
G01X2382990Y3455872D02*
X2386710D01*
G01X2384850D02*
Y3443372D01*
G01X2382990D02*
X2386710D01*
G01X2394150Y3455872D02*
Y3443372D01*
X2400350D01*
G01X2406395Y3445038D02*
X2407635Y3443997D01*
X2409030Y3443372D01*
X2410270D01*
X2411510Y3443997D01*
X2412440Y3445038D01*
X2412905Y3446497D01*
X2412595Y3447955D01*
X2411820Y3449205D01*
X2410425Y3450039D01*
X2408565Y3450455D01*
X2407480Y3451289D01*
X2407015Y3452747D01*
X2407325Y3454205D01*
X2408100Y3455247D01*
X2409185Y3455872D01*
X2410270D01*
X2411355Y3455455D01*
X2412285Y3454414D01*
G01X2157225Y3733112D02*
X2161100Y3745612D01*
X2164975Y3733112D01*
G01X2163580Y3737487D02*
X2158620D01*
G01X2170400Y3745612D02*
Y3733112D01*
X2176600D01*
G01X2182800Y3745612D02*
Y3733112D01*
X2189000D01*
G01X2207290Y3745612D02*
Y3736654D01*
X2207910Y3734778D01*
X2209150Y3733529D01*
X2210700Y3733112D01*
X2212250Y3733529D01*
X2213490Y3734778D01*
X2214110Y3736654D01*
Y3745612D01*
G01X2219535Y3733112D02*
Y3745612D01*
X2226665Y3733112D01*
Y3745612D01*
G01X2233640D02*
X2237360D01*
G01X2235500D02*
Y3733112D01*
G01X2233640D02*
X2237360D01*
G01X2247900Y3745612D02*
Y3733112D01*
G01X2244335Y3745612D02*
X2251465D01*
G01X2257045Y3734778D02*
X2258285Y3733737D01*
X2259680Y3733112D01*
X2260920D01*
X2262160Y3733737D01*
X2263090Y3734778D01*
X2263555Y3736237D01*
X2263245Y3737695D01*
X2262470Y3738945D01*
X2261075Y3739779D01*
X2259215Y3740195D01*
X2258130Y3741029D01*
X2257665Y3742487D01*
X2257975Y3743945D01*
X2258750Y3744987D01*
X2259835Y3745612D01*
X2260920D01*
X2262005Y3745195D01*
X2262935Y3744154D01*
G01X2281225Y3733112D02*
X2285100Y3745612D01*
X2288975Y3733112D01*
G01X2287580Y3737487D02*
X2282620D01*
G01X2294400Y3733112D02*
Y3745612D01*
X2298275D01*
X2299515Y3744987D01*
X2300290Y3744154D01*
X2300600Y3742487D01*
X2300290Y3740820D01*
X2299360Y3739779D01*
X2298275Y3739154D01*
X2294400D01*
G01X2298275D02*
X2300600Y3733112D01*
G01X2313000D02*
X2306800D01*
Y3745612D01*
X2313000D01*
G01X2310520Y3739570D02*
X2306800D01*
G01X2332840Y3745612D02*
X2336560D01*
G01X2334700D02*
Y3733112D01*
G01X2332840D02*
X2336560D01*
G01X2343535D02*
Y3745612D01*
X2350665Y3733112D01*
Y3745612D01*
G01X2367870Y3733112D02*
Y3745612D01*
X2371900Y3735195D01*
X2375930Y3745612D01*
Y3733112D01*
G01X2382440Y3745612D02*
X2386160D01*
G01X2384300D02*
Y3733112D01*
G01X2382440D02*
X2386160D01*
G01X2393600Y3745612D02*
Y3733112D01*
X2399800D01*
G01X2405845Y3734778D02*
X2407085Y3733737D01*
X2408480Y3733112D01*
X2409720D01*
X2410960Y3733737D01*
X2411890Y3734778D01*
X2412355Y3736237D01*
X2412045Y3737695D01*
X2411270Y3738945D01*
X2409875Y3739779D01*
X2408015Y3740195D01*
X2406930Y3741029D01*
X2406465Y3742487D01*
X2406775Y3743945D01*
X2407550Y3744987D01*
X2408635Y3745612D01*
X2409720D01*
X2410805Y3745195D01*
X2411735Y3744154D01*
G01X2171305Y2693662D02*
X2175180Y2706162D01*
X2179055Y2693662D01*
G01X2177660Y2698037D02*
X2172700D01*
G01X2184480Y2706162D02*
Y2693662D01*
X2190680D01*
G01X2196880Y2706162D02*
Y2693662D01*
X2203080D01*
G01X2221370Y2706162D02*
Y2697204D01*
X2221990Y2695328D01*
X2223230Y2694079D01*
X2224780Y2693662D01*
X2226330Y2694079D01*
X2227570Y2695328D01*
X2228190Y2697204D01*
Y2706162D01*
G01X2233615Y2693662D02*
Y2706162D01*
X2240745Y2693662D01*
Y2706162D01*
G01X2247720D02*
X2251440D01*
G01X2249580D02*
Y2693662D01*
G01X2247720D02*
X2251440D01*
G01X2261980Y2706162D02*
Y2693662D01*
G01X2258415Y2706162D02*
X2265545D01*
G01X2271125Y2695328D02*
X2272365Y2694287D01*
X2273760Y2693662D01*
X2275000D01*
X2276240Y2694287D01*
X2277170Y2695328D01*
X2277635Y2696787D01*
X2277325Y2698245D01*
X2276550Y2699495D01*
X2275155Y2700329D01*
X2273295Y2700745D01*
X2272210Y2701579D01*
X2271745Y2703037D01*
X2272055Y2704495D01*
X2272830Y2705537D01*
X2273915Y2706162D01*
X2275000D01*
X2276085Y2705745D01*
X2277015Y2704704D01*
G01X2295305Y2693662D02*
X2299180Y2706162D01*
X2303055Y2693662D01*
G01X2301660Y2698037D02*
X2296700D01*
G01X2308480Y2693662D02*
Y2706162D01*
X2312355D01*
X2313595Y2705537D01*
X2314370Y2704704D01*
X2314680Y2703037D01*
X2314370Y2701370D01*
X2313440Y2700329D01*
X2312355Y2699704D01*
X2308480D01*
G01X2312355D02*
X2314680Y2693662D01*
G01X2327080D02*
X2320880D01*
Y2706162D01*
X2327080D01*
G01X2324600Y2700120D02*
X2320880D01*
G01X2346920Y2706162D02*
X2350640D01*
G01X2348780D02*
Y2693662D01*
G01X2346920D02*
X2350640D01*
G01X2357615D02*
Y2706162D01*
X2364745Y2693662D01*
Y2706162D01*
G01X2381950Y2693662D02*
Y2706162D01*
X2385980Y2695745D01*
X2390010Y2706162D01*
Y2693662D01*
G01X2396520Y2706162D02*
X2400240D01*
G01X2398380D02*
Y2693662D01*
G01X2396520D02*
X2400240D01*
G01X2407680Y2706162D02*
Y2693662D01*
X2413880D01*
G01X2419925Y2695328D02*
X2421165Y2694287D01*
X2422560Y2693662D01*
X2423800D01*
X2425040Y2694287D01*
X2425970Y2695328D01*
X2426435Y2696787D01*
X2426125Y2698245D01*
X2425350Y2699495D01*
X2423955Y2700329D01*
X2422095Y2700745D01*
X2421010Y2701579D01*
X2420545Y2703037D01*
X2420855Y2704495D01*
X2421630Y2705537D01*
X2422715Y2706162D01*
X2423800D01*
X2424885Y2705745D01*
X2425815Y2704704D01*
G01X2170220Y2725329D02*
X2170840Y2725954D01*
X2171305Y2726995D01*
X2171615Y2728454D01*
X2171305Y2729704D01*
X2170685Y2730537D01*
X2169600Y2731162D01*
X2165415D01*
Y2718662D01*
X2170530D01*
X2171615Y2719495D01*
X2172235Y2720745D01*
X2172545Y2722204D01*
X2172235Y2723662D01*
X2171305Y2724912D01*
X2170220Y2725329D01*
X2165415D01*
G01X2177505Y2718662D02*
X2181380Y2731162D01*
X2185255Y2718662D01*
G01X2183860Y2723037D02*
X2178900D01*
G01X2197190Y2730120D02*
X2196260Y2730745D01*
X2195175Y2731162D01*
X2193935D01*
X2192540Y2730537D01*
X2191455Y2729495D01*
X2190680Y2728245D01*
X2190060Y2726162D01*
X2189905Y2724287D01*
X2190215Y2722412D01*
X2190680Y2721162D01*
X2191610Y2719912D01*
X2192695Y2719079D01*
X2193780Y2718662D01*
X2194865D01*
X2195950Y2719079D01*
X2196880Y2719703D01*
X2197655Y2720537D01*
G01X2202770Y2718662D02*
Y2731162D01*
G01X2208660D02*
X2202770Y2723453D01*
G01X2209590Y2718662D02*
X2205405Y2726995D01*
G01X2215170Y2718662D02*
Y2731162D01*
X2218270D01*
X2219510Y2730537D01*
X2220440Y2729704D01*
X2221215Y2728454D01*
X2221835Y2726995D01*
X2221990Y2724912D01*
X2221835Y2722829D01*
X2221215Y2721370D01*
X2220440Y2720120D01*
X2219510Y2719287D01*
X2218270Y2718662D01*
X2215170D01*
G01X2227880D02*
Y2731162D01*
X2231755D01*
X2232995Y2730537D01*
X2233770Y2729704D01*
X2234080Y2728037D01*
X2233770Y2726370D01*
X2232840Y2725329D01*
X2231755Y2724704D01*
X2227880D01*
G01X2231755D02*
X2234080Y2718662D01*
G01X2241520Y2731162D02*
X2245240D01*
G01X2243380D02*
Y2718662D01*
G01X2241520D02*
X2245240D01*
G01X2252680Y2731162D02*
Y2718662D01*
X2258880D01*
G01X2265080Y2731162D02*
Y2718662D01*
X2271280D01*
G01X2280580Y2718245D02*
X2280270Y2718454D01*
Y2718870D01*
X2280580Y2719079D01*
X2280890Y2718870D01*
Y2718454D01*
X2280580Y2718245D01*
G01Y2723870D02*
X2280270Y2724079D01*
Y2724495D01*
X2280580Y2724704D01*
X2280890Y2724495D01*
Y2724079D01*
X2280580Y2723870D01*
G01X2305380Y2731162D02*
Y2718662D01*
G01X2301815Y2731162D02*
X2308945D01*
G01X2317780Y2718662D02*
X2316540Y2718870D01*
X2315455Y2719703D01*
X2314525Y2720954D01*
X2313905Y2722412D01*
X2313595Y2724079D01*
Y2725745D01*
X2313905Y2727412D01*
X2314525Y2728870D01*
X2315455Y2730120D01*
X2316540Y2730954D01*
X2317780Y2731162D01*
X2319020Y2730954D01*
X2320105Y2730120D01*
X2321035Y2728870D01*
X2321655Y2727412D01*
X2321965Y2725745D01*
Y2724079D01*
X2321655Y2722412D01*
X2321035Y2720954D01*
X2320105Y2719703D01*
X2319020Y2718870D01*
X2317780Y2718662D01*
G01X2327080D02*
Y2731162D01*
X2330800D01*
X2332040Y2730537D01*
X2332970Y2729079D01*
X2333280Y2727412D01*
X2332970Y2725745D01*
X2332195Y2724495D01*
X2330800Y2723870D01*
X2327080D01*
G01X2354980Y2731162D02*
Y2718662D01*
G01X2352810Y2726995D02*
X2357150D01*
G01X2367380Y2718662D02*
X2366450Y2718870D01*
X2365520Y2719703D01*
X2364900Y2721162D01*
X2364590Y2722829D01*
X2364900Y2724495D01*
X2365520Y2725954D01*
X2366450Y2726787D01*
X2367380Y2726995D01*
X2368310Y2726787D01*
X2369240Y2725954D01*
X2369860Y2724495D01*
X2370015Y2722829D01*
X2369860Y2721162D01*
X2369240Y2719703D01*
X2368310Y2718870D01*
X2367380Y2718662D01*
G01X2393110Y2724912D02*
X2396210D01*
Y2721162D01*
X2395280Y2719912D01*
X2394195Y2719079D01*
X2392645Y2718662D01*
X2391095Y2719079D01*
X2390010Y2719912D01*
X2389080Y2721162D01*
X2388460Y2722620D01*
X2388150Y2724287D01*
Y2725745D01*
X2388460Y2726995D01*
X2389080Y2728454D01*
X2390010Y2729704D01*
X2390940Y2730537D01*
X2392180Y2731162D01*
X2393265D01*
X2394505Y2730745D01*
X2395435Y2729912D01*
G01X2401015Y2718662D02*
Y2731162D01*
X2408145Y2718662D01*
Y2731162D01*
G01X2413570Y2718662D02*
Y2731162D01*
X2416670D01*
X2417910Y2730537D01*
X2418840Y2729704D01*
X2419615Y2728454D01*
X2420235Y2726995D01*
X2420390Y2724912D01*
X2420235Y2722829D01*
X2419615Y2721370D01*
X2418840Y2720120D01*
X2417910Y2719287D01*
X2416670Y2718662D01*
X2413570D01*
G01X2431240D02*
Y2731162D01*
X2425505Y2722204D01*
X2433255D01*
G01X2175353Y2909540D02*
Y2922040D01*
X2179383Y2911623D01*
X2183413Y2922040D01*
Y2909540D01*
G01X2188218D02*
Y2922040D01*
X2195348Y2909540D01*
Y2922040D01*
G01X2207593Y2920998D02*
X2206663Y2921623D01*
X2205578Y2922040D01*
X2204338D01*
X2202943Y2921415D01*
X2201858Y2920373D01*
X2201083Y2919123D01*
X2200463Y2917040D01*
X2200308Y2915165D01*
X2200618Y2913290D01*
X2201083Y2912040D01*
X2202013Y2910790D01*
X2203098Y2909957D01*
X2204183Y2909540D01*
X2205268D01*
X2206353Y2909957D01*
X2207283Y2910581D01*
X2208058Y2911415D01*
G01X2211933Y2905373D02*
X2221233D01*
G01X2225883Y2922040D02*
Y2909540D01*
X2232083D01*
G01X2237508D02*
X2241383Y2922040D01*
X2245258Y2909540D01*
G01X2243863Y2913915D02*
X2238903D01*
G01X2253783Y2909540D02*
Y2915165D01*
X2250683Y2922040D01*
G01X2256883D02*
X2253783Y2915165D01*
G01X2269283Y2909540D02*
X2263083D01*
Y2922040D01*
X2269283D01*
G01X2266803Y2915998D02*
X2263083D01*
G01X2275483Y2909540D02*
Y2922040D01*
X2279358D01*
X2280598Y2921415D01*
X2281373Y2920582D01*
X2281683Y2918915D01*
X2281373Y2917248D01*
X2280443Y2916207D01*
X2279358Y2915582D01*
X2275483D01*
G01X2279358D02*
X2281683Y2909540D01*
G01X2176600Y3125922D02*
Y3138422D01*
X2180630Y3128005D01*
X2184660Y3138422D01*
Y3125922D01*
G01X2189465D02*
Y3138422D01*
X2196595Y3125922D01*
Y3138422D01*
G01X2208840Y3137380D02*
X2207910Y3138005D01*
X2206825Y3138422D01*
X2205585D01*
X2204190Y3137797D01*
X2203105Y3136755D01*
X2202330Y3135505D01*
X2201710Y3133422D01*
X2201555Y3131547D01*
X2201865Y3129672D01*
X2202330Y3128422D01*
X2203260Y3127172D01*
X2204345Y3126339D01*
X2205430Y3125922D01*
X2206515D01*
X2207600Y3126339D01*
X2208530Y3126963D01*
X2209305Y3127797D01*
G01X2213180Y3121755D02*
X2222480D01*
G01X2227130Y3138422D02*
Y3125922D01*
X2233330D01*
G01X2238755D02*
X2242630Y3138422D01*
X2246505Y3125922D01*
G01X2245110Y3130297D02*
X2240150D01*
G01X2255030Y3125922D02*
Y3131547D01*
X2251930Y3138422D01*
G01X2258130D02*
X2255030Y3131547D01*
G01X2270530Y3125922D02*
X2264330D01*
Y3138422D01*
X2270530D01*
G01X2268050Y3132380D02*
X2264330D01*
G01X2276730Y3125922D02*
Y3138422D01*
X2280605D01*
X2281845Y3137797D01*
X2282620Y3136964D01*
X2282930Y3135297D01*
X2282620Y3133630D01*
X2281690Y3132589D01*
X2280605Y3131964D01*
X2276730D01*
G01X2280605D02*
X2282930Y3125922D01*
G01X2174670Y3418372D02*
Y3430872D01*
X2178700Y3420455D01*
X2182730Y3430872D01*
Y3418372D01*
G01X2187535D02*
Y3430872D01*
X2194665Y3418372D01*
Y3430872D01*
G01X2206910Y3429830D02*
X2205980Y3430455D01*
X2204895Y3430872D01*
X2203655D01*
X2202260Y3430247D01*
X2201175Y3429205D01*
X2200400Y3427955D01*
X2199780Y3425872D01*
X2199625Y3423997D01*
X2199935Y3422122D01*
X2200400Y3420872D01*
X2201330Y3419622D01*
X2202415Y3418789D01*
X2203500Y3418372D01*
X2204585D01*
X2205670Y3418789D01*
X2206600Y3419413D01*
X2207375Y3420247D01*
G01X2211250Y3414205D02*
X2220550D01*
G01X2225200Y3430872D02*
Y3418372D01*
X2231400D01*
G01X2236825D02*
X2240700Y3430872D01*
X2244575Y3418372D01*
G01X2243180Y3422747D02*
X2238220D01*
G01X2253100Y3418372D02*
Y3423997D01*
X2250000Y3430872D01*
G01X2256200D02*
X2253100Y3423997D01*
G01X2268600Y3418372D02*
X2262400D01*
Y3430872D01*
X2268600D01*
G01X2266120Y3424830D02*
X2262400D01*
G01X2274800Y3418372D02*
Y3430872D01*
X2278675D01*
X2279915Y3430247D01*
X2280690Y3429414D01*
X2281000Y3427747D01*
X2280690Y3426080D01*
X2279760Y3425039D01*
X2278675Y3424414D01*
X2274800D01*
G01X2278675D02*
X2281000Y3418372D01*
G01X2174120Y3708112D02*
Y3720612D01*
X2178150Y3710195D01*
X2182180Y3720612D01*
Y3708112D01*
G01X2186985D02*
Y3720612D01*
X2194115Y3708112D01*
Y3720612D01*
G01X2206360Y3719570D02*
X2205430Y3720195D01*
X2204345Y3720612D01*
X2203105D01*
X2201710Y3719987D01*
X2200625Y3718945D01*
X2199850Y3717695D01*
X2199230Y3715612D01*
X2199075Y3713737D01*
X2199385Y3711862D01*
X2199850Y3710612D01*
X2200780Y3709362D01*
X2201865Y3708529D01*
X2202950Y3708112D01*
X2204035D01*
X2205120Y3708529D01*
X2206050Y3709153D01*
X2206825Y3709987D01*
G01X2210700Y3703945D02*
X2220000D01*
G01X2224650Y3720612D02*
Y3708112D01*
X2230850D01*
G01X2236275D02*
X2240150Y3720612D01*
X2244025Y3708112D01*
G01X2242630Y3712487D02*
X2237670D01*
G01X2252550Y3708112D02*
Y3713737D01*
X2249450Y3720612D01*
G01X2255650D02*
X2252550Y3713737D01*
G01X2268050Y3708112D02*
X2261850D01*
Y3720612D01*
X2268050D01*
G01X2265570Y3714570D02*
X2261850D01*
G01X2274250Y3708112D02*
Y3720612D01*
X2278125D01*
X2279365Y3719987D01*
X2280140Y3719154D01*
X2280450Y3717487D01*
X2280140Y3715820D01*
X2279210Y3714779D01*
X2278125Y3714154D01*
X2274250D01*
G01X2278125D02*
X2280450Y3708112D01*
G01X2188200Y2668662D02*
Y2681162D01*
X2192230Y2670745D01*
X2196260Y2681162D01*
Y2668662D01*
G01X2201065D02*
Y2681162D01*
X2208195Y2668662D01*
Y2681162D01*
G01X2220440Y2680120D02*
X2219510Y2680745D01*
X2218425Y2681162D01*
X2217185D01*
X2215790Y2680537D01*
X2214705Y2679495D01*
X2213930Y2678245D01*
X2213310Y2676162D01*
X2213155Y2674287D01*
X2213465Y2672412D01*
X2213930Y2671162D01*
X2214860Y2669912D01*
X2215945Y2669079D01*
X2217030Y2668662D01*
X2218115D01*
X2219200Y2669079D01*
X2220130Y2669703D01*
X2220905Y2670537D01*
G01X2224780Y2664495D02*
X2234080D01*
G01X2238730Y2681162D02*
Y2668662D01*
X2244930D01*
G01X2250355D02*
X2254230Y2681162D01*
X2258105Y2668662D01*
G01X2256710Y2673037D02*
X2251750D01*
G01X2266630Y2668662D02*
Y2674287D01*
X2263530Y2681162D01*
G01X2269730D02*
X2266630Y2674287D01*
G01X2282130Y2668662D02*
X2275930D01*
Y2681162D01*
X2282130D01*
G01X2279650Y2675120D02*
X2275930D01*
G01X2288330Y2668662D02*
Y2681162D01*
X2292205D01*
X2293445Y2680537D01*
X2294220Y2679704D01*
X2294530Y2678037D01*
X2294220Y2676370D01*
X2293290Y2675329D01*
X2292205Y2674704D01*
X2288330D01*
G01X2292205D02*
X2294530Y2668662D01*
G01X2211313Y2890790D02*
X2214413D01*
Y2887040D01*
X2213483Y2885790D01*
X2212398Y2884957D01*
X2210848Y2884540D01*
X2209298Y2884957D01*
X2208213Y2885790D01*
X2207283Y2887040D01*
X2206663Y2888498D01*
X2206353Y2890165D01*
Y2891623D01*
X2206663Y2892873D01*
X2207283Y2894332D01*
X2208213Y2895582D01*
X2209143Y2896415D01*
X2210383Y2897040D01*
X2211468D01*
X2212708Y2896623D01*
X2213638Y2895790D01*
G01X2219218Y2884540D02*
Y2897040D01*
X2226348Y2884540D01*
Y2897040D01*
G01X2231773Y2884540D02*
Y2897040D01*
X2234873D01*
X2236113Y2896415D01*
X2237043Y2895582D01*
X2237818Y2894332D01*
X2238438Y2892873D01*
X2238593Y2890790D01*
X2238438Y2888707D01*
X2237818Y2887248D01*
X2237043Y2885998D01*
X2236113Y2885165D01*
X2234873Y2884540D01*
X2231773D01*
G01X2244173Y2887040D02*
X2245103Y2885581D01*
X2246343Y2884748D01*
X2247738Y2884540D01*
X2248978Y2884748D01*
X2250218Y2885790D01*
X2250993Y2887040D01*
X2251148Y2888290D01*
X2250838Y2889748D01*
X2249753Y2890790D01*
X2248668Y2891207D01*
X2247273D01*
G01X2248668D02*
X2249598Y2891832D01*
X2250373Y2892873D01*
X2250683Y2894123D01*
X2250373Y2895373D01*
X2249598Y2896415D01*
X2248203Y2897040D01*
X2246808Y2896832D01*
X2245413Y2895998D01*
G01X2227570Y2656162D02*
X2231290D01*
G01X2229430D02*
Y2643662D01*
G01X2227570D02*
X2231290D01*
G01X2238265D02*
Y2656162D01*
X2245395Y2643662D01*
Y2656162D01*
G01X2256090Y2643662D02*
Y2656162D01*
X2250355Y2647204D01*
X2258105D01*
G01X2215970Y3113422D02*
X2219690D01*
G01X2217830D02*
Y3100922D01*
G01X2215970D02*
X2219690D01*
G01X2226665D02*
Y3113422D01*
X2233795Y3100922D01*
Y3113422D01*
G01X2239220Y3103422D02*
X2240150Y3101963D01*
X2241390Y3101130D01*
X2242785Y3100922D01*
X2244025Y3101130D01*
X2245265Y3102172D01*
X2246040Y3103422D01*
X2246195Y3104672D01*
X2245885Y3106130D01*
X2244800Y3107172D01*
X2243715Y3107589D01*
X2242320D01*
G01X2243715D02*
X2244645Y3108214D01*
X2245420Y3109255D01*
X2245730Y3110505D01*
X2245420Y3111755D01*
X2244645Y3112797D01*
X2243250Y3113422D01*
X2241855Y3113214D01*
X2240460Y3112380D01*
G01X2214040Y3355872D02*
X2217760D01*
G01X2215900D02*
Y3343372D01*
G01X2214040D02*
X2217760D01*
G01X2224735D02*
Y3355872D01*
X2231865Y3343372D01*
Y3355872D01*
G01X2237755Y3348580D02*
X2238840Y3350039D01*
X2239770Y3350872D01*
X2241010Y3351289D01*
X2242095Y3350872D01*
X2242870Y3350039D01*
X2243490Y3348789D01*
X2243645Y3347330D01*
X2243490Y3346080D01*
X2242870Y3344830D01*
X2241940Y3343789D01*
X2240855Y3343372D01*
X2239615Y3343789D01*
X2238530Y3345038D01*
X2237910Y3346914D01*
X2237755Y3348997D01*
X2238065Y3351705D01*
X2238530Y3353164D01*
X2239305Y3354622D01*
X2240390Y3355664D01*
X2241475Y3355872D01*
X2242560Y3355455D01*
X2243335Y3354414D01*
G01X2214040Y3380872D02*
X2217760D01*
G01X2215900D02*
Y3368372D01*
G01X2214040D02*
X2217760D01*
G01X2224735D02*
Y3380872D01*
X2231865Y3368372D01*
Y3380872D01*
G01X2237755Y3373580D02*
X2238840Y3375039D01*
X2239770Y3375872D01*
X2241010Y3376289D01*
X2242095Y3375872D01*
X2242870Y3375039D01*
X2243490Y3373789D01*
X2243645Y3372330D01*
X2243490Y3371080D01*
X2242870Y3369830D01*
X2241940Y3368789D01*
X2240855Y3368372D01*
X2239615Y3368789D01*
X2238530Y3370038D01*
X2237910Y3371914D01*
X2237755Y3373997D01*
X2238065Y3376705D01*
X2238530Y3378164D01*
X2239305Y3379622D01*
X2240390Y3380664D01*
X2241475Y3380872D01*
X2242560Y3380455D01*
X2243335Y3379414D01*
G01X2214040Y3405872D02*
X2217760D01*
G01X2215900D02*
Y3393372D01*
G01X2214040D02*
X2217760D01*
G01X2224735D02*
Y3405872D01*
X2231865Y3393372D01*
Y3405872D01*
G01X2237755Y3398580D02*
X2238840Y3400039D01*
X2239770Y3400872D01*
X2241010Y3401289D01*
X2242095Y3400872D01*
X2242870Y3400039D01*
X2243490Y3398789D01*
X2243645Y3397330D01*
X2243490Y3396080D01*
X2242870Y3394830D01*
X2241940Y3393789D01*
X2240855Y3393372D01*
X2239615Y3393789D01*
X2238530Y3395038D01*
X2237910Y3396914D01*
X2237755Y3398997D01*
X2238065Y3401705D01*
X2238530Y3403164D01*
X2239305Y3404622D01*
X2240390Y3405664D01*
X2241475Y3405872D01*
X2242560Y3405455D01*
X2243335Y3404414D01*
G01X2213490Y3645612D02*
X2217210D01*
G01X2215350D02*
Y3633112D01*
G01X2213490D02*
X2217210D01*
G01X2224185D02*
Y3645612D01*
X2231315Y3633112D01*
Y3645612D01*
G01X2236740Y3634987D02*
X2237670Y3633945D01*
X2238755Y3633320D01*
X2240150Y3633112D01*
X2241545Y3633529D01*
X2242630Y3634362D01*
X2243405Y3635820D01*
X2243560Y3637487D01*
X2243250Y3639154D01*
X2242475Y3640195D01*
X2241390Y3641029D01*
X2240305Y3641237D01*
X2239220Y3641029D01*
X2237825Y3640195D01*
X2238290Y3645612D01*
X2242475D01*
G01X2213490Y3670612D02*
X2217210D01*
G01X2215350D02*
Y3658112D01*
G01X2213490D02*
X2217210D01*
G01X2224185D02*
Y3670612D01*
X2231315Y3658112D01*
Y3670612D01*
G01X2236740Y3659987D02*
X2237670Y3658945D01*
X2238755Y3658320D01*
X2240150Y3658112D01*
X2241545Y3658529D01*
X2242630Y3659362D01*
X2243405Y3660820D01*
X2243560Y3662487D01*
X2243250Y3664154D01*
X2242475Y3665195D01*
X2241390Y3666029D01*
X2240305Y3666237D01*
X2239220Y3666029D01*
X2237825Y3665195D01*
X2238290Y3670612D01*
X2242475D01*
G01X2213490Y3695612D02*
X2217210D01*
G01X2215350D02*
Y3683112D01*
G01X2213490D02*
X2217210D01*
G01X2224185D02*
Y3695612D01*
X2231315Y3683112D01*
Y3695612D01*
G01X2236740Y3684987D02*
X2237670Y3683945D01*
X2238755Y3683320D01*
X2240150Y3683112D01*
X2241545Y3683529D01*
X2242630Y3684362D01*
X2243405Y3685820D01*
X2243560Y3687487D01*
X2243250Y3689154D01*
X2242475Y3690195D01*
X2241390Y3691029D01*
X2240305Y3691237D01*
X2239220Y3691029D01*
X2237825Y3690195D01*
X2238290Y3695612D01*
X2242475D01*
G01X2339653Y2909540D02*
Y2922040D01*
X2343683Y2911623D01*
X2347713Y2922040D01*
Y2909540D01*
G01X2352208D02*
X2356083Y2922040D01*
X2359958Y2909540D01*
G01X2358563Y2913915D02*
X2353603D01*
G01X2365228Y2909540D02*
X2371738Y2922040D01*
G01X2365228D02*
X2371738Y2909540D01*
G01X2376233Y2905373D02*
X2385533D01*
G01X2389873Y2909540D02*
Y2922040D01*
X2392973D01*
X2394213Y2921415D01*
X2395143Y2920582D01*
X2395918Y2919332D01*
X2396538Y2917873D01*
X2396693Y2915790D01*
X2396538Y2913707D01*
X2395918Y2912248D01*
X2395143Y2910998D01*
X2394213Y2910165D01*
X2392973Y2909540D01*
X2389873D01*
G01X2408783D02*
X2402583D01*
Y2922040D01*
X2408783D01*
G01X2406303Y2915998D02*
X2402583D01*
G01X2414983Y2909540D02*
Y2922040D01*
X2418703D01*
X2419943Y2921415D01*
X2420873Y2919957D01*
X2421183Y2918290D01*
X2420873Y2916623D01*
X2420098Y2915373D01*
X2418703Y2914748D01*
X2414983D01*
G01X2430483Y2922040D02*
Y2909540D01*
G01X2426918Y2922040D02*
X2434048D01*
G01X2439628Y2909540D02*
Y2922040D01*
G01X2446138D02*
Y2909540D01*
G01Y2915790D02*
X2439628D01*
G01X2338970Y3418372D02*
Y3430872D01*
X2343000Y3420455D01*
X2347030Y3430872D01*
Y3418372D01*
G01X2351525D02*
X2355400Y3430872D01*
X2359275Y3418372D01*
G01X2357880Y3422747D02*
X2352920D01*
G01X2364545Y3418372D02*
X2371055Y3430872D01*
G01X2364545D02*
X2371055Y3418372D01*
G01X2375550Y3414205D02*
X2384850D01*
G01X2389190Y3418372D02*
Y3430872D01*
X2392290D01*
X2393530Y3430247D01*
X2394460Y3429414D01*
X2395235Y3428164D01*
X2395855Y3426705D01*
X2396010Y3424622D01*
X2395855Y3422539D01*
X2395235Y3421080D01*
X2394460Y3419830D01*
X2393530Y3418997D01*
X2392290Y3418372D01*
X2389190D01*
G01X2408100D02*
X2401900D01*
Y3430872D01*
X2408100D01*
G01X2405620Y3424830D02*
X2401900D01*
G01X2414300Y3418372D02*
Y3430872D01*
X2418020D01*
X2419260Y3430247D01*
X2420190Y3428789D01*
X2420500Y3427122D01*
X2420190Y3425455D01*
X2419415Y3424205D01*
X2418020Y3423580D01*
X2414300D01*
G01X2429800Y3430872D02*
Y3418372D01*
G01X2426235Y3430872D02*
X2433365D01*
G01X2438945Y3418372D02*
Y3430872D01*
G01X2445455D02*
Y3418372D01*
G01Y3424622D02*
X2438945D01*
G01X2338420Y3708112D02*
Y3720612D01*
X2342450Y3710195D01*
X2346480Y3720612D01*
Y3708112D01*
G01X2350975D02*
X2354850Y3720612D01*
X2358725Y3708112D01*
G01X2357330Y3712487D02*
X2352370D01*
G01X2363995Y3708112D02*
X2370505Y3720612D01*
G01X2363995D02*
X2370505Y3708112D01*
G01X2375000Y3703945D02*
X2384300D01*
G01X2388640Y3708112D02*
Y3720612D01*
X2391740D01*
X2392980Y3719987D01*
X2393910Y3719154D01*
X2394685Y3717904D01*
X2395305Y3716445D01*
X2395460Y3714362D01*
X2395305Y3712279D01*
X2394685Y3710820D01*
X2393910Y3709570D01*
X2392980Y3708737D01*
X2391740Y3708112D01*
X2388640D01*
G01X2407550D02*
X2401350D01*
Y3720612D01*
X2407550D01*
G01X2405070Y3714570D02*
X2401350D01*
G01X2413750Y3708112D02*
Y3720612D01*
X2417470D01*
X2418710Y3719987D01*
X2419640Y3718529D01*
X2419950Y3716862D01*
X2419640Y3715195D01*
X2418865Y3713945D01*
X2417470Y3713320D01*
X2413750D01*
G01X2429250Y3720612D02*
Y3708112D01*
G01X2425685Y3720612D02*
X2432815D01*
G01X2438395Y3708112D02*
Y3720612D01*
G01X2444905D02*
Y3708112D01*
G01Y3714362D02*
X2438395D01*
G01X2352500Y2668662D02*
Y2681162D01*
X2356530Y2670745D01*
X2360560Y2681162D01*
Y2668662D01*
G01X2365055D02*
X2368930Y2681162D01*
X2372805Y2668662D01*
G01X2371410Y2673037D02*
X2366450D01*
G01X2378075Y2668662D02*
X2384585Y2681162D01*
G01X2378075D02*
X2384585Y2668662D01*
G01X2389080Y2664495D02*
X2398380D01*
G01X2402720Y2668662D02*
Y2681162D01*
X2405820D01*
X2407060Y2680537D01*
X2407990Y2679704D01*
X2408765Y2678454D01*
X2409385Y2676995D01*
X2409540Y2674912D01*
X2409385Y2672829D01*
X2408765Y2671370D01*
X2407990Y2670120D01*
X2407060Y2669287D01*
X2405820Y2668662D01*
X2402720D01*
G01X2421630D02*
X2415430D01*
Y2681162D01*
X2421630D01*
G01X2419150Y2675120D02*
X2415430D01*
G01X2427830Y2668662D02*
Y2681162D01*
X2431550D01*
X2432790Y2680537D01*
X2433720Y2679079D01*
X2434030Y2677412D01*
X2433720Y2675745D01*
X2432945Y2674495D01*
X2431550Y2673870D01*
X2427830D01*
G01X2443330Y2681162D02*
Y2668662D01*
G01X2439765Y2681162D02*
X2446895D01*
G01X2452475Y2668662D02*
Y2681162D01*
G01X2458985D02*
Y2668662D01*
G01Y2674912D02*
X2452475D01*
G01X2340900Y3125922D02*
Y3138422D01*
X2344930Y3128005D01*
X2348960Y3138422D01*
Y3125922D01*
G01X2353455D02*
X2357330Y3138422D01*
X2361205Y3125922D01*
G01X2359810Y3130297D02*
X2354850D01*
G01X2366475Y3125922D02*
X2372985Y3138422D01*
G01X2366475D02*
X2372985Y3125922D01*
G01X2377480Y3121755D02*
X2386780D01*
G01X2391120Y3125922D02*
Y3138422D01*
X2394220D01*
X2395460Y3137797D01*
X2396390Y3136964D01*
X2397165Y3135714D01*
X2397785Y3134255D01*
X2397940Y3132172D01*
X2397785Y3130089D01*
X2397165Y3128630D01*
X2396390Y3127380D01*
X2395460Y3126547D01*
X2394220Y3125922D01*
X2391120D01*
G01X2410030D02*
X2403830D01*
Y3138422D01*
X2410030D01*
G01X2407550Y3132380D02*
X2403830D01*
G01X2416230Y3125922D02*
Y3138422D01*
X2419950D01*
X2421190Y3137797D01*
X2422120Y3136339D01*
X2422430Y3134672D01*
X2422120Y3133005D01*
X2421345Y3131755D01*
X2419950Y3131130D01*
X2416230D01*
G01X2431730Y3138422D02*
Y3125922D01*
G01X2428165Y3138422D02*
X2435295D01*
G01X2440875Y3125922D02*
Y3138422D01*
G01X2447385D02*
Y3125922D01*
G01Y3132172D02*
X2440875D01*
G01X2371273Y2886415D02*
X2372203Y2885373D01*
X2373288Y2884748D01*
X2374683Y2884540D01*
X2376078Y2884957D01*
X2377163Y2885790D01*
X2377938Y2887248D01*
X2378093Y2888915D01*
X2377783Y2890582D01*
X2377008Y2891623D01*
X2375923Y2892457D01*
X2374838Y2892665D01*
X2373753Y2892457D01*
X2372358Y2891623D01*
X2372823Y2897040D01*
X2377008D01*
G01X2383673Y2886415D02*
X2384603Y2885373D01*
X2385688Y2884748D01*
X2387083Y2884540D01*
X2388478Y2884957D01*
X2389563Y2885790D01*
X2390338Y2887248D01*
X2390493Y2888915D01*
X2390183Y2890582D01*
X2389408Y2891623D01*
X2388323Y2892457D01*
X2387238Y2892665D01*
X2386153Y2892457D01*
X2384758Y2891623D01*
X2385223Y2897040D01*
X2389408D01*
G01X2399483Y2884123D02*
X2399173Y2884332D01*
Y2884748D01*
X2399483Y2884957D01*
X2399793Y2884748D01*
Y2884332D01*
X2399483Y2884123D01*
G01X2411883Y2897040D02*
X2410643Y2896623D01*
X2409713Y2895582D01*
X2409093Y2894332D01*
X2408628Y2892665D01*
X2408473Y2890790D01*
X2408628Y2888915D01*
X2409093Y2887248D01*
X2409713Y2885998D01*
X2410643Y2884957D01*
X2411883Y2884540D01*
X2413123Y2884957D01*
X2414053Y2885998D01*
X2414673Y2887248D01*
X2415138Y2888915D01*
X2415293Y2890790D01*
X2415138Y2892665D01*
X2414673Y2894332D01*
X2414053Y2895582D01*
X2413123Y2896623D01*
X2411883Y2897040D01*
G01X2372520Y3103422D02*
X2373450Y3101963D01*
X2374690Y3101130D01*
X2376085Y3100922D01*
X2377325Y3101130D01*
X2378565Y3102172D01*
X2379340Y3103422D01*
X2379495Y3104672D01*
X2379185Y3106130D01*
X2378100Y3107172D01*
X2377015Y3107589D01*
X2375620D01*
G01X2377015D02*
X2377945Y3108214D01*
X2378720Y3109255D01*
X2379030Y3110505D01*
X2378720Y3111755D01*
X2377945Y3112797D01*
X2376550Y3113422D01*
X2375155Y3113214D01*
X2373760Y3112380D01*
G01X2388330Y3100922D02*
Y3113422D01*
X2386470Y3110922D01*
G01Y3100922D02*
X2390190D01*
G01X2400730Y3100505D02*
X2400420Y3100714D01*
Y3101130D01*
X2400730Y3101339D01*
X2401040Y3101130D01*
Y3100714D01*
X2400730Y3100505D01*
G01X2410185Y3111339D02*
X2411115Y3112588D01*
X2412200Y3113214D01*
X2413440Y3113422D01*
X2414990Y3113005D01*
X2416075Y3111964D01*
X2416385Y3110714D01*
X2416230Y3109463D01*
X2415610Y3108422D01*
X2412510Y3106339D01*
X2411115Y3104880D01*
X2410185Y3102797D01*
X2409875Y3100922D01*
X2416385D01*
G01X2364305Y3643529D02*
X2365235Y3644778D01*
X2366320Y3645404D01*
X2367560Y3645612D01*
X2369110Y3645195D01*
X2370195Y3644154D01*
X2370505Y3642904D01*
X2370350Y3641653D01*
X2369730Y3640612D01*
X2366630Y3638529D01*
X2365235Y3637070D01*
X2364305Y3634987D01*
X2363995Y3633112D01*
X2370505D01*
G01X2379650Y3645612D02*
X2378410Y3645195D01*
X2377480Y3644154D01*
X2376860Y3642904D01*
X2376395Y3641237D01*
X2376240Y3639362D01*
X2376395Y3637487D01*
X2376860Y3635820D01*
X2377480Y3634570D01*
X2378410Y3633529D01*
X2379650Y3633112D01*
X2380890Y3633529D01*
X2381820Y3634570D01*
X2382440Y3635820D01*
X2382905Y3637487D01*
X2383060Y3639362D01*
X2382905Y3641237D01*
X2382440Y3642904D01*
X2381820Y3644154D01*
X2380890Y3645195D01*
X2379650Y3645612D01*
G01X2392050Y3632695D02*
X2391740Y3632904D01*
Y3633320D01*
X2392050Y3633529D01*
X2392360Y3633320D01*
Y3632904D01*
X2392050Y3632695D01*
G01X2401505Y3643529D02*
X2402435Y3644778D01*
X2403520Y3645404D01*
X2404760Y3645612D01*
X2406310Y3645195D01*
X2407395Y3644154D01*
X2407705Y3642904D01*
X2407550Y3641653D01*
X2406930Y3640612D01*
X2403830Y3638529D01*
X2402435Y3637070D01*
X2401505Y3634987D01*
X2401195Y3633112D01*
X2407705D01*
G01X2413440Y3634987D02*
X2414370Y3633945D01*
X2415455Y3633320D01*
X2416850Y3633112D01*
X2418245Y3633529D01*
X2419330Y3634362D01*
X2420105Y3635820D01*
X2420260Y3637487D01*
X2419950Y3639154D01*
X2419175Y3640195D01*
X2418090Y3641029D01*
X2417005Y3641237D01*
X2415920Y3641029D01*
X2414525Y3640195D01*
X2414990Y3645612D01*
X2419175D01*
G01X2364305Y3668529D02*
X2365235Y3669778D01*
X2366320Y3670404D01*
X2367560Y3670612D01*
X2369110Y3670195D01*
X2370195Y3669154D01*
X2370505Y3667904D01*
X2370350Y3666653D01*
X2369730Y3665612D01*
X2366630Y3663529D01*
X2365235Y3662070D01*
X2364305Y3659987D01*
X2363995Y3658112D01*
X2370505D01*
G01X2379650Y3670612D02*
X2378410Y3670195D01*
X2377480Y3669154D01*
X2376860Y3667904D01*
X2376395Y3666237D01*
X2376240Y3664362D01*
X2376395Y3662487D01*
X2376860Y3660820D01*
X2377480Y3659570D01*
X2378410Y3658529D01*
X2379650Y3658112D01*
X2380890Y3658529D01*
X2381820Y3659570D01*
X2382440Y3660820D01*
X2382905Y3662487D01*
X2383060Y3664362D01*
X2382905Y3666237D01*
X2382440Y3667904D01*
X2381820Y3669154D01*
X2380890Y3670195D01*
X2379650Y3670612D01*
G01X2392050Y3657695D02*
X2391740Y3657904D01*
Y3658320D01*
X2392050Y3658529D01*
X2392360Y3658320D01*
Y3657904D01*
X2392050Y3657695D01*
G01X2401505Y3668529D02*
X2402435Y3669778D01*
X2403520Y3670404D01*
X2404760Y3670612D01*
X2406310Y3670195D01*
X2407395Y3669154D01*
X2407705Y3667904D01*
X2407550Y3666653D01*
X2406930Y3665612D01*
X2403830Y3663529D01*
X2402435Y3662070D01*
X2401505Y3659987D01*
X2401195Y3658112D01*
X2407705D01*
G01X2413440Y3659987D02*
X2414370Y3658945D01*
X2415455Y3658320D01*
X2416850Y3658112D01*
X2418245Y3658529D01*
X2419330Y3659362D01*
X2420105Y3660820D01*
X2420260Y3662487D01*
X2419950Y3664154D01*
X2419175Y3665195D01*
X2418090Y3666029D01*
X2417005Y3666237D01*
X2415920Y3666029D01*
X2414525Y3665195D01*
X2414990Y3670612D01*
X2419175D01*
G01X2364305Y3693529D02*
X2365235Y3694778D01*
X2366320Y3695404D01*
X2367560Y3695612D01*
X2369110Y3695195D01*
X2370195Y3694154D01*
X2370505Y3692904D01*
X2370350Y3691653D01*
X2369730Y3690612D01*
X2366630Y3688529D01*
X2365235Y3687070D01*
X2364305Y3684987D01*
X2363995Y3683112D01*
X2370505D01*
G01X2379650Y3695612D02*
X2378410Y3695195D01*
X2377480Y3694154D01*
X2376860Y3692904D01*
X2376395Y3691237D01*
X2376240Y3689362D01*
X2376395Y3687487D01*
X2376860Y3685820D01*
X2377480Y3684570D01*
X2378410Y3683529D01*
X2379650Y3683112D01*
X2380890Y3683529D01*
X2381820Y3684570D01*
X2382440Y3685820D01*
X2382905Y3687487D01*
X2383060Y3689362D01*
X2382905Y3691237D01*
X2382440Y3692904D01*
X2381820Y3694154D01*
X2380890Y3695195D01*
X2379650Y3695612D01*
G01X2392050Y3682695D02*
X2391740Y3682904D01*
Y3683320D01*
X2392050Y3683529D01*
X2392360Y3683320D01*
Y3682904D01*
X2392050Y3682695D01*
G01X2401505Y3693529D02*
X2402435Y3694778D01*
X2403520Y3695404D01*
X2404760Y3695612D01*
X2406310Y3695195D01*
X2407395Y3694154D01*
X2407705Y3692904D01*
X2407550Y3691653D01*
X2406930Y3690612D01*
X2403830Y3688529D01*
X2402435Y3687070D01*
X2401505Y3684987D01*
X2401195Y3683112D01*
X2407705D01*
G01X2413440Y3684987D02*
X2414370Y3683945D01*
X2415455Y3683320D01*
X2416850Y3683112D01*
X2418245Y3683529D01*
X2419330Y3684362D01*
X2420105Y3685820D01*
X2420260Y3687487D01*
X2419950Y3689154D01*
X2419175Y3690195D01*
X2418090Y3691029D01*
X2417005Y3691237D01*
X2415920Y3691029D01*
X2414525Y3690195D01*
X2414990Y3695612D01*
X2419175D01*
G01X2384585Y2648870D02*
X2385670Y2650329D01*
X2386600Y2651162D01*
X2387840Y2651579D01*
X2388925Y2651162D01*
X2389700Y2650329D01*
X2390320Y2649079D01*
X2390475Y2647620D01*
X2390320Y2646370D01*
X2389700Y2645120D01*
X2388770Y2644079D01*
X2387685Y2643662D01*
X2386445Y2644079D01*
X2385360Y2645328D01*
X2384740Y2647204D01*
X2384585Y2649287D01*
X2384895Y2651995D01*
X2385360Y2653454D01*
X2386135Y2654912D01*
X2387220Y2655954D01*
X2388305Y2656162D01*
X2389390Y2655745D01*
X2390165Y2654704D01*
G01X2399930Y2643662D02*
Y2656162D01*
X2398070Y2653662D01*
G01Y2643662D02*
X2401790D01*
G01X2412330Y2643245D02*
X2412020Y2643454D01*
Y2643870D01*
X2412330Y2644079D01*
X2412640Y2643870D01*
Y2643454D01*
X2412330Y2643245D01*
G01X2421320Y2646162D02*
X2422250Y2644703D01*
X2423490Y2643870D01*
X2424885Y2643662D01*
X2426125Y2643870D01*
X2427365Y2644912D01*
X2428140Y2646162D01*
X2428295Y2647412D01*
X2427985Y2648870D01*
X2426900Y2649912D01*
X2425815Y2650329D01*
X2424420D01*
G01X2425815D02*
X2426745Y2650954D01*
X2427520Y2651995D01*
X2427830Y2653245D01*
X2427520Y2654495D01*
X2426745Y2655537D01*
X2425350Y2656162D01*
X2423955Y2655954D01*
X2422560Y2655120D01*
G01X2377565Y3344830D02*
X2378650Y3343789D01*
X2379890Y3343372D01*
X2381130Y3343789D01*
X2382215Y3345038D01*
X2382990Y3346914D01*
X2383300Y3348789D01*
Y3351080D01*
X2382990Y3352955D01*
X2382215Y3354622D01*
X2381285Y3355455D01*
X2380200Y3355872D01*
X2378960Y3355455D01*
X2378030Y3354622D01*
X2377410Y3353372D01*
X2377100Y3351705D01*
X2377410Y3350247D01*
X2378185Y3348789D01*
X2379115Y3347955D01*
X2380200Y3347747D01*
X2381440Y3348163D01*
X2382370Y3349205D01*
X2383300Y3351080D01*
G01X2392600Y3342955D02*
X2392290Y3343164D01*
Y3343580D01*
X2392600Y3343789D01*
X2392910Y3343580D01*
Y3343164D01*
X2392600Y3342955D01*
G01X2401590Y3345872D02*
X2402520Y3344413D01*
X2403760Y3343580D01*
X2405155Y3343372D01*
X2406395Y3343580D01*
X2407635Y3344622D01*
X2408410Y3345872D01*
X2408565Y3347122D01*
X2408255Y3348580D01*
X2407170Y3349622D01*
X2406085Y3350039D01*
X2404690D01*
G01X2406085D02*
X2407015Y3350664D01*
X2407790Y3351705D01*
X2408100Y3352955D01*
X2407790Y3354205D01*
X2407015Y3355247D01*
X2405620Y3355872D01*
X2404225Y3355664D01*
X2402830Y3354830D01*
G01X2377565Y3369830D02*
X2378650Y3368789D01*
X2379890Y3368372D01*
X2381130Y3368789D01*
X2382215Y3370038D01*
X2382990Y3371914D01*
X2383300Y3373789D01*
Y3376080D01*
X2382990Y3377955D01*
X2382215Y3379622D01*
X2381285Y3380455D01*
X2380200Y3380872D01*
X2378960Y3380455D01*
X2378030Y3379622D01*
X2377410Y3378372D01*
X2377100Y3376705D01*
X2377410Y3375247D01*
X2378185Y3373789D01*
X2379115Y3372955D01*
X2380200Y3372747D01*
X2381440Y3373163D01*
X2382370Y3374205D01*
X2383300Y3376080D01*
G01X2392600Y3367955D02*
X2392290Y3368164D01*
Y3368580D01*
X2392600Y3368789D01*
X2392910Y3368580D01*
Y3368164D01*
X2392600Y3367955D01*
G01X2401590Y3370872D02*
X2402520Y3369413D01*
X2403760Y3368580D01*
X2405155Y3368372D01*
X2406395Y3368580D01*
X2407635Y3369622D01*
X2408410Y3370872D01*
X2408565Y3372122D01*
X2408255Y3373580D01*
X2407170Y3374622D01*
X2406085Y3375039D01*
X2404690D01*
G01X2406085D02*
X2407015Y3375664D01*
X2407790Y3376705D01*
X2408100Y3377955D01*
X2407790Y3379205D01*
X2407015Y3380247D01*
X2405620Y3380872D01*
X2404225Y3380664D01*
X2402830Y3379830D01*
G01X2377565Y3394830D02*
X2378650Y3393789D01*
X2379890Y3393372D01*
X2381130Y3393789D01*
X2382215Y3395038D01*
X2382990Y3396914D01*
X2383300Y3398789D01*
Y3401080D01*
X2382990Y3402955D01*
X2382215Y3404622D01*
X2381285Y3405455D01*
X2380200Y3405872D01*
X2378960Y3405455D01*
X2378030Y3404622D01*
X2377410Y3403372D01*
X2377100Y3401705D01*
X2377410Y3400247D01*
X2378185Y3398789D01*
X2379115Y3397955D01*
X2380200Y3397747D01*
X2381440Y3398163D01*
X2382370Y3399205D01*
X2383300Y3401080D01*
G01X2392600Y3392955D02*
X2392290Y3393164D01*
Y3393580D01*
X2392600Y3393789D01*
X2392910Y3393580D01*
Y3393164D01*
X2392600Y3392955D01*
G01X2401590Y3395872D02*
X2402520Y3394413D01*
X2403760Y3393580D01*
X2405155Y3393372D01*
X2406395Y3393580D01*
X2407635Y3394622D01*
X2408410Y3395872D01*
X2408565Y3397122D01*
X2408255Y3398580D01*
X2407170Y3399622D01*
X2406085Y3400039D01*
X2404690D01*
G01X2406085D02*
X2407015Y3400664D01*
X2407790Y3401705D01*
X2408100Y3402955D01*
X2407790Y3404205D01*
X2407015Y3405247D01*
X2405620Y3405872D01*
X2404225Y3405664D01*
X2402830Y3404830D01*
G01X2485800Y2668662D02*
Y2681162D01*
X2489830Y2670745D01*
X2493860Y2681162D01*
Y2668662D01*
G01X2499285D02*
Y2681162D01*
X2505175D01*
G01X2503005Y2675120D02*
X2499285D01*
G01X2515560Y2674912D02*
X2518660D01*
Y2671162D01*
X2517730Y2669912D01*
X2516645Y2669079D01*
X2515095Y2668662D01*
X2513545Y2669079D01*
X2512460Y2669912D01*
X2511530Y2671162D01*
X2510910Y2672620D01*
X2510600Y2674287D01*
Y2675745D01*
X2510910Y2676995D01*
X2511530Y2678454D01*
X2512460Y2679704D01*
X2513390Y2680537D01*
X2514630Y2681162D01*
X2515715D01*
X2516955Y2680745D01*
X2517885Y2679912D01*
G01X2522380Y2664495D02*
X2531680D01*
G01X2536175Y2670328D02*
X2537415Y2669287D01*
X2538810Y2668662D01*
X2540050D01*
X2541290Y2669287D01*
X2542220Y2670328D01*
X2542685Y2671787D01*
X2542375Y2673245D01*
X2541600Y2674495D01*
X2540205Y2675329D01*
X2538345Y2675745D01*
X2537260Y2676579D01*
X2536795Y2678037D01*
X2537105Y2679495D01*
X2537880Y2680537D01*
X2538965Y2681162D01*
X2540050D01*
X2541135Y2680745D01*
X2542065Y2679704D01*
G01X2551830Y2681162D02*
Y2668662D01*
G01X2548265Y2681162D02*
X2555395D01*
G01X2560820D02*
Y2672204D01*
X2561440Y2670328D01*
X2562680Y2669079D01*
X2564230Y2668662D01*
X2565780Y2669079D01*
X2567020Y2670328D01*
X2567640Y2672204D01*
Y2681162D01*
G01X2577870Y2675329D02*
X2578490Y2675954D01*
X2578955Y2676995D01*
X2579265Y2678454D01*
X2578955Y2679704D01*
X2578335Y2680537D01*
X2577250Y2681162D01*
X2573065D01*
Y2668662D01*
X2578180D01*
X2579265Y2669495D01*
X2579885Y2670745D01*
X2580195Y2672204D01*
X2579885Y2673662D01*
X2578955Y2674912D01*
X2577870Y2675329D01*
X2573065D01*
G01X2472953Y2909540D02*
Y2922040D01*
X2476983Y2911623D01*
X2481013Y2922040D01*
Y2909540D01*
G01X2486438D02*
Y2922040D01*
X2492328D01*
G01X2490158Y2915998D02*
X2486438D01*
G01X2502713Y2915790D02*
X2505813D01*
Y2912040D01*
X2504883Y2910790D01*
X2503798Y2909957D01*
X2502248Y2909540D01*
X2500698Y2909957D01*
X2499613Y2910790D01*
X2498683Y2912040D01*
X2498063Y2913498D01*
X2497753Y2915165D01*
Y2916623D01*
X2498063Y2917873D01*
X2498683Y2919332D01*
X2499613Y2920582D01*
X2500543Y2921415D01*
X2501783Y2922040D01*
X2502868D01*
X2504108Y2921623D01*
X2505038Y2920790D01*
G01X2509533Y2905373D02*
X2518833D01*
G01X2523328Y2911206D02*
X2524568Y2910165D01*
X2525963Y2909540D01*
X2527203D01*
X2528443Y2910165D01*
X2529373Y2911206D01*
X2529838Y2912665D01*
X2529528Y2914123D01*
X2528753Y2915373D01*
X2527358Y2916207D01*
X2525498Y2916623D01*
X2524413Y2917457D01*
X2523948Y2918915D01*
X2524258Y2920373D01*
X2525033Y2921415D01*
X2526118Y2922040D01*
X2527203D01*
X2528288Y2921623D01*
X2529218Y2920582D01*
G01X2538983Y2922040D02*
Y2909540D01*
G01X2535418Y2922040D02*
X2542548D01*
G01X2547973D02*
Y2913082D01*
X2548593Y2911206D01*
X2549833Y2909957D01*
X2551383Y2909540D01*
X2552933Y2909957D01*
X2554173Y2911206D01*
X2554793Y2913082D01*
Y2922040D01*
G01X2565023Y2916207D02*
X2565643Y2916832D01*
X2566108Y2917873D01*
X2566418Y2919332D01*
X2566108Y2920582D01*
X2565488Y2921415D01*
X2564403Y2922040D01*
X2560218D01*
Y2909540D01*
X2565333D01*
X2566418Y2910373D01*
X2567038Y2911623D01*
X2567348Y2913082D01*
X2567038Y2914540D01*
X2566108Y2915790D01*
X2565023Y2916207D01*
X2560218D01*
G01X2474200Y3125922D02*
Y3138422D01*
X2478230Y3128005D01*
X2482260Y3138422D01*
Y3125922D01*
G01X2487685D02*
Y3138422D01*
X2493575D01*
G01X2491405Y3132380D02*
X2487685D01*
G01X2503960Y3132172D02*
X2507060D01*
Y3128422D01*
X2506130Y3127172D01*
X2505045Y3126339D01*
X2503495Y3125922D01*
X2501945Y3126339D01*
X2500860Y3127172D01*
X2499930Y3128422D01*
X2499310Y3129880D01*
X2499000Y3131547D01*
Y3133005D01*
X2499310Y3134255D01*
X2499930Y3135714D01*
X2500860Y3136964D01*
X2501790Y3137797D01*
X2503030Y3138422D01*
X2504115D01*
X2505355Y3138005D01*
X2506285Y3137172D01*
G01X2510780Y3121755D02*
X2520080D01*
G01X2524575Y3127588D02*
X2525815Y3126547D01*
X2527210Y3125922D01*
X2528450D01*
X2529690Y3126547D01*
X2530620Y3127588D01*
X2531085Y3129047D01*
X2530775Y3130505D01*
X2530000Y3131755D01*
X2528605Y3132589D01*
X2526745Y3133005D01*
X2525660Y3133839D01*
X2525195Y3135297D01*
X2525505Y3136755D01*
X2526280Y3137797D01*
X2527365Y3138422D01*
X2528450D01*
X2529535Y3138005D01*
X2530465Y3136964D01*
G01X2540230Y3138422D02*
Y3125922D01*
G01X2536665Y3138422D02*
X2543795D01*
G01X2549220D02*
Y3129464D01*
X2549840Y3127588D01*
X2551080Y3126339D01*
X2552630Y3125922D01*
X2554180Y3126339D01*
X2555420Y3127588D01*
X2556040Y3129464D01*
Y3138422D01*
G01X2566270Y3132589D02*
X2566890Y3133214D01*
X2567355Y3134255D01*
X2567665Y3135714D01*
X2567355Y3136964D01*
X2566735Y3137797D01*
X2565650Y3138422D01*
X2561465D01*
Y3125922D01*
X2566580D01*
X2567665Y3126755D01*
X2568285Y3128005D01*
X2568595Y3129464D01*
X2568285Y3130922D01*
X2567355Y3132172D01*
X2566270Y3132589D01*
X2561465D01*
G01X2472270Y3418372D02*
Y3430872D01*
X2476300Y3420455D01*
X2480330Y3430872D01*
Y3418372D01*
G01X2485755D02*
Y3430872D01*
X2491645D01*
G01X2489475Y3424830D02*
X2485755D01*
G01X2502030Y3424622D02*
X2505130D01*
Y3420872D01*
X2504200Y3419622D01*
X2503115Y3418789D01*
X2501565Y3418372D01*
X2500015Y3418789D01*
X2498930Y3419622D01*
X2498000Y3420872D01*
X2497380Y3422330D01*
X2497070Y3423997D01*
Y3425455D01*
X2497380Y3426705D01*
X2498000Y3428164D01*
X2498930Y3429414D01*
X2499860Y3430247D01*
X2501100Y3430872D01*
X2502185D01*
X2503425Y3430455D01*
X2504355Y3429622D01*
G01X2508850Y3414205D02*
X2518150D01*
G01X2522645Y3420038D02*
X2523885Y3418997D01*
X2525280Y3418372D01*
X2526520D01*
X2527760Y3418997D01*
X2528690Y3420038D01*
X2529155Y3421497D01*
X2528845Y3422955D01*
X2528070Y3424205D01*
X2526675Y3425039D01*
X2524815Y3425455D01*
X2523730Y3426289D01*
X2523265Y3427747D01*
X2523575Y3429205D01*
X2524350Y3430247D01*
X2525435Y3430872D01*
X2526520D01*
X2527605Y3430455D01*
X2528535Y3429414D01*
G01X2538300Y3430872D02*
Y3418372D01*
G01X2534735Y3430872D02*
X2541865D01*
G01X2547290D02*
Y3421914D01*
X2547910Y3420038D01*
X2549150Y3418789D01*
X2550700Y3418372D01*
X2552250Y3418789D01*
X2553490Y3420038D01*
X2554110Y3421914D01*
Y3430872D01*
G01X2564340Y3425039D02*
X2564960Y3425664D01*
X2565425Y3426705D01*
X2565735Y3428164D01*
X2565425Y3429414D01*
X2564805Y3430247D01*
X2563720Y3430872D01*
X2559535D01*
Y3418372D01*
X2564650D01*
X2565735Y3419205D01*
X2566355Y3420455D01*
X2566665Y3421914D01*
X2566355Y3423372D01*
X2565425Y3424622D01*
X2564340Y3425039D01*
X2559535D01*
G01X2471720Y3708112D02*
Y3720612D01*
X2475750Y3710195D01*
X2479780Y3720612D01*
Y3708112D01*
G01X2485205D02*
Y3720612D01*
X2491095D01*
G01X2488925Y3714570D02*
X2485205D01*
G01X2501480Y3714362D02*
X2504580D01*
Y3710612D01*
X2503650Y3709362D01*
X2502565Y3708529D01*
X2501015Y3708112D01*
X2499465Y3708529D01*
X2498380Y3709362D01*
X2497450Y3710612D01*
X2496830Y3712070D01*
X2496520Y3713737D01*
Y3715195D01*
X2496830Y3716445D01*
X2497450Y3717904D01*
X2498380Y3719154D01*
X2499310Y3719987D01*
X2500550Y3720612D01*
X2501635D01*
X2502875Y3720195D01*
X2503805Y3719362D01*
G01X2508300Y3703945D02*
X2517600D01*
G01X2522095Y3709778D02*
X2523335Y3708737D01*
X2524730Y3708112D01*
X2525970D01*
X2527210Y3708737D01*
X2528140Y3709778D01*
X2528605Y3711237D01*
X2528295Y3712695D01*
X2527520Y3713945D01*
X2526125Y3714779D01*
X2524265Y3715195D01*
X2523180Y3716029D01*
X2522715Y3717487D01*
X2523025Y3718945D01*
X2523800Y3719987D01*
X2524885Y3720612D01*
X2525970D01*
X2527055Y3720195D01*
X2527985Y3719154D01*
G01X2537750Y3720612D02*
Y3708112D01*
G01X2534185Y3720612D02*
X2541315D01*
G01X2546740D02*
Y3711654D01*
X2547360Y3709778D01*
X2548600Y3708529D01*
X2550150Y3708112D01*
X2551700Y3708529D01*
X2552940Y3709778D01*
X2553560Y3711654D01*
Y3720612D01*
G01X2563790Y3714779D02*
X2564410Y3715404D01*
X2564875Y3716445D01*
X2565185Y3717904D01*
X2564875Y3719154D01*
X2564255Y3719987D01*
X2563170Y3720612D01*
X2558985D01*
Y3708112D01*
X2564100D01*
X2565185Y3708945D01*
X2565805Y3710195D01*
X2566115Y3711654D01*
X2565805Y3713112D01*
X2564875Y3714362D01*
X2563790Y3714779D01*
X2558985D01*
G01X2518368Y2888707D02*
X2522398D01*
G01X2519615Y3105089D02*
X2523645D01*
G01X2517685Y3347539D02*
X2521715D01*
G01X2517685Y3372539D02*
X2521715D01*
G01X2517685Y3397539D02*
X2521715D01*
G01X2517135Y3637279D02*
X2521165D01*
G01X2517135Y3662279D02*
X2521165D01*
G01X2517135Y3687279D02*
X2521165D01*
G01X2531215Y2647829D02*
X2535245D01*
G01X2607338Y2894957D02*
X2608268Y2896206D01*
X2609353Y2896832D01*
X2610593Y2897040D01*
X2612143Y2896623D01*
X2613228Y2895582D01*
X2613538Y2894332D01*
X2613383Y2893081D01*
X2612763Y2892040D01*
X2609663Y2889957D01*
X2608268Y2888498D01*
X2607338Y2886415D01*
X2607028Y2884540D01*
X2613538D01*
G01X2619273Y2886415D02*
X2620203Y2885373D01*
X2621288Y2884748D01*
X2622683Y2884540D01*
X2624078Y2884957D01*
X2625163Y2885790D01*
X2625938Y2887248D01*
X2626093Y2888915D01*
X2625783Y2890582D01*
X2625008Y2891623D01*
X2623923Y2892457D01*
X2622838Y2892665D01*
X2621753Y2892457D01*
X2620358Y2891623D01*
X2620823Y2897040D01*
X2625008D01*
G01X2632138Y2889748D02*
X2633223Y2891207D01*
X2634153Y2892040D01*
X2635393Y2892457D01*
X2636478Y2892040D01*
X2637253Y2891207D01*
X2637873Y2889957D01*
X2638028Y2888498D01*
X2637873Y2887248D01*
X2637253Y2885998D01*
X2636323Y2884957D01*
X2635238Y2884540D01*
X2633998Y2884957D01*
X2632913Y2886206D01*
X2632293Y2888082D01*
X2632138Y2890165D01*
X2632448Y2892873D01*
X2632913Y2894332D01*
X2633688Y2895790D01*
X2634773Y2896832D01*
X2635858Y2897040D01*
X2636943Y2896623D01*
X2637718Y2895582D01*
G01X2610283Y2909540D02*
X2609043Y2909748D01*
X2607958Y2910581D01*
X2607028Y2911832D01*
X2606408Y2913290D01*
X2606098Y2914957D01*
Y2916623D01*
X2606408Y2918290D01*
X2607028Y2919748D01*
X2607958Y2920998D01*
X2609043Y2921832D01*
X2610283Y2922040D01*
X2611523Y2921832D01*
X2612608Y2920998D01*
X2613538Y2919748D01*
X2614158Y2918290D01*
X2614468Y2916623D01*
Y2914957D01*
X2614158Y2913290D01*
X2613538Y2911832D01*
X2612608Y2910581D01*
X2611523Y2909748D01*
X2610283Y2909540D01*
G01X2611523Y2912873D02*
X2613383Y2909540D01*
G01X2622683Y2922040D02*
Y2909540D01*
G01X2619118Y2922040D02*
X2626248D01*
G01X2635083Y2909540D02*
Y2915165D01*
X2631983Y2922040D01*
G01X2638183D02*
X2635083Y2915165D01*
G01X2617730Y3100922D02*
Y3113422D01*
X2615870Y3110922D01*
G01Y3100922D02*
X2619590D01*
G01X2627185Y3106130D02*
X2628270Y3107589D01*
X2629200Y3108422D01*
X2630440Y3108839D01*
X2631525Y3108422D01*
X2632300Y3107589D01*
X2632920Y3106339D01*
X2633075Y3104880D01*
X2632920Y3103630D01*
X2632300Y3102380D01*
X2631370Y3101339D01*
X2630285Y3100922D01*
X2629045Y3101339D01*
X2627960Y3102588D01*
X2627340Y3104464D01*
X2627185Y3106547D01*
X2627495Y3109255D01*
X2627960Y3110714D01*
X2628735Y3112172D01*
X2629820Y3113214D01*
X2630905Y3113422D01*
X2631990Y3113005D01*
X2632765Y3111964D01*
G01X2611530Y3125922D02*
X2610290Y3126130D01*
X2609205Y3126963D01*
X2608275Y3128214D01*
X2607655Y3129672D01*
X2607345Y3131339D01*
Y3133005D01*
X2607655Y3134672D01*
X2608275Y3136130D01*
X2609205Y3137380D01*
X2610290Y3138214D01*
X2611530Y3138422D01*
X2612770Y3138214D01*
X2613855Y3137380D01*
X2614785Y3136130D01*
X2615405Y3134672D01*
X2615715Y3133005D01*
Y3131339D01*
X2615405Y3129672D01*
X2614785Y3128214D01*
X2613855Y3126963D01*
X2612770Y3126130D01*
X2611530Y3125922D01*
G01X2612770Y3129255D02*
X2614630Y3125922D01*
G01X2623930Y3138422D02*
Y3125922D01*
G01X2620365Y3138422D02*
X2627495D01*
G01X2636330Y3125922D02*
Y3131547D01*
X2633230Y3138422D01*
G01X2639430D02*
X2636330Y3131547D01*
G01X2609600Y3368372D02*
Y3380872D01*
X2607740Y3378372D01*
G01Y3368372D02*
X2611460D01*
G01X2619055Y3373580D02*
X2620140Y3375039D01*
X2621070Y3375872D01*
X2622310Y3376289D01*
X2623395Y3375872D01*
X2624170Y3375039D01*
X2624790Y3373789D01*
X2624945Y3372330D01*
X2624790Y3371080D01*
X2624170Y3369830D01*
X2623240Y3368789D01*
X2622155Y3368372D01*
X2620915Y3368789D01*
X2619830Y3370038D01*
X2619210Y3371914D01*
X2619055Y3373997D01*
X2619365Y3376705D01*
X2619830Y3378164D01*
X2620605Y3379622D01*
X2621690Y3380664D01*
X2622775Y3380872D01*
X2623860Y3380455D01*
X2624635Y3379414D01*
G01X2631455Y3378789D02*
X2632385Y3380038D01*
X2633470Y3380664D01*
X2634710Y3380872D01*
X2636260Y3380455D01*
X2637345Y3379414D01*
X2637655Y3378164D01*
X2637500Y3376913D01*
X2636880Y3375872D01*
X2633780Y3373789D01*
X2632385Y3372330D01*
X2631455Y3370247D01*
X2631145Y3368372D01*
X2637655D01*
G01X2609600Y3393372D02*
Y3405872D01*
X2607740Y3403372D01*
G01Y3393372D02*
X2611460D01*
G01X2619055Y3403789D02*
X2619985Y3405038D01*
X2621070Y3405664D01*
X2622310Y3405872D01*
X2623860Y3405455D01*
X2624945Y3404414D01*
X2625255Y3403164D01*
X2625100Y3401913D01*
X2624480Y3400872D01*
X2621380Y3398789D01*
X2619985Y3397330D01*
X2619055Y3395247D01*
X2618745Y3393372D01*
X2625255D01*
G01X2634400D02*
X2635485Y3393580D01*
X2636725Y3394205D01*
X2637500Y3395247D01*
X2637810Y3396705D01*
X2637500Y3398163D01*
X2636570Y3399414D01*
X2635175Y3400039D01*
X2633625D01*
X2632695Y3400455D01*
X2631920Y3401497D01*
X2631610Y3402955D01*
X2632075Y3404414D01*
X2633160Y3405455D01*
X2634400Y3405872D01*
X2635640Y3405455D01*
X2636725Y3404414D01*
X2637190Y3402955D01*
X2636880Y3401497D01*
X2636105Y3400455D01*
X2635175Y3400039D01*
X2633625D01*
X2632230Y3399414D01*
X2631300Y3398163D01*
X2630990Y3396705D01*
X2631300Y3395247D01*
X2632075Y3394205D01*
X2633315Y3393580D01*
X2634400Y3393372D01*
G01X2609600Y3418372D02*
X2608360Y3418580D01*
X2607275Y3419413D01*
X2606345Y3420664D01*
X2605725Y3422122D01*
X2605415Y3423789D01*
Y3425455D01*
X2605725Y3427122D01*
X2606345Y3428580D01*
X2607275Y3429830D01*
X2608360Y3430664D01*
X2609600Y3430872D01*
X2610840Y3430664D01*
X2611925Y3429830D01*
X2612855Y3428580D01*
X2613475Y3427122D01*
X2613785Y3425455D01*
Y3423789D01*
X2613475Y3422122D01*
X2612855Y3420664D01*
X2611925Y3419413D01*
X2610840Y3418580D01*
X2609600Y3418372D01*
G01X2610840Y3421705D02*
X2612700Y3418372D01*
G01X2622000Y3430872D02*
Y3418372D01*
G01X2618435Y3430872D02*
X2625565D01*
G01X2634400Y3418372D02*
Y3423997D01*
X2631300Y3430872D01*
G01X2637500D02*
X2634400Y3423997D01*
G01X2609050Y3633112D02*
Y3645612D01*
X2607190Y3643112D01*
G01Y3633112D02*
X2610910D01*
G01X2618505Y3643529D02*
X2619435Y3644778D01*
X2620520Y3645404D01*
X2621760Y3645612D01*
X2623310Y3645195D01*
X2624395Y3644154D01*
X2624705Y3642904D01*
X2624550Y3641653D01*
X2623930Y3640612D01*
X2620830Y3638529D01*
X2619435Y3637070D01*
X2618505Y3634987D01*
X2618195Y3633112D01*
X2624705D01*
G01X2633850D02*
X2634935Y3633320D01*
X2636175Y3633945D01*
X2636950Y3634987D01*
X2637260Y3636445D01*
X2636950Y3637903D01*
X2636020Y3639154D01*
X2634625Y3639779D01*
X2633075D01*
X2632145Y3640195D01*
X2631370Y3641237D01*
X2631060Y3642695D01*
X2631525Y3644154D01*
X2632610Y3645195D01*
X2633850Y3645612D01*
X2635090Y3645195D01*
X2636175Y3644154D01*
X2636640Y3642695D01*
X2636330Y3641237D01*
X2635555Y3640195D01*
X2634625Y3639779D01*
X2633075D01*
X2631680Y3639154D01*
X2630750Y3637903D01*
X2630440Y3636445D01*
X2630750Y3634987D01*
X2631525Y3633945D01*
X2632765Y3633320D01*
X2633850Y3633112D01*
G01X2609050Y3683112D02*
Y3695612D01*
X2607190Y3693112D01*
G01Y3683112D02*
X2610910D01*
G01X2618040Y3685612D02*
X2618970Y3684153D01*
X2620210Y3683320D01*
X2621605Y3683112D01*
X2622845Y3683320D01*
X2624085Y3684362D01*
X2624860Y3685612D01*
X2625015Y3686862D01*
X2624705Y3688320D01*
X2623620Y3689362D01*
X2622535Y3689779D01*
X2621140D01*
G01X2622535D02*
X2623465Y3690404D01*
X2624240Y3691445D01*
X2624550Y3692695D01*
X2624240Y3693945D01*
X2623465Y3694987D01*
X2622070Y3695612D01*
X2620675Y3695404D01*
X2619280Y3694570D01*
G01X2630905Y3688320D02*
X2631990Y3689779D01*
X2632920Y3690612D01*
X2634160Y3691029D01*
X2635245Y3690612D01*
X2636020Y3689779D01*
X2636640Y3688529D01*
X2636795Y3687070D01*
X2636640Y3685820D01*
X2636020Y3684570D01*
X2635090Y3683529D01*
X2634005Y3683112D01*
X2632765Y3683529D01*
X2631680Y3684778D01*
X2631060Y3686654D01*
X2630905Y3688737D01*
X2631215Y3691445D01*
X2631680Y3692904D01*
X2632455Y3694362D01*
X2633540Y3695404D01*
X2634625Y3695612D01*
X2635710Y3695195D01*
X2636485Y3694154D01*
G01X2609050Y3708112D02*
X2607810Y3708320D01*
X2606725Y3709153D01*
X2605795Y3710404D01*
X2605175Y3711862D01*
X2604865Y3713529D01*
Y3715195D01*
X2605175Y3716862D01*
X2605795Y3718320D01*
X2606725Y3719570D01*
X2607810Y3720404D01*
X2609050Y3720612D01*
X2610290Y3720404D01*
X2611375Y3719570D01*
X2612305Y3718320D01*
X2612925Y3716862D01*
X2613235Y3715195D01*
Y3713529D01*
X2612925Y3711862D01*
X2612305Y3710404D01*
X2611375Y3709153D01*
X2610290Y3708320D01*
X2609050Y3708112D01*
G01X2610290Y3711445D02*
X2612150Y3708112D01*
G01X2621450Y3720612D02*
Y3708112D01*
G01X2617885Y3720612D02*
X2625015D01*
G01X2633850Y3708112D02*
Y3713737D01*
X2630750Y3720612D01*
G01X2636950D02*
X2633850Y3713737D01*
G01X2635530Y2643662D02*
X2636615Y2643870D01*
X2637855Y2644495D01*
X2638630Y2645537D01*
X2638940Y2646995D01*
X2638630Y2648453D01*
X2637700Y2649704D01*
X2636305Y2650329D01*
X2634755D01*
X2633825Y2650745D01*
X2633050Y2651787D01*
X2632740Y2653245D01*
X2633205Y2654704D01*
X2634290Y2655745D01*
X2635530Y2656162D01*
X2636770Y2655745D01*
X2637855Y2654704D01*
X2638320Y2653245D01*
X2638010Y2651787D01*
X2637235Y2650745D01*
X2636305Y2650329D01*
X2634755D01*
X2633360Y2649704D01*
X2632430Y2648453D01*
X2632120Y2646995D01*
X2632430Y2645537D01*
X2633205Y2644495D01*
X2634445Y2643870D01*
X2635530Y2643662D01*
G01X2623130Y2668662D02*
X2621890Y2668870D01*
X2620805Y2669703D01*
X2619875Y2670954D01*
X2619255Y2672412D01*
X2618945Y2674079D01*
Y2675745D01*
X2619255Y2677412D01*
X2619875Y2678870D01*
X2620805Y2680120D01*
X2621890Y2680954D01*
X2623130Y2681162D01*
X2624370Y2680954D01*
X2625455Y2680120D01*
X2626385Y2678870D01*
X2627005Y2677412D01*
X2627315Y2675745D01*
Y2674079D01*
X2627005Y2672412D01*
X2626385Y2670954D01*
X2625455Y2669703D01*
X2624370Y2668870D01*
X2623130Y2668662D01*
G01X2624370Y2671995D02*
X2626230Y2668662D01*
G01X2635530Y2681162D02*
Y2668662D01*
G01X2631965Y2681162D02*
X2639095D01*
G01X2647930Y2668662D02*
Y2674287D01*
X2644830Y2681162D01*
G01X2651030D02*
X2647930Y2674287D01*
G01X2619055Y3348580D02*
X2620140Y3350039D01*
X2621070Y3350872D01*
X2622310Y3351289D01*
X2623395Y3350872D01*
X2624170Y3350039D01*
X2624790Y3348789D01*
X2624945Y3347330D01*
X2624790Y3346080D01*
X2624170Y3344830D01*
X2623240Y3343789D01*
X2622155Y3343372D01*
X2620915Y3343789D01*
X2619830Y3345038D01*
X2619210Y3346914D01*
X2619055Y3348997D01*
X2619365Y3351705D01*
X2619830Y3353164D01*
X2620605Y3354622D01*
X2621690Y3355664D01*
X2622775Y3355872D01*
X2623860Y3355455D01*
X2624635Y3354414D01*
G01X2621450Y3658112D02*
X2622535Y3658320D01*
X2623775Y3658945D01*
X2624550Y3659987D01*
X2624860Y3661445D01*
X2624550Y3662903D01*
X2623620Y3664154D01*
X2622225Y3664779D01*
X2620675D01*
X2619745Y3665195D01*
X2618970Y3666237D01*
X2618660Y3667695D01*
X2619125Y3669154D01*
X2620210Y3670195D01*
X2621450Y3670612D01*
X2622690Y3670195D01*
X2623775Y3669154D01*
X2624240Y3667695D01*
X2623930Y3666237D01*
X2623155Y3665195D01*
X2622225Y3664779D01*
X2620675D01*
X2619280Y3664154D01*
X2618350Y3662903D01*
X2618040Y3661445D01*
X2618350Y3659987D01*
X2619125Y3658945D01*
X2620365Y3658320D01*
X2621450Y3658112D01*
G01X2788376Y2031229D02*
Y2043729D01*
X2794266D01*
G01X2792096Y2037687D02*
X2788376D01*
G01X2801861Y2043729D02*
X2805581D01*
G01X2803721D02*
Y2031229D01*
G01X2801861D02*
X2805581D01*
G01X2817051Y2037479D02*
X2820151D01*
Y2033729D01*
X2819221Y2032479D01*
X2818136Y2031646D01*
X2816586Y2031229D01*
X2815036Y2031646D01*
X2813951Y2032479D01*
X2813021Y2033729D01*
X2812401Y2035187D01*
X2812091Y2036854D01*
Y2038312D01*
X2812401Y2039562D01*
X2813021Y2041021D01*
X2813951Y2042271D01*
X2814881Y2043104D01*
X2816121Y2043729D01*
X2817206D01*
X2818446Y2043312D01*
X2819376Y2042479D01*
G01X2825111Y2043729D02*
Y2034771D01*
X2825731Y2032895D01*
X2826971Y2031646D01*
X2828521Y2031229D01*
X2830071Y2031646D01*
X2831311Y2032895D01*
X2831931Y2034771D01*
Y2043729D01*
G01X2837821Y2031229D02*
Y2043729D01*
X2841696D01*
X2842936Y2043104D01*
X2843711Y2042271D01*
X2844021Y2040604D01*
X2843711Y2038937D01*
X2842781Y2037896D01*
X2841696Y2037271D01*
X2837821D01*
G01X2841696D02*
X2844021Y2031229D01*
G01X2856421D02*
X2850221D01*
Y2043729D01*
X2856421D01*
G01X2853941Y2037687D02*
X2850221D01*
G01X2953970Y2498349D02*
X2954590Y2498974D01*
X2955055Y2500015D01*
X2955365Y2501474D01*
X2955055Y2502724D01*
X2954435Y2503557D01*
X2953350Y2504182D01*
X2949165D01*
Y2491682D01*
X2954280D01*
X2955365Y2492515D01*
X2955985Y2493765D01*
X2956295Y2495224D01*
X2955985Y2496682D01*
X2955055Y2497932D01*
X2953970Y2498349D01*
X2949165D01*
G01X2961255Y2491682D02*
X2965130Y2504182D01*
X2969005Y2491682D01*
G01X2967610Y2496057D02*
X2962650D01*
G01X2980940Y2503140D02*
X2980010Y2503765D01*
X2978925Y2504182D01*
X2977685D01*
X2976290Y2503557D01*
X2975205Y2502515D01*
X2974430Y2501265D01*
X2973810Y2499182D01*
X2973655Y2497307D01*
X2973965Y2495432D01*
X2974430Y2494182D01*
X2975360Y2492932D01*
X2976445Y2492099D01*
X2977530Y2491682D01*
X2978615D01*
X2979700Y2492099D01*
X2980630Y2492723D01*
X2981405Y2493557D01*
G01X2986520Y2491682D02*
Y2504182D01*
G01X2992410D02*
X2986520Y2496473D01*
G01X2993340Y2491682D02*
X2989155Y2500015D01*
G01X2998920Y2491682D02*
Y2504182D01*
X3002020D01*
X3003260Y2503557D01*
X3004190Y2502724D01*
X3004965Y2501474D01*
X3005585Y2500015D01*
X3005740Y2497932D01*
X3005585Y2495849D01*
X3004965Y2494390D01*
X3004190Y2493140D01*
X3003260Y2492307D01*
X3002020Y2491682D01*
X2998920D01*
G01X3011630D02*
Y2504182D01*
X3015505D01*
X3016745Y2503557D01*
X3017520Y2502724D01*
X3017830Y2501057D01*
X3017520Y2499390D01*
X3016590Y2498349D01*
X3015505Y2497724D01*
X3011630D01*
G01X3015505D02*
X3017830Y2491682D01*
G01X3025270Y2504182D02*
X3028990D01*
G01X3027130D02*
Y2491682D01*
G01X3025270D02*
X3028990D01*
G01X3036430Y2504182D02*
Y2491682D01*
X3042630D01*
G01X3048830Y2504182D02*
Y2491682D01*
X3055030D01*
G01X3073475Y2493348D02*
X3074715Y2492307D01*
X3076110Y2491682D01*
X3077350D01*
X3078590Y2492307D01*
X3079520Y2493348D01*
X3079985Y2494807D01*
X3079675Y2496265D01*
X3078900Y2497515D01*
X3077505Y2498349D01*
X3075645Y2498765D01*
X3074560Y2499599D01*
X3074095Y2501057D01*
X3074405Y2502515D01*
X3075180Y2503557D01*
X3076265Y2504182D01*
X3077350D01*
X3078435Y2503765D01*
X3079365Y2502724D01*
G01X3089130Y2504182D02*
Y2491682D01*
G01X3085565Y2504182D02*
X3092695D01*
G01X3098120D02*
Y2495224D01*
X3098740Y2493348D01*
X3099980Y2492099D01*
X3101530Y2491682D01*
X3103080Y2492099D01*
X3104320Y2493348D01*
X3104940Y2495224D01*
Y2504182D01*
G01X3115170Y2498349D02*
X3115790Y2498974D01*
X3116255Y2500015D01*
X3116565Y2501474D01*
X3116255Y2502724D01*
X3115635Y2503557D01*
X3114550Y2504182D01*
X3110365D01*
Y2491682D01*
X3115480D01*
X3116565Y2492515D01*
X3117185Y2493765D01*
X3117495Y2495224D01*
X3117185Y2496682D01*
X3116255Y2497932D01*
X3115170Y2498349D01*
X3110365D01*
G01X3135630Y2504182D02*
Y2491682D01*
X3141830D01*
G01X3154230D02*
X3148030D01*
Y2504182D01*
X3154230D01*
G01X3151750Y2498140D02*
X3148030D01*
G01X3159965Y2491682D02*
Y2504182D01*
X3167095Y2491682D01*
Y2504182D01*
G01X3176860Y2497932D02*
X3179960D01*
Y2494182D01*
X3179030Y2492932D01*
X3177945Y2492099D01*
X3176395Y2491682D01*
X3174845Y2492099D01*
X3173760Y2492932D01*
X3172830Y2494182D01*
X3172210Y2495640D01*
X3171900Y2497307D01*
Y2498765D01*
X3172210Y2500015D01*
X3172830Y2501474D01*
X3173760Y2502724D01*
X3174690Y2503557D01*
X3175930Y2504182D01*
X3177015D01*
X3178255Y2503765D01*
X3179185Y2502932D01*
G01X3188330Y2504182D02*
Y2491682D01*
G01X3184765Y2504182D02*
X3191895D01*
G01X3197475Y2491682D02*
Y2504182D01*
G01X3203985D02*
Y2491682D01*
G01Y2497932D02*
X3197475D01*
G01X3225530Y2504182D02*
Y2491682D01*
G01X3221965Y2504182D02*
X3229095D01*
G01X3237930Y2491682D02*
X3236690Y2491890D01*
X3235605Y2492723D01*
X3234675Y2493974D01*
X3234055Y2495432D01*
X3233745Y2497099D01*
Y2498765D01*
X3234055Y2500432D01*
X3234675Y2501890D01*
X3235605Y2503140D01*
X3236690Y2503974D01*
X3237930Y2504182D01*
X3239170Y2503974D01*
X3240255Y2503140D01*
X3241185Y2501890D01*
X3241805Y2500432D01*
X3242115Y2498765D01*
Y2497099D01*
X3241805Y2495432D01*
X3241185Y2493974D01*
X3240255Y2492723D01*
X3239170Y2491890D01*
X3237930Y2491682D01*
G01X3247230Y2504182D02*
Y2491682D01*
X3253430D01*
G01X3265830D02*
X3259630D01*
Y2504182D01*
X3265830D01*
G01X3263350Y2498140D02*
X3259630D01*
G01X3272030Y2491682D02*
Y2504182D01*
X3275905D01*
X3277145Y2503557D01*
X3277920Y2502724D01*
X3278230Y2501057D01*
X3277920Y2499390D01*
X3276990Y2498349D01*
X3275905Y2497724D01*
X3272030D01*
G01X3275905D02*
X3278230Y2491682D01*
G01X3283655D02*
X3287530Y2504182D01*
X3291405Y2491682D01*
G01X3290010Y2496057D02*
X3285050D01*
G01X3296365Y2491682D02*
Y2504182D01*
X3303495Y2491682D01*
Y2504182D01*
G01X3315740Y2503140D02*
X3314810Y2503765D01*
X3313725Y2504182D01*
X3312485D01*
X3311090Y2503557D01*
X3310005Y2502515D01*
X3309230Y2501265D01*
X3308610Y2499182D01*
X3308455Y2497307D01*
X3308765Y2495432D01*
X3309230Y2494182D01*
X3310160Y2492932D01*
X3311245Y2492099D01*
X3312330Y2491682D01*
X3313415D01*
X3314500Y2492099D01*
X3315430Y2492723D01*
X3316205Y2493557D01*
G01X3327830Y2491682D02*
X3321630D01*
Y2504182D01*
X3327830D01*
G01X3325350Y2498140D02*
X3321630D01*
G01X3349530Y2504182D02*
Y2491682D01*
G01X3345965Y2504182D02*
X3353095D01*
G01X3361930Y2491682D02*
X3360690Y2491890D01*
X3359605Y2492723D01*
X3358675Y2493974D01*
X3358055Y2495432D01*
X3357745Y2497099D01*
Y2498765D01*
X3358055Y2500432D01*
X3358675Y2501890D01*
X3359605Y2503140D01*
X3360690Y2503974D01*
X3361930Y2504182D01*
X3363170Y2503974D01*
X3364255Y2503140D01*
X3365185Y2501890D01*
X3365805Y2500432D01*
X3366115Y2498765D01*
Y2497099D01*
X3365805Y2495432D01*
X3365185Y2493974D01*
X3364255Y2492723D01*
X3363170Y2491890D01*
X3361930Y2491682D01*
G01X3387970Y2498349D02*
X3388590Y2498974D01*
X3389055Y2500015D01*
X3389365Y2501474D01*
X3389055Y2502724D01*
X3388435Y2503557D01*
X3387350Y2504182D01*
X3383165D01*
Y2491682D01*
X3388280D01*
X3389365Y2492515D01*
X3389985Y2493765D01*
X3390295Y2495224D01*
X3389985Y2496682D01*
X3389055Y2497932D01*
X3387970Y2498349D01*
X3383165D01*
G01X3402230Y2491682D02*
X3396030D01*
Y2504182D01*
X3402230D01*
G01X3399750Y2498140D02*
X3396030D01*
G01X3423620Y2491682D02*
X3423930Y2494390D01*
X3424395Y2496682D01*
X3425015Y2498765D01*
X3425790Y2501057D01*
X3427030Y2504182D01*
X3420830D01*
G01X3447025Y2495849D02*
X3450745D01*
G01X3448730Y2498557D02*
Y2493140D01*
G01X3458340Y2491265D02*
X3463920Y2504182D01*
G01X3471515Y2495849D02*
X3475545D01*
G01X3482520Y2493557D02*
X3483450Y2492515D01*
X3484535Y2491890D01*
X3485930Y2491682D01*
X3487325Y2492099D01*
X3488410Y2492932D01*
X3489185Y2494390D01*
X3489340Y2496057D01*
X3489030Y2497724D01*
X3488255Y2498765D01*
X3487170Y2499599D01*
X3486085Y2499807D01*
X3485000Y2499599D01*
X3483605Y2498765D01*
X3484070Y2504182D01*
X3488255D01*
G01X3506700Y2491682D02*
Y2504182D01*
X3510730Y2493765D01*
X3514760Y2504182D01*
Y2491682D01*
G01X3521270Y2504182D02*
X3524990D01*
G01X3523130D02*
Y2491682D01*
G01X3521270D02*
X3524990D01*
G01X3532430Y2504182D02*
Y2491682D01*
X3538630D01*
G01X3544675Y2493348D02*
X3545915Y2492307D01*
X3547310Y2491682D01*
X3548550D01*
X3549790Y2492307D01*
X3550720Y2493348D01*
X3551185Y2494807D01*
X3550875Y2496265D01*
X3550100Y2497515D01*
X3548705Y2498349D01*
X3546845Y2498765D01*
X3545760Y2499599D01*
X3545295Y2501057D01*
X3545605Y2502515D01*
X3546380Y2503557D01*
X3547465Y2504182D01*
X3548550D01*
X3549635Y2503765D01*
X3550565Y2502724D01*
G01X2789515Y2514599D02*
X2793545D01*
G01X2812300Y2510432D02*
Y2522932D01*
X2816330Y2512515D01*
X2820360Y2522932D01*
Y2510432D01*
G01X2825785D02*
Y2522932D01*
X2831675D01*
G01X2829505Y2516890D02*
X2825785D01*
G01X2842060Y2516682D02*
X2845160D01*
Y2512932D01*
X2844230Y2511682D01*
X2843145Y2510849D01*
X2841595Y2510432D01*
X2840045Y2510849D01*
X2838960Y2511682D01*
X2838030Y2512932D01*
X2837410Y2514390D01*
X2837100Y2516057D01*
Y2517515D01*
X2837410Y2518765D01*
X2838030Y2520224D01*
X2838960Y2521474D01*
X2839890Y2522307D01*
X2841130Y2522932D01*
X2842215D01*
X2843455Y2522515D01*
X2844385Y2521682D01*
G01X2848880Y2506265D02*
X2858180D01*
G01X2862675Y2512098D02*
X2863915Y2511057D01*
X2865310Y2510432D01*
X2866550D01*
X2867790Y2511057D01*
X2868720Y2512098D01*
X2869185Y2513557D01*
X2868875Y2515015D01*
X2868100Y2516265D01*
X2866705Y2517099D01*
X2864845Y2517515D01*
X2863760Y2518349D01*
X2863295Y2519807D01*
X2863605Y2521265D01*
X2864380Y2522307D01*
X2865465Y2522932D01*
X2866550D01*
X2867635Y2522515D01*
X2868565Y2521474D01*
G01X2878330Y2522932D02*
Y2510432D01*
G01X2874765Y2522932D02*
X2881895D01*
G01X2887320D02*
Y2513974D01*
X2887940Y2512098D01*
X2889180Y2510849D01*
X2890730Y2510432D01*
X2892280Y2510849D01*
X2893520Y2512098D01*
X2894140Y2513974D01*
Y2522932D01*
G01X2904370Y2517099D02*
X2904990Y2517724D01*
X2905455Y2518765D01*
X2905765Y2520224D01*
X2905455Y2521474D01*
X2904835Y2522307D01*
X2903750Y2522932D01*
X2899565D01*
Y2510432D01*
X2904680D01*
X2905765Y2511265D01*
X2906385Y2512515D01*
X2906695Y2513974D01*
X2906385Y2515432D01*
X2905455Y2516682D01*
X2904370Y2517099D01*
X2899565D01*
G01X2927930Y2510015D02*
X2927620Y2510224D01*
Y2510640D01*
X2927930Y2510849D01*
X2928240Y2510640D01*
Y2510224D01*
X2927930Y2510015D01*
G01Y2515640D02*
X2927620Y2515849D01*
Y2516265D01*
X2927930Y2516474D01*
X2928240Y2516265D01*
Y2515849D01*
X2927930Y2515640D01*
G01X2948700Y2510432D02*
Y2522932D01*
X2952730Y2512515D01*
X2956760Y2522932D01*
Y2510432D01*
G01X2961255D02*
X2965130Y2522932D01*
X2969005Y2510432D01*
G01X2967610Y2514807D02*
X2962650D01*
G01X2973965Y2510432D02*
Y2522932D01*
X2981095Y2510432D01*
Y2522932D01*
G01X2986520D02*
Y2513974D01*
X2987140Y2512098D01*
X2988380Y2510849D01*
X2989930Y2510432D01*
X2991480Y2510849D01*
X2992720Y2512098D01*
X2993340Y2513974D01*
Y2522932D01*
G01X2999385Y2510432D02*
Y2522932D01*
X3005275D01*
G01X3003105Y2516890D02*
X2999385D01*
G01X3010855Y2510432D02*
X3014730Y2522932D01*
X3018605Y2510432D01*
G01X3017210Y2514807D02*
X3012250D01*
G01X3030540Y2521890D02*
X3029610Y2522515D01*
X3028525Y2522932D01*
X3027285D01*
X3025890Y2522307D01*
X3024805Y2521265D01*
X3024030Y2520015D01*
X3023410Y2517932D01*
X3023255Y2516057D01*
X3023565Y2514182D01*
X3024030Y2512932D01*
X3024960Y2511682D01*
X3026045Y2510849D01*
X3027130Y2510432D01*
X3028215D01*
X3029300Y2510849D01*
X3030230Y2511473D01*
X3031005Y2512307D01*
G01X3039530Y2522932D02*
Y2510432D01*
G01X3035965Y2522932D02*
X3043095D01*
G01X3048520D02*
Y2513974D01*
X3049140Y2512098D01*
X3050380Y2510849D01*
X3051930Y2510432D01*
X3053480Y2510849D01*
X3054720Y2512098D01*
X3055340Y2513974D01*
Y2522932D01*
G01X3061230Y2510432D02*
Y2522932D01*
X3065105D01*
X3066345Y2522307D01*
X3067120Y2521474D01*
X3067430Y2519807D01*
X3067120Y2518140D01*
X3066190Y2517099D01*
X3065105Y2516474D01*
X3061230D01*
G01X3065105D02*
X3067430Y2510432D01*
G01X3074870Y2522932D02*
X3078590D01*
G01X3076730D02*
Y2510432D01*
G01X3074870D02*
X3078590D01*
G01X3085565D02*
Y2522932D01*
X3092695Y2510432D01*
Y2522932D01*
G01X3102460Y2516682D02*
X3105560D01*
Y2512932D01*
X3104630Y2511682D01*
X3103545Y2510849D01*
X3101995Y2510432D01*
X3100445Y2510849D01*
X3099360Y2511682D01*
X3098430Y2512932D01*
X3097810Y2514390D01*
X3097500Y2516057D01*
Y2517515D01*
X3097810Y2518765D01*
X3098430Y2520224D01*
X3099360Y2521474D01*
X3100290Y2522307D01*
X3101530Y2522932D01*
X3102615D01*
X3103855Y2522515D01*
X3104785Y2521682D01*
G01X3123075Y2512098D02*
X3124315Y2511057D01*
X3125710Y2510432D01*
X3126950D01*
X3128190Y2511057D01*
X3129120Y2512098D01*
X3129585Y2513557D01*
X3129275Y2515015D01*
X3128500Y2516265D01*
X3127105Y2517099D01*
X3125245Y2517515D01*
X3124160Y2518349D01*
X3123695Y2519807D01*
X3124005Y2521265D01*
X3124780Y2522307D01*
X3125865Y2522932D01*
X3126950D01*
X3128035Y2522515D01*
X3128965Y2521474D01*
G01X3138730Y2522932D02*
Y2510432D01*
G01X3135165Y2522932D02*
X3142295D01*
G01X3147720D02*
Y2513974D01*
X3148340Y2512098D01*
X3149580Y2510849D01*
X3151130Y2510432D01*
X3152680Y2510849D01*
X3153920Y2512098D01*
X3154540Y2513974D01*
Y2522932D01*
G01X3164770Y2517099D02*
X3165390Y2517724D01*
X3165855Y2518765D01*
X3166165Y2520224D01*
X3165855Y2521474D01*
X3165235Y2522307D01*
X3164150Y2522932D01*
X3159965D01*
Y2510432D01*
X3165080D01*
X3166165Y2511265D01*
X3166785Y2512515D01*
X3167095Y2513974D01*
X3166785Y2515432D01*
X3165855Y2516682D01*
X3164770Y2517099D01*
X3159965D01*
G01X3185230Y2522932D02*
Y2510432D01*
X3191430D01*
G01X3203830D02*
X3197630D01*
Y2522932D01*
X3203830D01*
G01X3201350Y2516890D02*
X3197630D01*
G01X3209565Y2510432D02*
Y2522932D01*
X3216695Y2510432D01*
Y2522932D01*
G01X3226460Y2516682D02*
X3229560D01*
Y2512932D01*
X3228630Y2511682D01*
X3227545Y2510849D01*
X3225995Y2510432D01*
X3224445Y2510849D01*
X3223360Y2511682D01*
X3222430Y2512932D01*
X3221810Y2514390D01*
X3221500Y2516057D01*
Y2517515D01*
X3221810Y2518765D01*
X3222430Y2520224D01*
X3223360Y2521474D01*
X3224290Y2522307D01*
X3225530Y2522932D01*
X3226615D01*
X3227855Y2522515D01*
X3228785Y2521682D01*
G01X3237930Y2522932D02*
Y2510432D01*
G01X3234365Y2522932D02*
X3241495D01*
G01X3247075Y2510432D02*
Y2522932D01*
G01X3253585D02*
Y2510432D01*
G01Y2516682D02*
X3247075D01*
G01X2949475Y2530848D02*
X2950715Y2529807D01*
X2952110Y2529182D01*
X2953350D01*
X2954590Y2529807D01*
X2955520Y2530848D01*
X2955985Y2532307D01*
X2955675Y2533765D01*
X2954900Y2535015D01*
X2953505Y2535849D01*
X2951645Y2536265D01*
X2950560Y2537099D01*
X2950095Y2538557D01*
X2950405Y2540015D01*
X2951180Y2541057D01*
X2952265Y2541682D01*
X2953350D01*
X2954435Y2541265D01*
X2955365Y2540224D01*
G01X2961720Y2541682D02*
Y2532724D01*
X2962340Y2530848D01*
X2963580Y2529599D01*
X2965130Y2529182D01*
X2966680Y2529599D01*
X2967920Y2530848D01*
X2968540Y2532724D01*
Y2541682D01*
G01X2974430Y2529182D02*
Y2541682D01*
X2978305D01*
X2979545Y2541057D01*
X2980320Y2540224D01*
X2980630Y2538557D01*
X2980320Y2536890D01*
X2979390Y2535849D01*
X2978305Y2535224D01*
X2974430D01*
G01X2978305D02*
X2980630Y2529182D01*
G01X2986985D02*
Y2541682D01*
X2992875D01*
G01X2990705Y2535640D02*
X2986985D01*
G01X2998455Y2529182D02*
X3002330Y2541682D01*
X3006205Y2529182D01*
G01X3004810Y2533557D02*
X2999850D01*
G01X3018140Y2540640D02*
X3017210Y2541265D01*
X3016125Y2541682D01*
X3014885D01*
X3013490Y2541057D01*
X3012405Y2540015D01*
X3011630Y2538765D01*
X3011010Y2536682D01*
X3010855Y2534807D01*
X3011165Y2532932D01*
X3011630Y2531682D01*
X3012560Y2530432D01*
X3013645Y2529599D01*
X3014730Y2529182D01*
X3015815D01*
X3016900Y2529599D01*
X3017830Y2530223D01*
X3018605Y2531057D01*
G01X3030230Y2529182D02*
X3024030D01*
Y2541682D01*
X3030230D01*
G01X3027750Y2535640D02*
X3024030D01*
G01X3051930Y2529182D02*
X3050690Y2529390D01*
X3049605Y2530223D01*
X3048675Y2531474D01*
X3048055Y2532932D01*
X3047745Y2534599D01*
Y2536265D01*
X3048055Y2537932D01*
X3048675Y2539390D01*
X3049605Y2540640D01*
X3050690Y2541474D01*
X3051930Y2541682D01*
X3053170Y2541474D01*
X3054255Y2540640D01*
X3055185Y2539390D01*
X3055805Y2537932D01*
X3056115Y2536265D01*
Y2534599D01*
X3055805Y2532932D01*
X3055185Y2531474D01*
X3054255Y2530223D01*
X3053170Y2529390D01*
X3051930Y2529182D01*
G01X3061385D02*
Y2541682D01*
X3067275D01*
G01X3065105Y2535640D02*
X3061385D01*
G01X3085100Y2529182D02*
Y2541682D01*
X3089130Y2531265D01*
X3093160Y2541682D01*
Y2529182D01*
G01X3098120Y2541682D02*
Y2532724D01*
X3098740Y2530848D01*
X3099980Y2529599D01*
X3101530Y2529182D01*
X3103080Y2529599D01*
X3104320Y2530848D01*
X3104940Y2532724D01*
Y2541682D01*
G01X3110675Y2530848D02*
X3111915Y2529807D01*
X3113310Y2529182D01*
X3114550D01*
X3115790Y2529807D01*
X3116720Y2530848D01*
X3117185Y2532307D01*
X3116875Y2533765D01*
X3116100Y2535015D01*
X3114705Y2535849D01*
X3112845Y2536265D01*
X3111760Y2537099D01*
X3111295Y2538557D01*
X3111605Y2540015D01*
X3112380Y2541057D01*
X3113465Y2541682D01*
X3114550D01*
X3115635Y2541265D01*
X3116565Y2540224D01*
G01X3126330Y2541682D02*
Y2529182D01*
G01X3122765Y2541682D02*
X3129895D01*
G01X3136715Y2533349D02*
X3140745D01*
G01X3147565Y2529182D02*
Y2541682D01*
X3154695Y2529182D01*
Y2541682D01*
G01X3163530Y2529182D02*
X3162290Y2529390D01*
X3161205Y2530223D01*
X3160275Y2531474D01*
X3159655Y2532932D01*
X3159345Y2534599D01*
Y2536265D01*
X3159655Y2537932D01*
X3160275Y2539390D01*
X3161205Y2540640D01*
X3162290Y2541474D01*
X3163530Y2541682D01*
X3164770Y2541474D01*
X3165855Y2540640D01*
X3166785Y2539390D01*
X3167405Y2537932D01*
X3167715Y2536265D01*
Y2534599D01*
X3167405Y2532932D01*
X3166785Y2531474D01*
X3165855Y2530223D01*
X3164770Y2529390D01*
X3163530Y2529182D01*
G01X3175930Y2541682D02*
Y2529182D01*
G01X3172365Y2541682D02*
X3179495D01*
G01X3186315Y2533349D02*
X3190345D01*
G01X3204140Y2540640D02*
X3203210Y2541265D01*
X3202125Y2541682D01*
X3200885D01*
X3199490Y2541057D01*
X3198405Y2540015D01*
X3197630Y2538765D01*
X3197010Y2536682D01*
X3196855Y2534807D01*
X3197165Y2532932D01*
X3197630Y2531682D01*
X3198560Y2530432D01*
X3199645Y2529599D01*
X3200730Y2529182D01*
X3201815D01*
X3202900Y2529599D01*
X3203830Y2530223D01*
X3204605Y2531057D01*
G01X3209720Y2541682D02*
Y2532724D01*
X3210340Y2530848D01*
X3211580Y2529599D01*
X3213130Y2529182D01*
X3214680Y2529599D01*
X3215920Y2530848D01*
X3216540Y2532724D01*
Y2541682D01*
G01X3225530D02*
Y2529182D01*
G01X3221965Y2541682D02*
X3229095D01*
G01X3235915Y2533349D02*
X3239945D01*
G01X3247230Y2541682D02*
Y2529182D01*
X3253430D01*
G01X3258855D02*
X3262730Y2541682D01*
X3266605Y2529182D01*
G01X3265210Y2533557D02*
X3260250D01*
G01X3275130Y2529182D02*
Y2534807D01*
X3272030Y2541682D01*
G01X3278230D02*
X3275130Y2534807D01*
G01X3290630Y2529182D02*
X3284430D01*
Y2541682D01*
X3290630D01*
G01X3288150Y2535640D02*
X3284430D01*
G01X3296830Y2529182D02*
Y2541682D01*
X3300705D01*
X3301945Y2541057D01*
X3302720Y2540224D01*
X3303030Y2538557D01*
X3302720Y2536890D01*
X3301790Y2535849D01*
X3300705Y2535224D01*
X3296830D01*
G01X3300705D02*
X3303030Y2529182D01*
G01X2789515Y2552099D02*
X2793545D01*
G01X2812300Y2547932D02*
Y2560432D01*
X2816330Y2550015D01*
X2820360Y2560432D01*
Y2547932D01*
G01X2824855D02*
X2828730Y2560432D01*
X2832605Y2547932D01*
G01X2831210Y2552307D02*
X2826250D01*
G01X2837875Y2547932D02*
X2844385Y2560432D01*
G01X2837875D02*
X2844385Y2547932D01*
G01X2848880Y2543765D02*
X2858180D01*
G01X2862520Y2547932D02*
Y2560432D01*
X2865620D01*
X2866860Y2559807D01*
X2867790Y2558974D01*
X2868565Y2557724D01*
X2869185Y2556265D01*
X2869340Y2554182D01*
X2869185Y2552099D01*
X2868565Y2550640D01*
X2867790Y2549390D01*
X2866860Y2548557D01*
X2865620Y2547932D01*
X2862520D01*
G01X2881430D02*
X2875230D01*
Y2560432D01*
X2881430D01*
G01X2878950Y2554390D02*
X2875230D01*
G01X2887630Y2547932D02*
Y2560432D01*
X2891350D01*
X2892590Y2559807D01*
X2893520Y2558349D01*
X2893830Y2556682D01*
X2893520Y2555015D01*
X2892745Y2553765D01*
X2891350Y2553140D01*
X2887630D01*
G01X2903130Y2560432D02*
Y2547932D01*
G01X2899565Y2560432D02*
X2906695D01*
G01X2912275Y2547932D02*
Y2560432D01*
G01X2918785D02*
Y2547932D01*
G01Y2554182D02*
X2912275D01*
G01X2927930Y2547515D02*
X2927620Y2547724D01*
Y2548140D01*
X2927930Y2548349D01*
X2928240Y2548140D01*
Y2547724D01*
X2927930Y2547515D01*
G01Y2553140D02*
X2927620Y2553349D01*
Y2553765D01*
X2927930Y2553974D01*
X2928240Y2553765D01*
Y2553349D01*
X2927930Y2553140D01*
G01X2949320Y2547932D02*
Y2560432D01*
X2952420D01*
X2953660Y2559807D01*
X2954590Y2558974D01*
X2955365Y2557724D01*
X2955985Y2556265D01*
X2956140Y2554182D01*
X2955985Y2552099D01*
X2955365Y2550640D01*
X2954590Y2549390D01*
X2953660Y2548557D01*
X2952420Y2547932D01*
X2949320D01*
G01X2968230D02*
X2962030D01*
Y2560432D01*
X2968230D01*
G01X2965750Y2554390D02*
X2962030D01*
G01X2974430Y2547932D02*
Y2560432D01*
X2978150D01*
X2979390Y2559807D01*
X2980320Y2558349D01*
X2980630Y2556682D01*
X2980320Y2555015D01*
X2979545Y2553765D01*
X2978150Y2553140D01*
X2974430D01*
G01X2989930Y2560432D02*
Y2547932D01*
G01X2986365Y2560432D02*
X2993495D01*
G01X2999075Y2547932D02*
Y2560432D01*
G01X3005585D02*
Y2547932D01*
G01Y2554182D02*
X2999075D01*
G01X3024185Y2547932D02*
Y2560432D01*
X3030075D01*
G01X3027905Y2554390D02*
X3024185D01*
G01X3036430Y2547932D02*
Y2560432D01*
X3040305D01*
X3041545Y2559807D01*
X3042320Y2558974D01*
X3042630Y2557307D01*
X3042320Y2555640D01*
X3041390Y2554599D01*
X3040305Y2553974D01*
X3036430D01*
G01X3040305D02*
X3042630Y2547932D01*
G01X3051930D02*
X3050690Y2548140D01*
X3049605Y2548973D01*
X3048675Y2550224D01*
X3048055Y2551682D01*
X3047745Y2553349D01*
Y2555015D01*
X3048055Y2556682D01*
X3048675Y2558140D01*
X3049605Y2559390D01*
X3050690Y2560224D01*
X3051930Y2560432D01*
X3053170Y2560224D01*
X3054255Y2559390D01*
X3055185Y2558140D01*
X3055805Y2556682D01*
X3056115Y2555015D01*
Y2553349D01*
X3055805Y2551682D01*
X3055185Y2550224D01*
X3054255Y2548973D01*
X3053170Y2548140D01*
X3051930Y2547932D01*
G01X3060300D02*
Y2560432D01*
X3064330Y2550015D01*
X3068360Y2560432D01*
Y2547932D01*
G01X3085875Y2549598D02*
X3087115Y2548557D01*
X3088510Y2547932D01*
X3089750D01*
X3090990Y2548557D01*
X3091920Y2549598D01*
X3092385Y2551057D01*
X3092075Y2552515D01*
X3091300Y2553765D01*
X3089905Y2554599D01*
X3088045Y2555015D01*
X3086960Y2555849D01*
X3086495Y2557307D01*
X3086805Y2558765D01*
X3087580Y2559807D01*
X3088665Y2560432D01*
X3089750D01*
X3090835Y2560015D01*
X3091765Y2558974D01*
G01X3101530Y2560432D02*
Y2547932D01*
G01X3097965Y2560432D02*
X3105095D01*
G01X3110055Y2547932D02*
X3113930Y2560432D01*
X3117805Y2547932D01*
G01X3116410Y2552307D02*
X3111450D01*
G01X3123230Y2547932D02*
Y2560432D01*
X3127105D01*
X3128345Y2559807D01*
X3129120Y2558974D01*
X3129430Y2557307D01*
X3129120Y2555640D01*
X3128190Y2554599D01*
X3127105Y2553974D01*
X3123230D01*
G01X3127105D02*
X3129430Y2547932D01*
G01X3138730Y2560432D02*
Y2547932D01*
G01X3135165Y2560432D02*
X3142295D01*
G01X3160430D02*
Y2547932D01*
X3166630D01*
G01X3172055D02*
X3175930Y2560432D01*
X3179805Y2547932D01*
G01X3178410Y2552307D02*
X3173450D01*
G01X3188330Y2547932D02*
Y2553557D01*
X3185230Y2560432D01*
G01X3191430D02*
X3188330Y2553557D01*
G01X3203830Y2547932D02*
X3197630D01*
Y2560432D01*
X3203830D01*
G01X3201350Y2554390D02*
X3197630D01*
G01X3210030Y2547932D02*
Y2560432D01*
X3213905D01*
X3215145Y2559807D01*
X3215920Y2558974D01*
X3216230Y2557307D01*
X3215920Y2555640D01*
X3214990Y2554599D01*
X3213905Y2553974D01*
X3210030D01*
G01X3213905D02*
X3216230Y2547932D01*
G01X3237930Y2560432D02*
Y2547932D01*
G01X3234365Y2560432D02*
X3241495D01*
G01X3250330Y2547932D02*
X3249090Y2548140D01*
X3248005Y2548973D01*
X3247075Y2550224D01*
X3246455Y2551682D01*
X3246145Y2553349D01*
Y2555015D01*
X3246455Y2556682D01*
X3247075Y2558140D01*
X3248005Y2559390D01*
X3249090Y2560224D01*
X3250330Y2560432D01*
X3251570Y2560224D01*
X3252655Y2559390D01*
X3253585Y2558140D01*
X3254205Y2556682D01*
X3254515Y2555015D01*
Y2553349D01*
X3254205Y2551682D01*
X3253585Y2550224D01*
X3252655Y2548973D01*
X3251570Y2548140D01*
X3250330Y2547932D01*
G01X3275130Y2560432D02*
Y2547932D01*
G01X3271565Y2560432D02*
X3278695D01*
G01X3284275Y2547932D02*
Y2560432D01*
G01X3290785D02*
Y2547932D01*
G01Y2554182D02*
X3284275D01*
G01X3303030Y2547932D02*
X3296830D01*
Y2560432D01*
X3303030D01*
G01X3300550Y2554390D02*
X3296830D01*
G01X2789515Y2570849D02*
X2793545D01*
G01X2812300Y2566682D02*
Y2579182D01*
X2816330Y2568765D01*
X2820360Y2579182D01*
Y2566682D01*
G01X2825165D02*
Y2579182D01*
X2832295Y2566682D01*
Y2579182D01*
G01X2844540Y2578140D02*
X2843610Y2578765D01*
X2842525Y2579182D01*
X2841285D01*
X2839890Y2578557D01*
X2838805Y2577515D01*
X2838030Y2576265D01*
X2837410Y2574182D01*
X2837255Y2572307D01*
X2837565Y2570432D01*
X2838030Y2569182D01*
X2838960Y2567932D01*
X2840045Y2567099D01*
X2841130Y2566682D01*
X2842215D01*
X2843300Y2567099D01*
X2844230Y2567723D01*
X2845005Y2568557D01*
G01X2848880Y2562515D02*
X2858180D01*
G01X2862830Y2579182D02*
Y2566682D01*
X2869030D01*
G01X2874455D02*
X2878330Y2579182D01*
X2882205Y2566682D01*
G01X2880810Y2571057D02*
X2875850D01*
G01X2890730Y2566682D02*
Y2572307D01*
X2887630Y2579182D01*
G01X2893830D02*
X2890730Y2572307D01*
G01X2906230Y2566682D02*
X2900030D01*
Y2579182D01*
X2906230D01*
G01X2903750Y2573140D02*
X2900030D01*
G01X2912430Y2566682D02*
Y2579182D01*
X2916305D01*
X2917545Y2578557D01*
X2918320Y2577724D01*
X2918630Y2576057D01*
X2918320Y2574390D01*
X2917390Y2573349D01*
X2916305Y2572724D01*
X2912430D01*
G01X2916305D02*
X2918630Y2566682D01*
G01X2927930Y2566265D02*
X2927620Y2566474D01*
Y2566890D01*
X2927930Y2567099D01*
X2928240Y2566890D01*
Y2566474D01*
X2927930Y2566265D01*
G01Y2571890D02*
X2927620Y2572099D01*
Y2572515D01*
X2927930Y2572724D01*
X2928240Y2572515D01*
Y2572099D01*
X2927930Y2571890D01*
G01X2948700Y2566682D02*
Y2579182D01*
X2952730Y2568765D01*
X2956760Y2579182D01*
Y2566682D01*
G01X2961720Y2579182D02*
Y2570224D01*
X2962340Y2568348D01*
X2963580Y2567099D01*
X2965130Y2566682D01*
X2966680Y2567099D01*
X2967920Y2568348D01*
X2968540Y2570224D01*
Y2579182D01*
G01X2974275Y2568348D02*
X2975515Y2567307D01*
X2976910Y2566682D01*
X2978150D01*
X2979390Y2567307D01*
X2980320Y2568348D01*
X2980785Y2569807D01*
X2980475Y2571265D01*
X2979700Y2572515D01*
X2978305Y2573349D01*
X2976445Y2573765D01*
X2975360Y2574599D01*
X2974895Y2576057D01*
X2975205Y2577515D01*
X2975980Y2578557D01*
X2977065Y2579182D01*
X2978150D01*
X2979235Y2578765D01*
X2980165Y2577724D01*
G01X2989930Y2579182D02*
Y2566682D01*
G01X2986365Y2579182D02*
X2993495D01*
G01X3000315Y2570849D02*
X3004345D01*
G01X3011165Y2566682D02*
Y2579182D01*
X3018295Y2566682D01*
Y2579182D01*
G01X3027130Y2566682D02*
X3025890Y2566890D01*
X3024805Y2567723D01*
X3023875Y2568974D01*
X3023255Y2570432D01*
X3022945Y2572099D01*
Y2573765D01*
X3023255Y2575432D01*
X3023875Y2576890D01*
X3024805Y2578140D01*
X3025890Y2578974D01*
X3027130Y2579182D01*
X3028370Y2578974D01*
X3029455Y2578140D01*
X3030385Y2576890D01*
X3031005Y2575432D01*
X3031315Y2573765D01*
Y2572099D01*
X3031005Y2570432D01*
X3030385Y2568974D01*
X3029455Y2567723D01*
X3028370Y2566890D01*
X3027130Y2566682D01*
G01X3039530Y2579182D02*
Y2566682D01*
G01X3035965Y2579182D02*
X3043095D01*
G01X3049915Y2570849D02*
X3053945D01*
G01X3067740Y2578140D02*
X3066810Y2578765D01*
X3065725Y2579182D01*
X3064485D01*
X3063090Y2578557D01*
X3062005Y2577515D01*
X3061230Y2576265D01*
X3060610Y2574182D01*
X3060455Y2572307D01*
X3060765Y2570432D01*
X3061230Y2569182D01*
X3062160Y2567932D01*
X3063245Y2567099D01*
X3064330Y2566682D01*
X3065415D01*
X3066500Y2567099D01*
X3067430Y2567723D01*
X3068205Y2568557D01*
G01X3073320Y2579182D02*
Y2570224D01*
X3073940Y2568348D01*
X3075180Y2567099D01*
X3076730Y2566682D01*
X3078280Y2567099D01*
X3079520Y2568348D01*
X3080140Y2570224D01*
Y2579182D01*
G01X3089130D02*
Y2566682D01*
G01X3085565Y2579182D02*
X3092695D01*
G01X3099515Y2570849D02*
X3103545D01*
G01X3110830Y2579182D02*
Y2566682D01*
X3117030D01*
G01X3122455D02*
X3126330Y2579182D01*
X3130205Y2566682D01*
G01X3128810Y2571057D02*
X3123850D01*
G01X3138730Y2566682D02*
Y2572307D01*
X3135630Y2579182D01*
G01X3141830D02*
X3138730Y2572307D01*
G01X3154230Y2566682D02*
X3148030D01*
Y2579182D01*
X3154230D01*
G01X3151750Y2573140D02*
X3148030D01*
G01X3160430Y2566682D02*
Y2579182D01*
X3164305D01*
X3165545Y2578557D01*
X3166320Y2577724D01*
X3166630Y2576057D01*
X3166320Y2574390D01*
X3165390Y2573349D01*
X3164305Y2572724D01*
X3160430D01*
G01X3164305D02*
X3166630Y2566682D01*
G01X2787965Y2585432D02*
Y2597932D01*
X2795095Y2585432D01*
Y2597932D01*
G01X2803930Y2585432D02*
X2802690Y2585640D01*
X2801605Y2586473D01*
X2800675Y2587724D01*
X2800055Y2589182D01*
X2799745Y2590849D01*
Y2592515D01*
X2800055Y2594182D01*
X2800675Y2595640D01*
X2801605Y2596890D01*
X2802690Y2597724D01*
X2803930Y2597932D01*
X2805170Y2597724D01*
X2806255Y2596890D01*
X2807185Y2595640D01*
X2807805Y2594182D01*
X2808115Y2592515D01*
Y2590849D01*
X2807805Y2589182D01*
X2807185Y2587724D01*
X2806255Y2586473D01*
X2805170Y2585640D01*
X2803930Y2585432D01*
G01X2816330Y2597932D02*
Y2585432D01*
G01X2812765Y2597932D02*
X2819895D01*
G01X2831830Y2585432D02*
X2825630D01*
Y2597932D01*
X2831830D01*
G01X2829350Y2591890D02*
X2825630D01*
G01X2837875Y2587098D02*
X2839115Y2586057D01*
X2840510Y2585432D01*
X2841750D01*
X2842990Y2586057D01*
X2843920Y2587098D01*
X2844385Y2588557D01*
X2844075Y2590015D01*
X2843300Y2591265D01*
X2841905Y2592099D01*
X2840045Y2592515D01*
X2838960Y2593349D01*
X2838495Y2594807D01*
X2838805Y2596265D01*
X2839580Y2597307D01*
X2840665Y2597932D01*
X2841750D01*
X2842835Y2597515D01*
X2843765Y2596474D01*
G01X2853530Y2585015D02*
X2853220Y2585224D01*
Y2585640D01*
X2853530Y2585849D01*
X2853840Y2585640D01*
Y2585224D01*
X2853530Y2585015D01*
G01Y2590640D02*
X2853220Y2590849D01*
Y2591265D01*
X2853530Y2591474D01*
X2853840Y2591265D01*
Y2590849D01*
X2853530Y2590640D01*
G01X2954966Y2762266D02*
X2955586Y2762891D01*
X2956051Y2763932D01*
X2956361Y2765391D01*
X2956051Y2766641D01*
X2955431Y2767474D01*
X2954346Y2768099D01*
X2950161D01*
Y2755599D01*
X2955276D01*
X2956361Y2756432D01*
X2956981Y2757682D01*
X2957291Y2759141D01*
X2956981Y2760599D01*
X2956051Y2761849D01*
X2954966Y2762266D01*
X2950161D01*
G01X2962251Y2755599D02*
X2966126Y2768099D01*
X2970001Y2755599D01*
G01X2968606Y2759974D02*
X2963646D01*
G01X2981936Y2767057D02*
X2981006Y2767682D01*
X2979921Y2768099D01*
X2978681D01*
X2977286Y2767474D01*
X2976201Y2766432D01*
X2975426Y2765182D01*
X2974806Y2763099D01*
X2974651Y2761224D01*
X2974961Y2759349D01*
X2975426Y2758099D01*
X2976356Y2756849D01*
X2977441Y2756016D01*
X2978526Y2755599D01*
X2979611D01*
X2980696Y2756016D01*
X2981626Y2756640D01*
X2982401Y2757474D01*
G01X2987516Y2755599D02*
Y2768099D01*
G01X2993406D02*
X2987516Y2760390D01*
G01X2994336Y2755599D02*
X2990151Y2763932D01*
G01X2999916Y2755599D02*
Y2768099D01*
X3003016D01*
X3004256Y2767474D01*
X3005186Y2766641D01*
X3005961Y2765391D01*
X3006581Y2763932D01*
X3006736Y2761849D01*
X3006581Y2759766D01*
X3005961Y2758307D01*
X3005186Y2757057D01*
X3004256Y2756224D01*
X3003016Y2755599D01*
X2999916D01*
G01X3012626D02*
Y2768099D01*
X3016501D01*
X3017741Y2767474D01*
X3018516Y2766641D01*
X3018826Y2764974D01*
X3018516Y2763307D01*
X3017586Y2762266D01*
X3016501Y2761641D01*
X3012626D01*
G01X3016501D02*
X3018826Y2755599D01*
G01X3026266Y2768099D02*
X3029986D01*
G01X3028126D02*
Y2755599D01*
G01X3026266D02*
X3029986D01*
G01X3037426Y2768099D02*
Y2755599D01*
X3043626D01*
G01X3049826Y2768099D02*
Y2755599D01*
X3056026D01*
G01X3074471Y2757265D02*
X3075711Y2756224D01*
X3077106Y2755599D01*
X3078346D01*
X3079586Y2756224D01*
X3080516Y2757265D01*
X3080981Y2758724D01*
X3080671Y2760182D01*
X3079896Y2761432D01*
X3078501Y2762266D01*
X3076641Y2762682D01*
X3075556Y2763516D01*
X3075091Y2764974D01*
X3075401Y2766432D01*
X3076176Y2767474D01*
X3077261Y2768099D01*
X3078346D01*
X3079431Y2767682D01*
X3080361Y2766641D01*
G01X3090126Y2768099D02*
Y2755599D01*
G01X3086561Y2768099D02*
X3093691D01*
G01X3099116D02*
Y2759141D01*
X3099736Y2757265D01*
X3100976Y2756016D01*
X3102526Y2755599D01*
X3104076Y2756016D01*
X3105316Y2757265D01*
X3105936Y2759141D01*
Y2768099D01*
G01X3116166Y2762266D02*
X3116786Y2762891D01*
X3117251Y2763932D01*
X3117561Y2765391D01*
X3117251Y2766641D01*
X3116631Y2767474D01*
X3115546Y2768099D01*
X3111361D01*
Y2755599D01*
X3116476D01*
X3117561Y2756432D01*
X3118181Y2757682D01*
X3118491Y2759141D01*
X3118181Y2760599D01*
X3117251Y2761849D01*
X3116166Y2762266D01*
X3111361D01*
G01X3136626Y2768099D02*
Y2755599D01*
X3142826D01*
G01X3155226D02*
X3149026D01*
Y2768099D01*
X3155226D01*
G01X3152746Y2762057D02*
X3149026D01*
G01X3160961Y2755599D02*
Y2768099D01*
X3168091Y2755599D01*
Y2768099D01*
G01X3177856Y2761849D02*
X3180956D01*
Y2758099D01*
X3180026Y2756849D01*
X3178941Y2756016D01*
X3177391Y2755599D01*
X3175841Y2756016D01*
X3174756Y2756849D01*
X3173826Y2758099D01*
X3173206Y2759557D01*
X3172896Y2761224D01*
Y2762682D01*
X3173206Y2763932D01*
X3173826Y2765391D01*
X3174756Y2766641D01*
X3175686Y2767474D01*
X3176926Y2768099D01*
X3178011D01*
X3179251Y2767682D01*
X3180181Y2766849D01*
G01X3189326Y2768099D02*
Y2755599D01*
G01X3185761Y2768099D02*
X3192891D01*
G01X3198471Y2755599D02*
Y2768099D01*
G01X3204981D02*
Y2755599D01*
G01Y2761849D02*
X3198471D01*
G01X3226526Y2768099D02*
Y2755599D01*
G01X3222961Y2768099D02*
X3230091D01*
G01X3238926Y2755599D02*
X3237686Y2755807D01*
X3236601Y2756640D01*
X3235671Y2757891D01*
X3235051Y2759349D01*
X3234741Y2761016D01*
Y2762682D01*
X3235051Y2764349D01*
X3235671Y2765807D01*
X3236601Y2767057D01*
X3237686Y2767891D01*
X3238926Y2768099D01*
X3240166Y2767891D01*
X3241251Y2767057D01*
X3242181Y2765807D01*
X3242801Y2764349D01*
X3243111Y2762682D01*
Y2761016D01*
X3242801Y2759349D01*
X3242181Y2757891D01*
X3241251Y2756640D01*
X3240166Y2755807D01*
X3238926Y2755599D01*
G01X3248226Y2768099D02*
Y2755599D01*
X3254426D01*
G01X3266826D02*
X3260626D01*
Y2768099D01*
X3266826D01*
G01X3264346Y2762057D02*
X3260626D01*
G01X3273026Y2755599D02*
Y2768099D01*
X3276901D01*
X3278141Y2767474D01*
X3278916Y2766641D01*
X3279226Y2764974D01*
X3278916Y2763307D01*
X3277986Y2762266D01*
X3276901Y2761641D01*
X3273026D01*
G01X3276901D02*
X3279226Y2755599D01*
G01X3284651D02*
X3288526Y2768099D01*
X3292401Y2755599D01*
G01X3291006Y2759974D02*
X3286046D01*
G01X3297361Y2755599D02*
Y2768099D01*
X3304491Y2755599D01*
Y2768099D01*
G01X3316736Y2767057D02*
X3315806Y2767682D01*
X3314721Y2768099D01*
X3313481D01*
X3312086Y2767474D01*
X3311001Y2766432D01*
X3310226Y2765182D01*
X3309606Y2763099D01*
X3309451Y2761224D01*
X3309761Y2759349D01*
X3310226Y2758099D01*
X3311156Y2756849D01*
X3312241Y2756016D01*
X3313326Y2755599D01*
X3314411D01*
X3315496Y2756016D01*
X3316426Y2756640D01*
X3317201Y2757474D01*
G01X3328826Y2755599D02*
X3322626D01*
Y2768099D01*
X3328826D01*
G01X3326346Y2762057D02*
X3322626D01*
G01X3350526Y2768099D02*
Y2755599D01*
G01X3346961Y2768099D02*
X3354091D01*
G01X3362926Y2755599D02*
X3361686Y2755807D01*
X3360601Y2756640D01*
X3359671Y2757891D01*
X3359051Y2759349D01*
X3358741Y2761016D01*
Y2762682D01*
X3359051Y2764349D01*
X3359671Y2765807D01*
X3360601Y2767057D01*
X3361686Y2767891D01*
X3362926Y2768099D01*
X3364166Y2767891D01*
X3365251Y2767057D01*
X3366181Y2765807D01*
X3366801Y2764349D01*
X3367111Y2762682D01*
Y2761016D01*
X3366801Y2759349D01*
X3366181Y2757891D01*
X3365251Y2756640D01*
X3364166Y2755807D01*
X3362926Y2755599D01*
G01X3388966Y2762266D02*
X3389586Y2762891D01*
X3390051Y2763932D01*
X3390361Y2765391D01*
X3390051Y2766641D01*
X3389431Y2767474D01*
X3388346Y2768099D01*
X3384161D01*
Y2755599D01*
X3389276D01*
X3390361Y2756432D01*
X3390981Y2757682D01*
X3391291Y2759141D01*
X3390981Y2760599D01*
X3390051Y2761849D01*
X3388966Y2762266D01*
X3384161D01*
G01X3403226Y2755599D02*
X3397026D01*
Y2768099D01*
X3403226D01*
G01X3400746Y2762057D02*
X3397026D01*
G01X3424616Y2755599D02*
X3424926Y2758307D01*
X3425391Y2760599D01*
X3426011Y2762682D01*
X3426786Y2764974D01*
X3428026Y2768099D01*
X3421826D01*
G01X3448021Y2759766D02*
X3451741D01*
G01X3449726Y2762474D02*
Y2757057D01*
G01X3459336Y2755182D02*
X3464916Y2768099D01*
G01X3472511Y2759766D02*
X3476541D01*
G01X3483516Y2757474D02*
X3484446Y2756432D01*
X3485531Y2755807D01*
X3486926Y2755599D01*
X3488321Y2756016D01*
X3489406Y2756849D01*
X3490181Y2758307D01*
X3490336Y2759974D01*
X3490026Y2761641D01*
X3489251Y2762682D01*
X3488166Y2763516D01*
X3487081Y2763724D01*
X3485996Y2763516D01*
X3484601Y2762682D01*
X3485066Y2768099D01*
X3489251D01*
G01X3507696Y2755599D02*
Y2768099D01*
X3511726Y2757682D01*
X3515756Y2768099D01*
Y2755599D01*
G01X3522266Y2768099D02*
X3525986D01*
G01X3524126D02*
Y2755599D01*
G01X3522266D02*
X3525986D01*
G01X3533426Y2768099D02*
Y2755599D01*
X3539626D01*
G01X3545671Y2757265D02*
X3546911Y2756224D01*
X3548306Y2755599D01*
X3549546D01*
X3550786Y2756224D01*
X3551716Y2757265D01*
X3552181Y2758724D01*
X3551871Y2760182D01*
X3551096Y2761432D01*
X3549701Y2762266D01*
X3547841Y2762682D01*
X3546756Y2763516D01*
X3546291Y2764974D01*
X3546601Y2766432D01*
X3547376Y2767474D01*
X3548461Y2768099D01*
X3549546D01*
X3550631Y2767682D01*
X3551561Y2766641D01*
G01X2790511Y2778516D02*
X2794541D01*
G01X2813296Y2774349D02*
Y2786849D01*
X2817326Y2776432D01*
X2821356Y2786849D01*
Y2774349D01*
G01X2826781D02*
Y2786849D01*
X2832671D01*
G01X2830501Y2780807D02*
X2826781D01*
G01X2843056Y2780599D02*
X2846156D01*
Y2776849D01*
X2845226Y2775599D01*
X2844141Y2774766D01*
X2842591Y2774349D01*
X2841041Y2774766D01*
X2839956Y2775599D01*
X2839026Y2776849D01*
X2838406Y2778307D01*
X2838096Y2779974D01*
Y2781432D01*
X2838406Y2782682D01*
X2839026Y2784141D01*
X2839956Y2785391D01*
X2840886Y2786224D01*
X2842126Y2786849D01*
X2843211D01*
X2844451Y2786432D01*
X2845381Y2785599D01*
G01X2849876Y2770182D02*
X2859176D01*
G01X2863671Y2776015D02*
X2864911Y2774974D01*
X2866306Y2774349D01*
X2867546D01*
X2868786Y2774974D01*
X2869716Y2776015D01*
X2870181Y2777474D01*
X2869871Y2778932D01*
X2869096Y2780182D01*
X2867701Y2781016D01*
X2865841Y2781432D01*
X2864756Y2782266D01*
X2864291Y2783724D01*
X2864601Y2785182D01*
X2865376Y2786224D01*
X2866461Y2786849D01*
X2867546D01*
X2868631Y2786432D01*
X2869561Y2785391D01*
G01X2879326Y2786849D02*
Y2774349D01*
G01X2875761Y2786849D02*
X2882891D01*
G01X2888316D02*
Y2777891D01*
X2888936Y2776015D01*
X2890176Y2774766D01*
X2891726Y2774349D01*
X2893276Y2774766D01*
X2894516Y2776015D01*
X2895136Y2777891D01*
Y2786849D01*
G01X2905366Y2781016D02*
X2905986Y2781641D01*
X2906451Y2782682D01*
X2906761Y2784141D01*
X2906451Y2785391D01*
X2905831Y2786224D01*
X2904746Y2786849D01*
X2900561D01*
Y2774349D01*
X2905676D01*
X2906761Y2775182D01*
X2907381Y2776432D01*
X2907691Y2777891D01*
X2907381Y2779349D01*
X2906451Y2780599D01*
X2905366Y2781016D01*
X2900561D01*
G01X2928926Y2773932D02*
X2928616Y2774141D01*
Y2774557D01*
X2928926Y2774766D01*
X2929236Y2774557D01*
Y2774141D01*
X2928926Y2773932D01*
G01Y2779557D02*
X2928616Y2779766D01*
Y2780182D01*
X2928926Y2780391D01*
X2929236Y2780182D01*
Y2779766D01*
X2928926Y2779557D01*
G01X2949696Y2774349D02*
Y2786849D01*
X2953726Y2776432D01*
X2957756Y2786849D01*
Y2774349D01*
G01X2962251D02*
X2966126Y2786849D01*
X2970001Y2774349D01*
G01X2968606Y2778724D02*
X2963646D01*
G01X2974961Y2774349D02*
Y2786849D01*
X2982091Y2774349D01*
Y2786849D01*
G01X2987516D02*
Y2777891D01*
X2988136Y2776015D01*
X2989376Y2774766D01*
X2990926Y2774349D01*
X2992476Y2774766D01*
X2993716Y2776015D01*
X2994336Y2777891D01*
Y2786849D01*
G01X3000381Y2774349D02*
Y2786849D01*
X3006271D01*
G01X3004101Y2780807D02*
X3000381D01*
G01X3011851Y2774349D02*
X3015726Y2786849D01*
X3019601Y2774349D01*
G01X3018206Y2778724D02*
X3013246D01*
G01X3031536Y2785807D02*
X3030606Y2786432D01*
X3029521Y2786849D01*
X3028281D01*
X3026886Y2786224D01*
X3025801Y2785182D01*
X3025026Y2783932D01*
X3024406Y2781849D01*
X3024251Y2779974D01*
X3024561Y2778099D01*
X3025026Y2776849D01*
X3025956Y2775599D01*
X3027041Y2774766D01*
X3028126Y2774349D01*
X3029211D01*
X3030296Y2774766D01*
X3031226Y2775390D01*
X3032001Y2776224D01*
G01X3040526Y2786849D02*
Y2774349D01*
G01X3036961Y2786849D02*
X3044091D01*
G01X3049516D02*
Y2777891D01*
X3050136Y2776015D01*
X3051376Y2774766D01*
X3052926Y2774349D01*
X3054476Y2774766D01*
X3055716Y2776015D01*
X3056336Y2777891D01*
Y2786849D01*
G01X3062226Y2774349D02*
Y2786849D01*
X3066101D01*
X3067341Y2786224D01*
X3068116Y2785391D01*
X3068426Y2783724D01*
X3068116Y2782057D01*
X3067186Y2781016D01*
X3066101Y2780391D01*
X3062226D01*
G01X3066101D02*
X3068426Y2774349D01*
G01X3075866Y2786849D02*
X3079586D01*
G01X3077726D02*
Y2774349D01*
G01X3075866D02*
X3079586D01*
G01X3086561D02*
Y2786849D01*
X3093691Y2774349D01*
Y2786849D01*
G01X3103456Y2780599D02*
X3106556D01*
Y2776849D01*
X3105626Y2775599D01*
X3104541Y2774766D01*
X3102991Y2774349D01*
X3101441Y2774766D01*
X3100356Y2775599D01*
X3099426Y2776849D01*
X3098806Y2778307D01*
X3098496Y2779974D01*
Y2781432D01*
X3098806Y2782682D01*
X3099426Y2784141D01*
X3100356Y2785391D01*
X3101286Y2786224D01*
X3102526Y2786849D01*
X3103611D01*
X3104851Y2786432D01*
X3105781Y2785599D01*
G01X3124071Y2776015D02*
X3125311Y2774974D01*
X3126706Y2774349D01*
X3127946D01*
X3129186Y2774974D01*
X3130116Y2776015D01*
X3130581Y2777474D01*
X3130271Y2778932D01*
X3129496Y2780182D01*
X3128101Y2781016D01*
X3126241Y2781432D01*
X3125156Y2782266D01*
X3124691Y2783724D01*
X3125001Y2785182D01*
X3125776Y2786224D01*
X3126861Y2786849D01*
X3127946D01*
X3129031Y2786432D01*
X3129961Y2785391D01*
G01X3139726Y2786849D02*
Y2774349D01*
G01X3136161Y2786849D02*
X3143291D01*
G01X3148716D02*
Y2777891D01*
X3149336Y2776015D01*
X3150576Y2774766D01*
X3152126Y2774349D01*
X3153676Y2774766D01*
X3154916Y2776015D01*
X3155536Y2777891D01*
Y2786849D01*
G01X3165766Y2781016D02*
X3166386Y2781641D01*
X3166851Y2782682D01*
X3167161Y2784141D01*
X3166851Y2785391D01*
X3166231Y2786224D01*
X3165146Y2786849D01*
X3160961D01*
Y2774349D01*
X3166076D01*
X3167161Y2775182D01*
X3167781Y2776432D01*
X3168091Y2777891D01*
X3167781Y2779349D01*
X3166851Y2780599D01*
X3165766Y2781016D01*
X3160961D01*
G01X3186226Y2786849D02*
Y2774349D01*
X3192426D01*
G01X3204826D02*
X3198626D01*
Y2786849D01*
X3204826D01*
G01X3202346Y2780807D02*
X3198626D01*
G01X3210561Y2774349D02*
Y2786849D01*
X3217691Y2774349D01*
Y2786849D01*
G01X3227456Y2780599D02*
X3230556D01*
Y2776849D01*
X3229626Y2775599D01*
X3228541Y2774766D01*
X3226991Y2774349D01*
X3225441Y2774766D01*
X3224356Y2775599D01*
X3223426Y2776849D01*
X3222806Y2778307D01*
X3222496Y2779974D01*
Y2781432D01*
X3222806Y2782682D01*
X3223426Y2784141D01*
X3224356Y2785391D01*
X3225286Y2786224D01*
X3226526Y2786849D01*
X3227611D01*
X3228851Y2786432D01*
X3229781Y2785599D01*
G01X3238926Y2786849D02*
Y2774349D01*
G01X3235361Y2786849D02*
X3242491D01*
G01X3248071Y2774349D02*
Y2786849D01*
G01X3254581D02*
Y2774349D01*
G01Y2780599D02*
X3248071D01*
G01X2950471Y2794765D02*
X2951711Y2793724D01*
X2953106Y2793099D01*
X2954346D01*
X2955586Y2793724D01*
X2956516Y2794765D01*
X2956981Y2796224D01*
X2956671Y2797682D01*
X2955896Y2798932D01*
X2954501Y2799766D01*
X2952641Y2800182D01*
X2951556Y2801016D01*
X2951091Y2802474D01*
X2951401Y2803932D01*
X2952176Y2804974D01*
X2953261Y2805599D01*
X2954346D01*
X2955431Y2805182D01*
X2956361Y2804141D01*
G01X2962716Y2805599D02*
Y2796641D01*
X2963336Y2794765D01*
X2964576Y2793516D01*
X2966126Y2793099D01*
X2967676Y2793516D01*
X2968916Y2794765D01*
X2969536Y2796641D01*
Y2805599D01*
G01X2975426Y2793099D02*
Y2805599D01*
X2979301D01*
X2980541Y2804974D01*
X2981316Y2804141D01*
X2981626Y2802474D01*
X2981316Y2800807D01*
X2980386Y2799766D01*
X2979301Y2799141D01*
X2975426D01*
G01X2979301D02*
X2981626Y2793099D01*
G01X2987981D02*
Y2805599D01*
X2993871D01*
G01X2991701Y2799557D02*
X2987981D01*
G01X2999451Y2793099D02*
X3003326Y2805599D01*
X3007201Y2793099D01*
G01X3005806Y2797474D02*
X3000846D01*
G01X3019136Y2804557D02*
X3018206Y2805182D01*
X3017121Y2805599D01*
X3015881D01*
X3014486Y2804974D01*
X3013401Y2803932D01*
X3012626Y2802682D01*
X3012006Y2800599D01*
X3011851Y2798724D01*
X3012161Y2796849D01*
X3012626Y2795599D01*
X3013556Y2794349D01*
X3014641Y2793516D01*
X3015726Y2793099D01*
X3016811D01*
X3017896Y2793516D01*
X3018826Y2794140D01*
X3019601Y2794974D01*
G01X3031226Y2793099D02*
X3025026D01*
Y2805599D01*
X3031226D01*
G01X3028746Y2799557D02*
X3025026D01*
G01X3052926Y2793099D02*
X3051686Y2793307D01*
X3050601Y2794140D01*
X3049671Y2795391D01*
X3049051Y2796849D01*
X3048741Y2798516D01*
Y2800182D01*
X3049051Y2801849D01*
X3049671Y2803307D01*
X3050601Y2804557D01*
X3051686Y2805391D01*
X3052926Y2805599D01*
X3054166Y2805391D01*
X3055251Y2804557D01*
X3056181Y2803307D01*
X3056801Y2801849D01*
X3057111Y2800182D01*
Y2798516D01*
X3056801Y2796849D01*
X3056181Y2795391D01*
X3055251Y2794140D01*
X3054166Y2793307D01*
X3052926Y2793099D01*
G01X3062381D02*
Y2805599D01*
X3068271D01*
G01X3066101Y2799557D02*
X3062381D01*
G01X3086096Y2793099D02*
Y2805599D01*
X3090126Y2795182D01*
X3094156Y2805599D01*
Y2793099D01*
G01X3099116Y2805599D02*
Y2796641D01*
X3099736Y2794765D01*
X3100976Y2793516D01*
X3102526Y2793099D01*
X3104076Y2793516D01*
X3105316Y2794765D01*
X3105936Y2796641D01*
Y2805599D01*
G01X3111671Y2794765D02*
X3112911Y2793724D01*
X3114306Y2793099D01*
X3115546D01*
X3116786Y2793724D01*
X3117716Y2794765D01*
X3118181Y2796224D01*
X3117871Y2797682D01*
X3117096Y2798932D01*
X3115701Y2799766D01*
X3113841Y2800182D01*
X3112756Y2801016D01*
X3112291Y2802474D01*
X3112601Y2803932D01*
X3113376Y2804974D01*
X3114461Y2805599D01*
X3115546D01*
X3116631Y2805182D01*
X3117561Y2804141D01*
G01X3127326Y2805599D02*
Y2793099D01*
G01X3123761Y2805599D02*
X3130891D01*
G01X3137711Y2797266D02*
X3141741D01*
G01X3148561Y2793099D02*
Y2805599D01*
X3155691Y2793099D01*
Y2805599D01*
G01X3164526Y2793099D02*
X3163286Y2793307D01*
X3162201Y2794140D01*
X3161271Y2795391D01*
X3160651Y2796849D01*
X3160341Y2798516D01*
Y2800182D01*
X3160651Y2801849D01*
X3161271Y2803307D01*
X3162201Y2804557D01*
X3163286Y2805391D01*
X3164526Y2805599D01*
X3165766Y2805391D01*
X3166851Y2804557D01*
X3167781Y2803307D01*
X3168401Y2801849D01*
X3168711Y2800182D01*
Y2798516D01*
X3168401Y2796849D01*
X3167781Y2795391D01*
X3166851Y2794140D01*
X3165766Y2793307D01*
X3164526Y2793099D01*
G01X3176926Y2805599D02*
Y2793099D01*
G01X3173361Y2805599D02*
X3180491D01*
G01X3187311Y2797266D02*
X3191341D01*
G01X3205136Y2804557D02*
X3204206Y2805182D01*
X3203121Y2805599D01*
X3201881D01*
X3200486Y2804974D01*
X3199401Y2803932D01*
X3198626Y2802682D01*
X3198006Y2800599D01*
X3197851Y2798724D01*
X3198161Y2796849D01*
X3198626Y2795599D01*
X3199556Y2794349D01*
X3200641Y2793516D01*
X3201726Y2793099D01*
X3202811D01*
X3203896Y2793516D01*
X3204826Y2794140D01*
X3205601Y2794974D01*
G01X3210716Y2805599D02*
Y2796641D01*
X3211336Y2794765D01*
X3212576Y2793516D01*
X3214126Y2793099D01*
X3215676Y2793516D01*
X3216916Y2794765D01*
X3217536Y2796641D01*
Y2805599D01*
G01X3226526D02*
Y2793099D01*
G01X3222961Y2805599D02*
X3230091D01*
G01X3236911Y2797266D02*
X3240941D01*
G01X3248226Y2805599D02*
Y2793099D01*
X3254426D01*
G01X3259851D02*
X3263726Y2805599D01*
X3267601Y2793099D01*
G01X3266206Y2797474D02*
X3261246D01*
G01X3276126Y2793099D02*
Y2798724D01*
X3273026Y2805599D01*
G01X3279226D02*
X3276126Y2798724D01*
G01X3291626Y2793099D02*
X3285426D01*
Y2805599D01*
X3291626D01*
G01X3289146Y2799557D02*
X3285426D01*
G01X3297826Y2793099D02*
Y2805599D01*
X3301701D01*
X3302941Y2804974D01*
X3303716Y2804141D01*
X3304026Y2802474D01*
X3303716Y2800807D01*
X3302786Y2799766D01*
X3301701Y2799141D01*
X3297826D01*
G01X3301701D02*
X3304026Y2793099D01*
G01X2790511Y2816016D02*
X2794541D01*
G01X2813296Y2811849D02*
Y2824349D01*
X2817326Y2813932D01*
X2821356Y2824349D01*
Y2811849D01*
G01X2825851D02*
X2829726Y2824349D01*
X2833601Y2811849D01*
G01X2832206Y2816224D02*
X2827246D01*
G01X2838871Y2811849D02*
X2845381Y2824349D01*
G01X2838871D02*
X2845381Y2811849D01*
G01X2849876Y2807682D02*
X2859176D01*
G01X2863516Y2811849D02*
Y2824349D01*
X2866616D01*
X2867856Y2823724D01*
X2868786Y2822891D01*
X2869561Y2821641D01*
X2870181Y2820182D01*
X2870336Y2818099D01*
X2870181Y2816016D01*
X2869561Y2814557D01*
X2868786Y2813307D01*
X2867856Y2812474D01*
X2866616Y2811849D01*
X2863516D01*
G01X2882426D02*
X2876226D01*
Y2824349D01*
X2882426D01*
G01X2879946Y2818307D02*
X2876226D01*
G01X2888626Y2811849D02*
Y2824349D01*
X2892346D01*
X2893586Y2823724D01*
X2894516Y2822266D01*
X2894826Y2820599D01*
X2894516Y2818932D01*
X2893741Y2817682D01*
X2892346Y2817057D01*
X2888626D01*
G01X2904126Y2824349D02*
Y2811849D01*
G01X2900561Y2824349D02*
X2907691D01*
G01X2913271Y2811849D02*
Y2824349D01*
G01X2919781D02*
Y2811849D01*
G01Y2818099D02*
X2913271D01*
G01X2928926Y2811432D02*
X2928616Y2811641D01*
Y2812057D01*
X2928926Y2812266D01*
X2929236Y2812057D01*
Y2811641D01*
X2928926Y2811432D01*
G01Y2817057D02*
X2928616Y2817266D01*
Y2817682D01*
X2928926Y2817891D01*
X2929236Y2817682D01*
Y2817266D01*
X2928926Y2817057D01*
G01X2950316Y2811849D02*
Y2824349D01*
X2953416D01*
X2954656Y2823724D01*
X2955586Y2822891D01*
X2956361Y2821641D01*
X2956981Y2820182D01*
X2957136Y2818099D01*
X2956981Y2816016D01*
X2956361Y2814557D01*
X2955586Y2813307D01*
X2954656Y2812474D01*
X2953416Y2811849D01*
X2950316D01*
G01X2969226D02*
X2963026D01*
Y2824349D01*
X2969226D01*
G01X2966746Y2818307D02*
X2963026D01*
G01X2975426Y2811849D02*
Y2824349D01*
X2979146D01*
X2980386Y2823724D01*
X2981316Y2822266D01*
X2981626Y2820599D01*
X2981316Y2818932D01*
X2980541Y2817682D01*
X2979146Y2817057D01*
X2975426D01*
G01X2990926Y2824349D02*
Y2811849D01*
G01X2987361Y2824349D02*
X2994491D01*
G01X3000071Y2811849D02*
Y2824349D01*
G01X3006581D02*
Y2811849D01*
G01Y2818099D02*
X3000071D01*
G01X3025181Y2811849D02*
Y2824349D01*
X3031071D01*
G01X3028901Y2818307D02*
X3025181D01*
G01X3037426Y2811849D02*
Y2824349D01*
X3041301D01*
X3042541Y2823724D01*
X3043316Y2822891D01*
X3043626Y2821224D01*
X3043316Y2819557D01*
X3042386Y2818516D01*
X3041301Y2817891D01*
X3037426D01*
G01X3041301D02*
X3043626Y2811849D01*
G01X3052926D02*
X3051686Y2812057D01*
X3050601Y2812890D01*
X3049671Y2814141D01*
X3049051Y2815599D01*
X3048741Y2817266D01*
Y2818932D01*
X3049051Y2820599D01*
X3049671Y2822057D01*
X3050601Y2823307D01*
X3051686Y2824141D01*
X3052926Y2824349D01*
X3054166Y2824141D01*
X3055251Y2823307D01*
X3056181Y2822057D01*
X3056801Y2820599D01*
X3057111Y2818932D01*
Y2817266D01*
X3056801Y2815599D01*
X3056181Y2814141D01*
X3055251Y2812890D01*
X3054166Y2812057D01*
X3052926Y2811849D01*
G01X3061296D02*
Y2824349D01*
X3065326Y2813932D01*
X3069356Y2824349D01*
Y2811849D01*
G01X3086871Y2813515D02*
X3088111Y2812474D01*
X3089506Y2811849D01*
X3090746D01*
X3091986Y2812474D01*
X3092916Y2813515D01*
X3093381Y2814974D01*
X3093071Y2816432D01*
X3092296Y2817682D01*
X3090901Y2818516D01*
X3089041Y2818932D01*
X3087956Y2819766D01*
X3087491Y2821224D01*
X3087801Y2822682D01*
X3088576Y2823724D01*
X3089661Y2824349D01*
X3090746D01*
X3091831Y2823932D01*
X3092761Y2822891D01*
G01X3102526Y2824349D02*
Y2811849D01*
G01X3098961Y2824349D02*
X3106091D01*
G01X3111051Y2811849D02*
X3114926Y2824349D01*
X3118801Y2811849D01*
G01X3117406Y2816224D02*
X3112446D01*
G01X3124226Y2811849D02*
Y2824349D01*
X3128101D01*
X3129341Y2823724D01*
X3130116Y2822891D01*
X3130426Y2821224D01*
X3130116Y2819557D01*
X3129186Y2818516D01*
X3128101Y2817891D01*
X3124226D01*
G01X3128101D02*
X3130426Y2811849D01*
G01X3139726Y2824349D02*
Y2811849D01*
G01X3136161Y2824349D02*
X3143291D01*
G01X3161426D02*
Y2811849D01*
X3167626D01*
G01X3173051D02*
X3176926Y2824349D01*
X3180801Y2811849D01*
G01X3179406Y2816224D02*
X3174446D01*
G01X3189326Y2811849D02*
Y2817474D01*
X3186226Y2824349D01*
G01X3192426D02*
X3189326Y2817474D01*
G01X3204826Y2811849D02*
X3198626D01*
Y2824349D01*
X3204826D01*
G01X3202346Y2818307D02*
X3198626D01*
G01X3211026Y2811849D02*
Y2824349D01*
X3214901D01*
X3216141Y2823724D01*
X3216916Y2822891D01*
X3217226Y2821224D01*
X3216916Y2819557D01*
X3215986Y2818516D01*
X3214901Y2817891D01*
X3211026D01*
G01X3214901D02*
X3217226Y2811849D01*
G01X3238926Y2824349D02*
Y2811849D01*
G01X3235361Y2824349D02*
X3242491D01*
G01X3251326Y2811849D02*
X3250086Y2812057D01*
X3249001Y2812890D01*
X3248071Y2814141D01*
X3247451Y2815599D01*
X3247141Y2817266D01*
Y2818932D01*
X3247451Y2820599D01*
X3248071Y2822057D01*
X3249001Y2823307D01*
X3250086Y2824141D01*
X3251326Y2824349D01*
X3252566Y2824141D01*
X3253651Y2823307D01*
X3254581Y2822057D01*
X3255201Y2820599D01*
X3255511Y2818932D01*
Y2817266D01*
X3255201Y2815599D01*
X3254581Y2814141D01*
X3253651Y2812890D01*
X3252566Y2812057D01*
X3251326Y2811849D01*
G01X3276126Y2824349D02*
Y2811849D01*
G01X3272561Y2824349D02*
X3279691D01*
G01X3285271Y2811849D02*
Y2824349D01*
G01X3291781D02*
Y2811849D01*
G01Y2818099D02*
X3285271D01*
G01X3304026Y2811849D02*
X3297826D01*
Y2824349D01*
X3304026D01*
G01X3301546Y2818307D02*
X3297826D01*
G01X2790511Y2834766D02*
X2794541D01*
G01X2813296Y2830599D02*
Y2843099D01*
X2817326Y2832682D01*
X2821356Y2843099D01*
Y2830599D01*
G01X2826161D02*
Y2843099D01*
X2833291Y2830599D01*
Y2843099D01*
G01X2845536Y2842057D02*
X2844606Y2842682D01*
X2843521Y2843099D01*
X2842281D01*
X2840886Y2842474D01*
X2839801Y2841432D01*
X2839026Y2840182D01*
X2838406Y2838099D01*
X2838251Y2836224D01*
X2838561Y2834349D01*
X2839026Y2833099D01*
X2839956Y2831849D01*
X2841041Y2831016D01*
X2842126Y2830599D01*
X2843211D01*
X2844296Y2831016D01*
X2845226Y2831640D01*
X2846001Y2832474D01*
G01X2849876Y2826432D02*
X2859176D01*
G01X2863826Y2843099D02*
Y2830599D01*
X2870026D01*
G01X2875451D02*
X2879326Y2843099D01*
X2883201Y2830599D01*
G01X2881806Y2834974D02*
X2876846D01*
G01X2891726Y2830599D02*
Y2836224D01*
X2888626Y2843099D01*
G01X2894826D02*
X2891726Y2836224D01*
G01X2907226Y2830599D02*
X2901026D01*
Y2843099D01*
X2907226D01*
G01X2904746Y2837057D02*
X2901026D01*
G01X2913426Y2830599D02*
Y2843099D01*
X2917301D01*
X2918541Y2842474D01*
X2919316Y2841641D01*
X2919626Y2839974D01*
X2919316Y2838307D01*
X2918386Y2837266D01*
X2917301Y2836641D01*
X2913426D01*
G01X2917301D02*
X2919626Y2830599D01*
G01X2928926Y2830182D02*
X2928616Y2830391D01*
Y2830807D01*
X2928926Y2831016D01*
X2929236Y2830807D01*
Y2830391D01*
X2928926Y2830182D01*
G01Y2835807D02*
X2928616Y2836016D01*
Y2836432D01*
X2928926Y2836641D01*
X2929236Y2836432D01*
Y2836016D01*
X2928926Y2835807D01*
G01X2949696Y2830599D02*
Y2843099D01*
X2953726Y2832682D01*
X2957756Y2843099D01*
Y2830599D01*
G01X2962716Y2843099D02*
Y2834141D01*
X2963336Y2832265D01*
X2964576Y2831016D01*
X2966126Y2830599D01*
X2967676Y2831016D01*
X2968916Y2832265D01*
X2969536Y2834141D01*
Y2843099D01*
G01X2975271Y2832265D02*
X2976511Y2831224D01*
X2977906Y2830599D01*
X2979146D01*
X2980386Y2831224D01*
X2981316Y2832265D01*
X2981781Y2833724D01*
X2981471Y2835182D01*
X2980696Y2836432D01*
X2979301Y2837266D01*
X2977441Y2837682D01*
X2976356Y2838516D01*
X2975891Y2839974D01*
X2976201Y2841432D01*
X2976976Y2842474D01*
X2978061Y2843099D01*
X2979146D01*
X2980231Y2842682D01*
X2981161Y2841641D01*
G01X2990926Y2843099D02*
Y2830599D01*
G01X2987361Y2843099D02*
X2994491D01*
G01X3001311Y2834766D02*
X3005341D01*
G01X3012161Y2830599D02*
Y2843099D01*
X3019291Y2830599D01*
Y2843099D01*
G01X3028126Y2830599D02*
X3026886Y2830807D01*
X3025801Y2831640D01*
X3024871Y2832891D01*
X3024251Y2834349D01*
X3023941Y2836016D01*
Y2837682D01*
X3024251Y2839349D01*
X3024871Y2840807D01*
X3025801Y2842057D01*
X3026886Y2842891D01*
X3028126Y2843099D01*
X3029366Y2842891D01*
X3030451Y2842057D01*
X3031381Y2840807D01*
X3032001Y2839349D01*
X3032311Y2837682D01*
Y2836016D01*
X3032001Y2834349D01*
X3031381Y2832891D01*
X3030451Y2831640D01*
X3029366Y2830807D01*
X3028126Y2830599D01*
G01X3040526Y2843099D02*
Y2830599D01*
G01X3036961Y2843099D02*
X3044091D01*
G01X3050911Y2834766D02*
X3054941D01*
G01X3068736Y2842057D02*
X3067806Y2842682D01*
X3066721Y2843099D01*
X3065481D01*
X3064086Y2842474D01*
X3063001Y2841432D01*
X3062226Y2840182D01*
X3061606Y2838099D01*
X3061451Y2836224D01*
X3061761Y2834349D01*
X3062226Y2833099D01*
X3063156Y2831849D01*
X3064241Y2831016D01*
X3065326Y2830599D01*
X3066411D01*
X3067496Y2831016D01*
X3068426Y2831640D01*
X3069201Y2832474D01*
G01X3074316Y2843099D02*
Y2834141D01*
X3074936Y2832265D01*
X3076176Y2831016D01*
X3077726Y2830599D01*
X3079276Y2831016D01*
X3080516Y2832265D01*
X3081136Y2834141D01*
Y2843099D01*
G01X3090126D02*
Y2830599D01*
G01X3086561Y2843099D02*
X3093691D01*
G01X3100511Y2834766D02*
X3104541D01*
G01X3111826Y2843099D02*
Y2830599D01*
X3118026D01*
G01X3123451D02*
X3127326Y2843099D01*
X3131201Y2830599D01*
G01X3129806Y2834974D02*
X3124846D01*
G01X3139726Y2830599D02*
Y2836224D01*
X3136626Y2843099D01*
G01X3142826D02*
X3139726Y2836224D01*
G01X3155226Y2830599D02*
X3149026D01*
Y2843099D01*
X3155226D01*
G01X3152746Y2837057D02*
X3149026D01*
G01X3161426Y2830599D02*
Y2843099D01*
X3165301D01*
X3166541Y2842474D01*
X3167316Y2841641D01*
X3167626Y2839974D01*
X3167316Y2838307D01*
X3166386Y2837266D01*
X3165301Y2836641D01*
X3161426D01*
G01X3165301D02*
X3167626Y2830599D01*
G01X2788961Y2849349D02*
Y2861849D01*
X2796091Y2849349D01*
Y2861849D01*
G01X2804926Y2849349D02*
X2803686Y2849557D01*
X2802601Y2850390D01*
X2801671Y2851641D01*
X2801051Y2853099D01*
X2800741Y2854766D01*
Y2856432D01*
X2801051Y2858099D01*
X2801671Y2859557D01*
X2802601Y2860807D01*
X2803686Y2861641D01*
X2804926Y2861849D01*
X2806166Y2861641D01*
X2807251Y2860807D01*
X2808181Y2859557D01*
X2808801Y2858099D01*
X2809111Y2856432D01*
Y2854766D01*
X2808801Y2853099D01*
X2808181Y2851641D01*
X2807251Y2850390D01*
X2806166Y2849557D01*
X2804926Y2849349D01*
G01X2817326Y2861849D02*
Y2849349D01*
G01X2813761Y2861849D02*
X2820891D01*
G01X2832826Y2849349D02*
X2826626D01*
Y2861849D01*
X2832826D01*
G01X2830346Y2855807D02*
X2826626D01*
G01X2838871Y2851015D02*
X2840111Y2849974D01*
X2841506Y2849349D01*
X2842746D01*
X2843986Y2849974D01*
X2844916Y2851015D01*
X2845381Y2852474D01*
X2845071Y2853932D01*
X2844296Y2855182D01*
X2842901Y2856016D01*
X2841041Y2856432D01*
X2839956Y2857266D01*
X2839491Y2858724D01*
X2839801Y2860182D01*
X2840576Y2861224D01*
X2841661Y2861849D01*
X2842746D01*
X2843831Y2861432D01*
X2844761Y2860391D01*
G01X2854526Y2848932D02*
X2854216Y2849141D01*
Y2849557D01*
X2854526Y2849766D01*
X2854836Y2849557D01*
Y2849141D01*
X2854526Y2848932D01*
G01Y2854557D02*
X2854216Y2854766D01*
Y2855182D01*
X2854526Y2855391D01*
X2854836Y2855182D01*
Y2854766D01*
X2854526Y2854557D01*
G01X2954976Y3012836D02*
X2955596Y3013461D01*
X2956061Y3014502D01*
X2956371Y3015961D01*
X2956061Y3017211D01*
X2955441Y3018044D01*
X2954356Y3018669D01*
X2950171D01*
Y3006169D01*
X2955286D01*
X2956371Y3007002D01*
X2956991Y3008252D01*
X2957301Y3009711D01*
X2956991Y3011169D01*
X2956061Y3012419D01*
X2954976Y3012836D01*
X2950171D01*
G01X2962261Y3006169D02*
X2966136Y3018669D01*
X2970011Y3006169D01*
G01X2968616Y3010544D02*
X2963656D01*
G01X2981946Y3017627D02*
X2981016Y3018252D01*
X2979931Y3018669D01*
X2978691D01*
X2977296Y3018044D01*
X2976211Y3017002D01*
X2975436Y3015752D01*
X2974816Y3013669D01*
X2974661Y3011794D01*
X2974971Y3009919D01*
X2975436Y3008669D01*
X2976366Y3007419D01*
X2977451Y3006586D01*
X2978536Y3006169D01*
X2979621D01*
X2980706Y3006586D01*
X2981636Y3007210D01*
X2982411Y3008044D01*
G01X2987526Y3006169D02*
Y3018669D01*
G01X2993416D02*
X2987526Y3010960D01*
G01X2994346Y3006169D02*
X2990161Y3014502D01*
G01X2999926Y3006169D02*
Y3018669D01*
X3003026D01*
X3004266Y3018044D01*
X3005196Y3017211D01*
X3005971Y3015961D01*
X3006591Y3014502D01*
X3006746Y3012419D01*
X3006591Y3010336D01*
X3005971Y3008877D01*
X3005196Y3007627D01*
X3004266Y3006794D01*
X3003026Y3006169D01*
X2999926D01*
G01X3012636D02*
Y3018669D01*
X3016511D01*
X3017751Y3018044D01*
X3018526Y3017211D01*
X3018836Y3015544D01*
X3018526Y3013877D01*
X3017596Y3012836D01*
X3016511Y3012211D01*
X3012636D01*
G01X3016511D02*
X3018836Y3006169D01*
G01X3026276Y3018669D02*
X3029996D01*
G01X3028136D02*
Y3006169D01*
G01X3026276D02*
X3029996D01*
G01X3037436Y3018669D02*
Y3006169D01*
X3043636D01*
G01X3049836Y3018669D02*
Y3006169D01*
X3056036D01*
G01X3074481Y3007835D02*
X3075721Y3006794D01*
X3077116Y3006169D01*
X3078356D01*
X3079596Y3006794D01*
X3080526Y3007835D01*
X3080991Y3009294D01*
X3080681Y3010752D01*
X3079906Y3012002D01*
X3078511Y3012836D01*
X3076651Y3013252D01*
X3075566Y3014086D01*
X3075101Y3015544D01*
X3075411Y3017002D01*
X3076186Y3018044D01*
X3077271Y3018669D01*
X3078356D01*
X3079441Y3018252D01*
X3080371Y3017211D01*
G01X3090136Y3018669D02*
Y3006169D01*
G01X3086571Y3018669D02*
X3093701D01*
G01X3099126D02*
Y3009711D01*
X3099746Y3007835D01*
X3100986Y3006586D01*
X3102536Y3006169D01*
X3104086Y3006586D01*
X3105326Y3007835D01*
X3105946Y3009711D01*
Y3018669D01*
G01X3116176Y3012836D02*
X3116796Y3013461D01*
X3117261Y3014502D01*
X3117571Y3015961D01*
X3117261Y3017211D01*
X3116641Y3018044D01*
X3115556Y3018669D01*
X3111371D01*
Y3006169D01*
X3116486D01*
X3117571Y3007002D01*
X3118191Y3008252D01*
X3118501Y3009711D01*
X3118191Y3011169D01*
X3117261Y3012419D01*
X3116176Y3012836D01*
X3111371D01*
G01X3136636Y3018669D02*
Y3006169D01*
X3142836D01*
G01X3155236D02*
X3149036D01*
Y3018669D01*
X3155236D01*
G01X3152756Y3012627D02*
X3149036D01*
G01X3160971Y3006169D02*
Y3018669D01*
X3168101Y3006169D01*
Y3018669D01*
G01X3177866Y3012419D02*
X3180966D01*
Y3008669D01*
X3180036Y3007419D01*
X3178951Y3006586D01*
X3177401Y3006169D01*
X3175851Y3006586D01*
X3174766Y3007419D01*
X3173836Y3008669D01*
X3173216Y3010127D01*
X3172906Y3011794D01*
Y3013252D01*
X3173216Y3014502D01*
X3173836Y3015961D01*
X3174766Y3017211D01*
X3175696Y3018044D01*
X3176936Y3018669D01*
X3178021D01*
X3179261Y3018252D01*
X3180191Y3017419D01*
G01X3189336Y3018669D02*
Y3006169D01*
G01X3185771Y3018669D02*
X3192901D01*
G01X3198481Y3006169D02*
Y3018669D01*
G01X3204991D02*
Y3006169D01*
G01Y3012419D02*
X3198481D01*
G01X3226536Y3018669D02*
Y3006169D01*
G01X3222971Y3018669D02*
X3230101D01*
G01X3238936Y3006169D02*
X3237696Y3006377D01*
X3236611Y3007210D01*
X3235681Y3008461D01*
X3235061Y3009919D01*
X3234751Y3011586D01*
Y3013252D01*
X3235061Y3014919D01*
X3235681Y3016377D01*
X3236611Y3017627D01*
X3237696Y3018461D01*
X3238936Y3018669D01*
X3240176Y3018461D01*
X3241261Y3017627D01*
X3242191Y3016377D01*
X3242811Y3014919D01*
X3243121Y3013252D01*
Y3011586D01*
X3242811Y3009919D01*
X3242191Y3008461D01*
X3241261Y3007210D01*
X3240176Y3006377D01*
X3238936Y3006169D01*
G01X3248236Y3018669D02*
Y3006169D01*
X3254436D01*
G01X3266836D02*
X3260636D01*
Y3018669D01*
X3266836D01*
G01X3264356Y3012627D02*
X3260636D01*
G01X3273036Y3006169D02*
Y3018669D01*
X3276911D01*
X3278151Y3018044D01*
X3278926Y3017211D01*
X3279236Y3015544D01*
X3278926Y3013877D01*
X3277996Y3012836D01*
X3276911Y3012211D01*
X3273036D01*
G01X3276911D02*
X3279236Y3006169D01*
G01X3284661D02*
X3288536Y3018669D01*
X3292411Y3006169D01*
G01X3291016Y3010544D02*
X3286056D01*
G01X3297371Y3006169D02*
Y3018669D01*
X3304501Y3006169D01*
Y3018669D01*
G01X3316746Y3017627D02*
X3315816Y3018252D01*
X3314731Y3018669D01*
X3313491D01*
X3312096Y3018044D01*
X3311011Y3017002D01*
X3310236Y3015752D01*
X3309616Y3013669D01*
X3309461Y3011794D01*
X3309771Y3009919D01*
X3310236Y3008669D01*
X3311166Y3007419D01*
X3312251Y3006586D01*
X3313336Y3006169D01*
X3314421D01*
X3315506Y3006586D01*
X3316436Y3007210D01*
X3317211Y3008044D01*
G01X3328836Y3006169D02*
X3322636D01*
Y3018669D01*
X3328836D01*
G01X3326356Y3012627D02*
X3322636D01*
G01X3350536Y3018669D02*
Y3006169D01*
G01X3346971Y3018669D02*
X3354101D01*
G01X3362936Y3006169D02*
X3361696Y3006377D01*
X3360611Y3007210D01*
X3359681Y3008461D01*
X3359061Y3009919D01*
X3358751Y3011586D01*
Y3013252D01*
X3359061Y3014919D01*
X3359681Y3016377D01*
X3360611Y3017627D01*
X3361696Y3018461D01*
X3362936Y3018669D01*
X3364176Y3018461D01*
X3365261Y3017627D01*
X3366191Y3016377D01*
X3366811Y3014919D01*
X3367121Y3013252D01*
Y3011586D01*
X3366811Y3009919D01*
X3366191Y3008461D01*
X3365261Y3007210D01*
X3364176Y3006377D01*
X3362936Y3006169D01*
G01X3388976Y3012836D02*
X3389596Y3013461D01*
X3390061Y3014502D01*
X3390371Y3015961D01*
X3390061Y3017211D01*
X3389441Y3018044D01*
X3388356Y3018669D01*
X3384171D01*
Y3006169D01*
X3389286D01*
X3390371Y3007002D01*
X3390991Y3008252D01*
X3391301Y3009711D01*
X3390991Y3011169D01*
X3390061Y3012419D01*
X3388976Y3012836D01*
X3384171D01*
G01X3403236Y3006169D02*
X3397036D01*
Y3018669D01*
X3403236D01*
G01X3400756Y3012627D02*
X3397036D01*
G01X3424626Y3006169D02*
X3424936Y3008877D01*
X3425401Y3011169D01*
X3426021Y3013252D01*
X3426796Y3015544D01*
X3428036Y3018669D01*
X3421836D01*
G01X3448031Y3010336D02*
X3451751D01*
G01X3449736Y3013044D02*
Y3007627D01*
G01X3459346Y3005752D02*
X3464926Y3018669D01*
G01X3472521Y3010336D02*
X3476551D01*
G01X3483526Y3008044D02*
X3484456Y3007002D01*
X3485541Y3006377D01*
X3486936Y3006169D01*
X3488331Y3006586D01*
X3489416Y3007419D01*
X3490191Y3008877D01*
X3490346Y3010544D01*
X3490036Y3012211D01*
X3489261Y3013252D01*
X3488176Y3014086D01*
X3487091Y3014294D01*
X3486006Y3014086D01*
X3484611Y3013252D01*
X3485076Y3018669D01*
X3489261D01*
G01X3507706Y3006169D02*
Y3018669D01*
X3511736Y3008252D01*
X3515766Y3018669D01*
Y3006169D01*
G01X3522276Y3018669D02*
X3525996D01*
G01X3524136D02*
Y3006169D01*
G01X3522276D02*
X3525996D01*
G01X3533436Y3018669D02*
Y3006169D01*
X3539636D01*
G01X3545681Y3007835D02*
X3546921Y3006794D01*
X3548316Y3006169D01*
X3549556D01*
X3550796Y3006794D01*
X3551726Y3007835D01*
X3552191Y3009294D01*
X3551881Y3010752D01*
X3551106Y3012002D01*
X3549711Y3012836D01*
X3547851Y3013252D01*
X3546766Y3014086D01*
X3546301Y3015544D01*
X3546611Y3017002D01*
X3547386Y3018044D01*
X3548471Y3018669D01*
X3549556D01*
X3550641Y3018252D01*
X3551571Y3017211D01*
G01X2790521Y3029086D02*
X2794551D01*
G01X2813306Y3024919D02*
Y3037419D01*
X2817336Y3027002D01*
X2821366Y3037419D01*
Y3024919D01*
G01X2826791D02*
Y3037419D01*
X2832681D01*
G01X2830511Y3031377D02*
X2826791D01*
G01X2843066Y3031169D02*
X2846166D01*
Y3027419D01*
X2845236Y3026169D01*
X2844151Y3025336D01*
X2842601Y3024919D01*
X2841051Y3025336D01*
X2839966Y3026169D01*
X2839036Y3027419D01*
X2838416Y3028877D01*
X2838106Y3030544D01*
Y3032002D01*
X2838416Y3033252D01*
X2839036Y3034711D01*
X2839966Y3035961D01*
X2840896Y3036794D01*
X2842136Y3037419D01*
X2843221D01*
X2844461Y3037002D01*
X2845391Y3036169D01*
G01X2849886Y3020752D02*
X2859186D01*
G01X2863681Y3026585D02*
X2864921Y3025544D01*
X2866316Y3024919D01*
X2867556D01*
X2868796Y3025544D01*
X2869726Y3026585D01*
X2870191Y3028044D01*
X2869881Y3029502D01*
X2869106Y3030752D01*
X2867711Y3031586D01*
X2865851Y3032002D01*
X2864766Y3032836D01*
X2864301Y3034294D01*
X2864611Y3035752D01*
X2865386Y3036794D01*
X2866471Y3037419D01*
X2867556D01*
X2868641Y3037002D01*
X2869571Y3035961D01*
G01X2879336Y3037419D02*
Y3024919D01*
G01X2875771Y3037419D02*
X2882901D01*
G01X2888326D02*
Y3028461D01*
X2888946Y3026585D01*
X2890186Y3025336D01*
X2891736Y3024919D01*
X2893286Y3025336D01*
X2894526Y3026585D01*
X2895146Y3028461D01*
Y3037419D01*
G01X2905376Y3031586D02*
X2905996Y3032211D01*
X2906461Y3033252D01*
X2906771Y3034711D01*
X2906461Y3035961D01*
X2905841Y3036794D01*
X2904756Y3037419D01*
X2900571D01*
Y3024919D01*
X2905686D01*
X2906771Y3025752D01*
X2907391Y3027002D01*
X2907701Y3028461D01*
X2907391Y3029919D01*
X2906461Y3031169D01*
X2905376Y3031586D01*
X2900571D01*
G01X2928936Y3024502D02*
X2928626Y3024711D01*
Y3025127D01*
X2928936Y3025336D01*
X2929246Y3025127D01*
Y3024711D01*
X2928936Y3024502D01*
G01Y3030127D02*
X2928626Y3030336D01*
Y3030752D01*
X2928936Y3030961D01*
X2929246Y3030752D01*
Y3030336D01*
X2928936Y3030127D01*
G01X2949706Y3024919D02*
Y3037419D01*
X2953736Y3027002D01*
X2957766Y3037419D01*
Y3024919D01*
G01X2962261D02*
X2966136Y3037419D01*
X2970011Y3024919D01*
G01X2968616Y3029294D02*
X2963656D01*
G01X2974971Y3024919D02*
Y3037419D01*
X2982101Y3024919D01*
Y3037419D01*
G01X2987526D02*
Y3028461D01*
X2988146Y3026585D01*
X2989386Y3025336D01*
X2990936Y3024919D01*
X2992486Y3025336D01*
X2993726Y3026585D01*
X2994346Y3028461D01*
Y3037419D01*
G01X3000391Y3024919D02*
Y3037419D01*
X3006281D01*
G01X3004111Y3031377D02*
X3000391D01*
G01X3011861Y3024919D02*
X3015736Y3037419D01*
X3019611Y3024919D01*
G01X3018216Y3029294D02*
X3013256D01*
G01X3031546Y3036377D02*
X3030616Y3037002D01*
X3029531Y3037419D01*
X3028291D01*
X3026896Y3036794D01*
X3025811Y3035752D01*
X3025036Y3034502D01*
X3024416Y3032419D01*
X3024261Y3030544D01*
X3024571Y3028669D01*
X3025036Y3027419D01*
X3025966Y3026169D01*
X3027051Y3025336D01*
X3028136Y3024919D01*
X3029221D01*
X3030306Y3025336D01*
X3031236Y3025960D01*
X3032011Y3026794D01*
G01X3040536Y3037419D02*
Y3024919D01*
G01X3036971Y3037419D02*
X3044101D01*
G01X3049526D02*
Y3028461D01*
X3050146Y3026585D01*
X3051386Y3025336D01*
X3052936Y3024919D01*
X3054486Y3025336D01*
X3055726Y3026585D01*
X3056346Y3028461D01*
Y3037419D01*
G01X3062236Y3024919D02*
Y3037419D01*
X3066111D01*
X3067351Y3036794D01*
X3068126Y3035961D01*
X3068436Y3034294D01*
X3068126Y3032627D01*
X3067196Y3031586D01*
X3066111Y3030961D01*
X3062236D01*
G01X3066111D02*
X3068436Y3024919D01*
G01X3075876Y3037419D02*
X3079596D01*
G01X3077736D02*
Y3024919D01*
G01X3075876D02*
X3079596D01*
G01X3086571D02*
Y3037419D01*
X3093701Y3024919D01*
Y3037419D01*
G01X3103466Y3031169D02*
X3106566D01*
Y3027419D01*
X3105636Y3026169D01*
X3104551Y3025336D01*
X3103001Y3024919D01*
X3101451Y3025336D01*
X3100366Y3026169D01*
X3099436Y3027419D01*
X3098816Y3028877D01*
X3098506Y3030544D01*
Y3032002D01*
X3098816Y3033252D01*
X3099436Y3034711D01*
X3100366Y3035961D01*
X3101296Y3036794D01*
X3102536Y3037419D01*
X3103621D01*
X3104861Y3037002D01*
X3105791Y3036169D01*
G01X3124081Y3026585D02*
X3125321Y3025544D01*
X3126716Y3024919D01*
X3127956D01*
X3129196Y3025544D01*
X3130126Y3026585D01*
X3130591Y3028044D01*
X3130281Y3029502D01*
X3129506Y3030752D01*
X3128111Y3031586D01*
X3126251Y3032002D01*
X3125166Y3032836D01*
X3124701Y3034294D01*
X3125011Y3035752D01*
X3125786Y3036794D01*
X3126871Y3037419D01*
X3127956D01*
X3129041Y3037002D01*
X3129971Y3035961D01*
G01X3139736Y3037419D02*
Y3024919D01*
G01X3136171Y3037419D02*
X3143301D01*
G01X3148726D02*
Y3028461D01*
X3149346Y3026585D01*
X3150586Y3025336D01*
X3152136Y3024919D01*
X3153686Y3025336D01*
X3154926Y3026585D01*
X3155546Y3028461D01*
Y3037419D01*
G01X3165776Y3031586D02*
X3166396Y3032211D01*
X3166861Y3033252D01*
X3167171Y3034711D01*
X3166861Y3035961D01*
X3166241Y3036794D01*
X3165156Y3037419D01*
X3160971D01*
Y3024919D01*
X3166086D01*
X3167171Y3025752D01*
X3167791Y3027002D01*
X3168101Y3028461D01*
X3167791Y3029919D01*
X3166861Y3031169D01*
X3165776Y3031586D01*
X3160971D01*
G01X3186236Y3037419D02*
Y3024919D01*
X3192436D01*
G01X3204836D02*
X3198636D01*
Y3037419D01*
X3204836D01*
G01X3202356Y3031377D02*
X3198636D01*
G01X3210571Y3024919D02*
Y3037419D01*
X3217701Y3024919D01*
Y3037419D01*
G01X3227466Y3031169D02*
X3230566D01*
Y3027419D01*
X3229636Y3026169D01*
X3228551Y3025336D01*
X3227001Y3024919D01*
X3225451Y3025336D01*
X3224366Y3026169D01*
X3223436Y3027419D01*
X3222816Y3028877D01*
X3222506Y3030544D01*
Y3032002D01*
X3222816Y3033252D01*
X3223436Y3034711D01*
X3224366Y3035961D01*
X3225296Y3036794D01*
X3226536Y3037419D01*
X3227621D01*
X3228861Y3037002D01*
X3229791Y3036169D01*
G01X3238936Y3037419D02*
Y3024919D01*
G01X3235371Y3037419D02*
X3242501D01*
G01X3248081Y3024919D02*
Y3037419D01*
G01X3254591D02*
Y3024919D01*
G01Y3031169D02*
X3248081D01*
G01X2950481Y3045335D02*
X2951721Y3044294D01*
X2953116Y3043669D01*
X2954356D01*
X2955596Y3044294D01*
X2956526Y3045335D01*
X2956991Y3046794D01*
X2956681Y3048252D01*
X2955906Y3049502D01*
X2954511Y3050336D01*
X2952651Y3050752D01*
X2951566Y3051586D01*
X2951101Y3053044D01*
X2951411Y3054502D01*
X2952186Y3055544D01*
X2953271Y3056169D01*
X2954356D01*
X2955441Y3055752D01*
X2956371Y3054711D01*
G01X2962726Y3056169D02*
Y3047211D01*
X2963346Y3045335D01*
X2964586Y3044086D01*
X2966136Y3043669D01*
X2967686Y3044086D01*
X2968926Y3045335D01*
X2969546Y3047211D01*
Y3056169D01*
G01X2975436Y3043669D02*
Y3056169D01*
X2979311D01*
X2980551Y3055544D01*
X2981326Y3054711D01*
X2981636Y3053044D01*
X2981326Y3051377D01*
X2980396Y3050336D01*
X2979311Y3049711D01*
X2975436D01*
G01X2979311D02*
X2981636Y3043669D01*
G01X2987991D02*
Y3056169D01*
X2993881D01*
G01X2991711Y3050127D02*
X2987991D01*
G01X2999461Y3043669D02*
X3003336Y3056169D01*
X3007211Y3043669D01*
G01X3005816Y3048044D02*
X3000856D01*
G01X3019146Y3055127D02*
X3018216Y3055752D01*
X3017131Y3056169D01*
X3015891D01*
X3014496Y3055544D01*
X3013411Y3054502D01*
X3012636Y3053252D01*
X3012016Y3051169D01*
X3011861Y3049294D01*
X3012171Y3047419D01*
X3012636Y3046169D01*
X3013566Y3044919D01*
X3014651Y3044086D01*
X3015736Y3043669D01*
X3016821D01*
X3017906Y3044086D01*
X3018836Y3044710D01*
X3019611Y3045544D01*
G01X3031236Y3043669D02*
X3025036D01*
Y3056169D01*
X3031236D01*
G01X3028756Y3050127D02*
X3025036D01*
G01X3052936Y3043669D02*
X3051696Y3043877D01*
X3050611Y3044710D01*
X3049681Y3045961D01*
X3049061Y3047419D01*
X3048751Y3049086D01*
Y3050752D01*
X3049061Y3052419D01*
X3049681Y3053877D01*
X3050611Y3055127D01*
X3051696Y3055961D01*
X3052936Y3056169D01*
X3054176Y3055961D01*
X3055261Y3055127D01*
X3056191Y3053877D01*
X3056811Y3052419D01*
X3057121Y3050752D01*
Y3049086D01*
X3056811Y3047419D01*
X3056191Y3045961D01*
X3055261Y3044710D01*
X3054176Y3043877D01*
X3052936Y3043669D01*
G01X3062391D02*
Y3056169D01*
X3068281D01*
G01X3066111Y3050127D02*
X3062391D01*
G01X3086106Y3043669D02*
Y3056169D01*
X3090136Y3045752D01*
X3094166Y3056169D01*
Y3043669D01*
G01X3099126Y3056169D02*
Y3047211D01*
X3099746Y3045335D01*
X3100986Y3044086D01*
X3102536Y3043669D01*
X3104086Y3044086D01*
X3105326Y3045335D01*
X3105946Y3047211D01*
Y3056169D01*
G01X3111681Y3045335D02*
X3112921Y3044294D01*
X3114316Y3043669D01*
X3115556D01*
X3116796Y3044294D01*
X3117726Y3045335D01*
X3118191Y3046794D01*
X3117881Y3048252D01*
X3117106Y3049502D01*
X3115711Y3050336D01*
X3113851Y3050752D01*
X3112766Y3051586D01*
X3112301Y3053044D01*
X3112611Y3054502D01*
X3113386Y3055544D01*
X3114471Y3056169D01*
X3115556D01*
X3116641Y3055752D01*
X3117571Y3054711D01*
G01X3127336Y3056169D02*
Y3043669D01*
G01X3123771Y3056169D02*
X3130901D01*
G01X3137721Y3047836D02*
X3141751D01*
G01X3148571Y3043669D02*
Y3056169D01*
X3155701Y3043669D01*
Y3056169D01*
G01X3164536Y3043669D02*
X3163296Y3043877D01*
X3162211Y3044710D01*
X3161281Y3045961D01*
X3160661Y3047419D01*
X3160351Y3049086D01*
Y3050752D01*
X3160661Y3052419D01*
X3161281Y3053877D01*
X3162211Y3055127D01*
X3163296Y3055961D01*
X3164536Y3056169D01*
X3165776Y3055961D01*
X3166861Y3055127D01*
X3167791Y3053877D01*
X3168411Y3052419D01*
X3168721Y3050752D01*
Y3049086D01*
X3168411Y3047419D01*
X3167791Y3045961D01*
X3166861Y3044710D01*
X3165776Y3043877D01*
X3164536Y3043669D01*
G01X3176936Y3056169D02*
Y3043669D01*
G01X3173371Y3056169D02*
X3180501D01*
G01X3187321Y3047836D02*
X3191351D01*
G01X3205146Y3055127D02*
X3204216Y3055752D01*
X3203131Y3056169D01*
X3201891D01*
X3200496Y3055544D01*
X3199411Y3054502D01*
X3198636Y3053252D01*
X3198016Y3051169D01*
X3197861Y3049294D01*
X3198171Y3047419D01*
X3198636Y3046169D01*
X3199566Y3044919D01*
X3200651Y3044086D01*
X3201736Y3043669D01*
X3202821D01*
X3203906Y3044086D01*
X3204836Y3044710D01*
X3205611Y3045544D01*
G01X3210726Y3056169D02*
Y3047211D01*
X3211346Y3045335D01*
X3212586Y3044086D01*
X3214136Y3043669D01*
X3215686Y3044086D01*
X3216926Y3045335D01*
X3217546Y3047211D01*
Y3056169D01*
G01X3226536D02*
Y3043669D01*
G01X3222971Y3056169D02*
X3230101D01*
G01X3236921Y3047836D02*
X3240951D01*
G01X3248236Y3056169D02*
Y3043669D01*
X3254436D01*
G01X3259861D02*
X3263736Y3056169D01*
X3267611Y3043669D01*
G01X3266216Y3048044D02*
X3261256D01*
G01X3276136Y3043669D02*
Y3049294D01*
X3273036Y3056169D01*
G01X3279236D02*
X3276136Y3049294D01*
G01X3291636Y3043669D02*
X3285436D01*
Y3056169D01*
X3291636D01*
G01X3289156Y3050127D02*
X3285436D01*
G01X3297836Y3043669D02*
Y3056169D01*
X3301711D01*
X3302951Y3055544D01*
X3303726Y3054711D01*
X3304036Y3053044D01*
X3303726Y3051377D01*
X3302796Y3050336D01*
X3301711Y3049711D01*
X3297836D01*
G01X3301711D02*
X3304036Y3043669D01*
G01X2790521Y3066586D02*
X2794551D01*
G01X2813306Y3062419D02*
Y3074919D01*
X2817336Y3064502D01*
X2821366Y3074919D01*
Y3062419D01*
G01X2825861D02*
X2829736Y3074919D01*
X2833611Y3062419D01*
G01X2832216Y3066794D02*
X2827256D01*
G01X2838881Y3062419D02*
X2845391Y3074919D01*
G01X2838881D02*
X2845391Y3062419D01*
G01X2849886Y3058252D02*
X2859186D01*
G01X2863526Y3062419D02*
Y3074919D01*
X2866626D01*
X2867866Y3074294D01*
X2868796Y3073461D01*
X2869571Y3072211D01*
X2870191Y3070752D01*
X2870346Y3068669D01*
X2870191Y3066586D01*
X2869571Y3065127D01*
X2868796Y3063877D01*
X2867866Y3063044D01*
X2866626Y3062419D01*
X2863526D01*
G01X2882436D02*
X2876236D01*
Y3074919D01*
X2882436D01*
G01X2879956Y3068877D02*
X2876236D01*
G01X2888636Y3062419D02*
Y3074919D01*
X2892356D01*
X2893596Y3074294D01*
X2894526Y3072836D01*
X2894836Y3071169D01*
X2894526Y3069502D01*
X2893751Y3068252D01*
X2892356Y3067627D01*
X2888636D01*
G01X2904136Y3074919D02*
Y3062419D01*
G01X2900571Y3074919D02*
X2907701D01*
G01X2913281Y3062419D02*
Y3074919D01*
G01X2919791D02*
Y3062419D01*
G01Y3068669D02*
X2913281D01*
G01X2928936Y3062002D02*
X2928626Y3062211D01*
Y3062627D01*
X2928936Y3062836D01*
X2929246Y3062627D01*
Y3062211D01*
X2928936Y3062002D01*
G01Y3067627D02*
X2928626Y3067836D01*
Y3068252D01*
X2928936Y3068461D01*
X2929246Y3068252D01*
Y3067836D01*
X2928936Y3067627D01*
G01X2950326Y3062419D02*
Y3074919D01*
X2953426D01*
X2954666Y3074294D01*
X2955596Y3073461D01*
X2956371Y3072211D01*
X2956991Y3070752D01*
X2957146Y3068669D01*
X2956991Y3066586D01*
X2956371Y3065127D01*
X2955596Y3063877D01*
X2954666Y3063044D01*
X2953426Y3062419D01*
X2950326D01*
G01X2969236D02*
X2963036D01*
Y3074919D01*
X2969236D01*
G01X2966756Y3068877D02*
X2963036D01*
G01X2975436Y3062419D02*
Y3074919D01*
X2979156D01*
X2980396Y3074294D01*
X2981326Y3072836D01*
X2981636Y3071169D01*
X2981326Y3069502D01*
X2980551Y3068252D01*
X2979156Y3067627D01*
X2975436D01*
G01X2990936Y3074919D02*
Y3062419D01*
G01X2987371Y3074919D02*
X2994501D01*
G01X3000081Y3062419D02*
Y3074919D01*
G01X3006591D02*
Y3062419D01*
G01Y3068669D02*
X3000081D01*
G01X3025191Y3062419D02*
Y3074919D01*
X3031081D01*
G01X3028911Y3068877D02*
X3025191D01*
G01X3037436Y3062419D02*
Y3074919D01*
X3041311D01*
X3042551Y3074294D01*
X3043326Y3073461D01*
X3043636Y3071794D01*
X3043326Y3070127D01*
X3042396Y3069086D01*
X3041311Y3068461D01*
X3037436D01*
G01X3041311D02*
X3043636Y3062419D01*
G01X3052936D02*
X3051696Y3062627D01*
X3050611Y3063460D01*
X3049681Y3064711D01*
X3049061Y3066169D01*
X3048751Y3067836D01*
Y3069502D01*
X3049061Y3071169D01*
X3049681Y3072627D01*
X3050611Y3073877D01*
X3051696Y3074711D01*
X3052936Y3074919D01*
X3054176Y3074711D01*
X3055261Y3073877D01*
X3056191Y3072627D01*
X3056811Y3071169D01*
X3057121Y3069502D01*
Y3067836D01*
X3056811Y3066169D01*
X3056191Y3064711D01*
X3055261Y3063460D01*
X3054176Y3062627D01*
X3052936Y3062419D01*
G01X3061306D02*
Y3074919D01*
X3065336Y3064502D01*
X3069366Y3074919D01*
Y3062419D01*
G01X3086881Y3064085D02*
X3088121Y3063044D01*
X3089516Y3062419D01*
X3090756D01*
X3091996Y3063044D01*
X3092926Y3064085D01*
X3093391Y3065544D01*
X3093081Y3067002D01*
X3092306Y3068252D01*
X3090911Y3069086D01*
X3089051Y3069502D01*
X3087966Y3070336D01*
X3087501Y3071794D01*
X3087811Y3073252D01*
X3088586Y3074294D01*
X3089671Y3074919D01*
X3090756D01*
X3091841Y3074502D01*
X3092771Y3073461D01*
G01X3102536Y3074919D02*
Y3062419D01*
G01X3098971Y3074919D02*
X3106101D01*
G01X3111061Y3062419D02*
X3114936Y3074919D01*
X3118811Y3062419D01*
G01X3117416Y3066794D02*
X3112456D01*
G01X3124236Y3062419D02*
Y3074919D01*
X3128111D01*
X3129351Y3074294D01*
X3130126Y3073461D01*
X3130436Y3071794D01*
X3130126Y3070127D01*
X3129196Y3069086D01*
X3128111Y3068461D01*
X3124236D01*
G01X3128111D02*
X3130436Y3062419D01*
G01X3139736Y3074919D02*
Y3062419D01*
G01X3136171Y3074919D02*
X3143301D01*
G01X3161436D02*
Y3062419D01*
X3167636D01*
G01X3173061D02*
X3176936Y3074919D01*
X3180811Y3062419D01*
G01X3179416Y3066794D02*
X3174456D01*
G01X3189336Y3062419D02*
Y3068044D01*
X3186236Y3074919D01*
G01X3192436D02*
X3189336Y3068044D01*
G01X3204836Y3062419D02*
X3198636D01*
Y3074919D01*
X3204836D01*
G01X3202356Y3068877D02*
X3198636D01*
G01X3211036Y3062419D02*
Y3074919D01*
X3214911D01*
X3216151Y3074294D01*
X3216926Y3073461D01*
X3217236Y3071794D01*
X3216926Y3070127D01*
X3215996Y3069086D01*
X3214911Y3068461D01*
X3211036D01*
G01X3214911D02*
X3217236Y3062419D01*
G01X3238936Y3074919D02*
Y3062419D01*
G01X3235371Y3074919D02*
X3242501D01*
G01X3251336Y3062419D02*
X3250096Y3062627D01*
X3249011Y3063460D01*
X3248081Y3064711D01*
X3247461Y3066169D01*
X3247151Y3067836D01*
Y3069502D01*
X3247461Y3071169D01*
X3248081Y3072627D01*
X3249011Y3073877D01*
X3250096Y3074711D01*
X3251336Y3074919D01*
X3252576Y3074711D01*
X3253661Y3073877D01*
X3254591Y3072627D01*
X3255211Y3071169D01*
X3255521Y3069502D01*
Y3067836D01*
X3255211Y3066169D01*
X3254591Y3064711D01*
X3253661Y3063460D01*
X3252576Y3062627D01*
X3251336Y3062419D01*
G01X3276136Y3074919D02*
Y3062419D01*
G01X3272571Y3074919D02*
X3279701D01*
G01X3285281Y3062419D02*
Y3074919D01*
G01X3291791D02*
Y3062419D01*
G01Y3068669D02*
X3285281D01*
G01X3304036Y3062419D02*
X3297836D01*
Y3074919D01*
X3304036D01*
G01X3301556Y3068877D02*
X3297836D01*
G01X2790521Y3085336D02*
X2794551D01*
G01X2813306Y3081169D02*
Y3093669D01*
X2817336Y3083252D01*
X2821366Y3093669D01*
Y3081169D01*
G01X2826171D02*
Y3093669D01*
X2833301Y3081169D01*
Y3093669D01*
G01X2845546Y3092627D02*
X2844616Y3093252D01*
X2843531Y3093669D01*
X2842291D01*
X2840896Y3093044D01*
X2839811Y3092002D01*
X2839036Y3090752D01*
X2838416Y3088669D01*
X2838261Y3086794D01*
X2838571Y3084919D01*
X2839036Y3083669D01*
X2839966Y3082419D01*
X2841051Y3081586D01*
X2842136Y3081169D01*
X2843221D01*
X2844306Y3081586D01*
X2845236Y3082210D01*
X2846011Y3083044D01*
G01X2849886Y3077002D02*
X2859186D01*
G01X2863836Y3093669D02*
Y3081169D01*
X2870036D01*
G01X2875461D02*
X2879336Y3093669D01*
X2883211Y3081169D01*
G01X2881816Y3085544D02*
X2876856D01*
G01X2891736Y3081169D02*
Y3086794D01*
X2888636Y3093669D01*
G01X2894836D02*
X2891736Y3086794D01*
G01X2907236Y3081169D02*
X2901036D01*
Y3093669D01*
X2907236D01*
G01X2904756Y3087627D02*
X2901036D01*
G01X2913436Y3081169D02*
Y3093669D01*
X2917311D01*
X2918551Y3093044D01*
X2919326Y3092211D01*
X2919636Y3090544D01*
X2919326Y3088877D01*
X2918396Y3087836D01*
X2917311Y3087211D01*
X2913436D01*
G01X2917311D02*
X2919636Y3081169D01*
G01X2928936Y3080752D02*
X2928626Y3080961D01*
Y3081377D01*
X2928936Y3081586D01*
X2929246Y3081377D01*
Y3080961D01*
X2928936Y3080752D01*
G01Y3086377D02*
X2928626Y3086586D01*
Y3087002D01*
X2928936Y3087211D01*
X2929246Y3087002D01*
Y3086586D01*
X2928936Y3086377D01*
G01X2949706Y3081169D02*
Y3093669D01*
X2953736Y3083252D01*
X2957766Y3093669D01*
Y3081169D01*
G01X2962726Y3093669D02*
Y3084711D01*
X2963346Y3082835D01*
X2964586Y3081586D01*
X2966136Y3081169D01*
X2967686Y3081586D01*
X2968926Y3082835D01*
X2969546Y3084711D01*
Y3093669D01*
G01X2975281Y3082835D02*
X2976521Y3081794D01*
X2977916Y3081169D01*
X2979156D01*
X2980396Y3081794D01*
X2981326Y3082835D01*
X2981791Y3084294D01*
X2981481Y3085752D01*
X2980706Y3087002D01*
X2979311Y3087836D01*
X2977451Y3088252D01*
X2976366Y3089086D01*
X2975901Y3090544D01*
X2976211Y3092002D01*
X2976986Y3093044D01*
X2978071Y3093669D01*
X2979156D01*
X2980241Y3093252D01*
X2981171Y3092211D01*
G01X2990936Y3093669D02*
Y3081169D01*
G01X2987371Y3093669D02*
X2994501D01*
G01X3001321Y3085336D02*
X3005351D01*
G01X3012171Y3081169D02*
Y3093669D01*
X3019301Y3081169D01*
Y3093669D01*
G01X3028136Y3081169D02*
X3026896Y3081377D01*
X3025811Y3082210D01*
X3024881Y3083461D01*
X3024261Y3084919D01*
X3023951Y3086586D01*
Y3088252D01*
X3024261Y3089919D01*
X3024881Y3091377D01*
X3025811Y3092627D01*
X3026896Y3093461D01*
X3028136Y3093669D01*
X3029376Y3093461D01*
X3030461Y3092627D01*
X3031391Y3091377D01*
X3032011Y3089919D01*
X3032321Y3088252D01*
Y3086586D01*
X3032011Y3084919D01*
X3031391Y3083461D01*
X3030461Y3082210D01*
X3029376Y3081377D01*
X3028136Y3081169D01*
G01X3040536Y3093669D02*
Y3081169D01*
G01X3036971Y3093669D02*
X3044101D01*
G01X3050921Y3085336D02*
X3054951D01*
G01X3068746Y3092627D02*
X3067816Y3093252D01*
X3066731Y3093669D01*
X3065491D01*
X3064096Y3093044D01*
X3063011Y3092002D01*
X3062236Y3090752D01*
X3061616Y3088669D01*
X3061461Y3086794D01*
X3061771Y3084919D01*
X3062236Y3083669D01*
X3063166Y3082419D01*
X3064251Y3081586D01*
X3065336Y3081169D01*
X3066421D01*
X3067506Y3081586D01*
X3068436Y3082210D01*
X3069211Y3083044D01*
G01X3074326Y3093669D02*
Y3084711D01*
X3074946Y3082835D01*
X3076186Y3081586D01*
X3077736Y3081169D01*
X3079286Y3081586D01*
X3080526Y3082835D01*
X3081146Y3084711D01*
Y3093669D01*
G01X3090136D02*
Y3081169D01*
G01X3086571Y3093669D02*
X3093701D01*
G01X3100521Y3085336D02*
X3104551D01*
G01X3111836Y3093669D02*
Y3081169D01*
X3118036D01*
G01X3123461D02*
X3127336Y3093669D01*
X3131211Y3081169D01*
G01X3129816Y3085544D02*
X3124856D01*
G01X3139736Y3081169D02*
Y3086794D01*
X3136636Y3093669D01*
G01X3142836D02*
X3139736Y3086794D01*
G01X3155236Y3081169D02*
X3149036D01*
Y3093669D01*
X3155236D01*
G01X3152756Y3087627D02*
X3149036D01*
G01X3161436Y3081169D02*
Y3093669D01*
X3165311D01*
X3166551Y3093044D01*
X3167326Y3092211D01*
X3167636Y3090544D01*
X3167326Y3088877D01*
X3166396Y3087836D01*
X3165311Y3087211D01*
X3161436D01*
G01X3165311D02*
X3167636Y3081169D01*
G01X2788971Y3099919D02*
Y3112419D01*
X2796101Y3099919D01*
Y3112419D01*
G01X2804936Y3099919D02*
X2803696Y3100127D01*
X2802611Y3100960D01*
X2801681Y3102211D01*
X2801061Y3103669D01*
X2800751Y3105336D01*
Y3107002D01*
X2801061Y3108669D01*
X2801681Y3110127D01*
X2802611Y3111377D01*
X2803696Y3112211D01*
X2804936Y3112419D01*
X2806176Y3112211D01*
X2807261Y3111377D01*
X2808191Y3110127D01*
X2808811Y3108669D01*
X2809121Y3107002D01*
Y3105336D01*
X2808811Y3103669D01*
X2808191Y3102211D01*
X2807261Y3100960D01*
X2806176Y3100127D01*
X2804936Y3099919D01*
G01X2817336Y3112419D02*
Y3099919D01*
G01X2813771Y3112419D02*
X2820901D01*
G01X2832836Y3099919D02*
X2826636D01*
Y3112419D01*
X2832836D01*
G01X2830356Y3106377D02*
X2826636D01*
G01X2838881Y3101585D02*
X2840121Y3100544D01*
X2841516Y3099919D01*
X2842756D01*
X2843996Y3100544D01*
X2844926Y3101585D01*
X2845391Y3103044D01*
X2845081Y3104502D01*
X2844306Y3105752D01*
X2842911Y3106586D01*
X2841051Y3107002D01*
X2839966Y3107836D01*
X2839501Y3109294D01*
X2839811Y3110752D01*
X2840586Y3111794D01*
X2841671Y3112419D01*
X2842756D01*
X2843841Y3112002D01*
X2844771Y3110961D01*
G01X2854536Y3099502D02*
X2854226Y3099711D01*
Y3100127D01*
X2854536Y3100336D01*
X2854846Y3100127D01*
Y3099711D01*
X2854536Y3099502D01*
G01Y3105127D02*
X2854226Y3105336D01*
Y3105752D01*
X2854536Y3105961D01*
X2854846Y3105752D01*
Y3105336D01*
X2854536Y3105127D01*
G01X2950630Y3268842D02*
X2951250Y3269467D01*
X2951715Y3270508D01*
X2952025Y3271967D01*
X2951715Y3273217D01*
X2951095Y3274050D01*
X2950010Y3274675D01*
X2945825D01*
Y3262175D01*
X2950940D01*
X2952025Y3263008D01*
X2952645Y3264258D01*
X2952955Y3265717D01*
X2952645Y3267175D01*
X2951715Y3268425D01*
X2950630Y3268842D01*
X2945825D01*
G01X2957915Y3262175D02*
X2961790Y3274675D01*
X2965665Y3262175D01*
G01X2964270Y3266550D02*
X2959310D01*
G01X2977600Y3273633D02*
X2976670Y3274258D01*
X2975585Y3274675D01*
X2974345D01*
X2972950Y3274050D01*
X2971865Y3273008D01*
X2971090Y3271758D01*
X2970470Y3269675D01*
X2970315Y3267800D01*
X2970625Y3265925D01*
X2971090Y3264675D01*
X2972020Y3263425D01*
X2973105Y3262592D01*
X2974190Y3262175D01*
X2975275D01*
X2976360Y3262592D01*
X2977290Y3263216D01*
X2978065Y3264050D01*
G01X2983180Y3262175D02*
Y3274675D01*
G01X2989070D02*
X2983180Y3266966D01*
G01X2990000Y3262175D02*
X2985815Y3270508D01*
G01X2995580Y3262175D02*
Y3274675D01*
X2998680D01*
X2999920Y3274050D01*
X3000850Y3273217D01*
X3001625Y3271967D01*
X3002245Y3270508D01*
X3002400Y3268425D01*
X3002245Y3266342D01*
X3001625Y3264883D01*
X3000850Y3263633D01*
X2999920Y3262800D01*
X2998680Y3262175D01*
X2995580D01*
G01X3008290D02*
Y3274675D01*
X3012165D01*
X3013405Y3274050D01*
X3014180Y3273217D01*
X3014490Y3271550D01*
X3014180Y3269883D01*
X3013250Y3268842D01*
X3012165Y3268217D01*
X3008290D01*
G01X3012165D02*
X3014490Y3262175D01*
G01X3021930Y3274675D02*
X3025650D01*
G01X3023790D02*
Y3262175D01*
G01X3021930D02*
X3025650D01*
G01X3033090Y3274675D02*
Y3262175D01*
X3039290D01*
G01X3045490Y3274675D02*
Y3262175D01*
X3051690D01*
G01X3070135Y3263841D02*
X3071375Y3262800D01*
X3072770Y3262175D01*
X3074010D01*
X3075250Y3262800D01*
X3076180Y3263841D01*
X3076645Y3265300D01*
X3076335Y3266758D01*
X3075560Y3268008D01*
X3074165Y3268842D01*
X3072305Y3269258D01*
X3071220Y3270092D01*
X3070755Y3271550D01*
X3071065Y3273008D01*
X3071840Y3274050D01*
X3072925Y3274675D01*
X3074010D01*
X3075095Y3274258D01*
X3076025Y3273217D01*
G01X3085790Y3274675D02*
Y3262175D01*
G01X3082225Y3274675D02*
X3089355D01*
G01X3094780D02*
Y3265717D01*
X3095400Y3263841D01*
X3096640Y3262592D01*
X3098190Y3262175D01*
X3099740Y3262592D01*
X3100980Y3263841D01*
X3101600Y3265717D01*
Y3274675D01*
G01X3111830Y3268842D02*
X3112450Y3269467D01*
X3112915Y3270508D01*
X3113225Y3271967D01*
X3112915Y3273217D01*
X3112295Y3274050D01*
X3111210Y3274675D01*
X3107025D01*
Y3262175D01*
X3112140D01*
X3113225Y3263008D01*
X3113845Y3264258D01*
X3114155Y3265717D01*
X3113845Y3267175D01*
X3112915Y3268425D01*
X3111830Y3268842D01*
X3107025D01*
G01X3132290Y3274675D02*
Y3262175D01*
X3138490D01*
G01X3150890D02*
X3144690D01*
Y3274675D01*
X3150890D01*
G01X3148410Y3268633D02*
X3144690D01*
G01X3156625Y3262175D02*
Y3274675D01*
X3163755Y3262175D01*
Y3274675D01*
G01X3173520Y3268425D02*
X3176620D01*
Y3264675D01*
X3175690Y3263425D01*
X3174605Y3262592D01*
X3173055Y3262175D01*
X3171505Y3262592D01*
X3170420Y3263425D01*
X3169490Y3264675D01*
X3168870Y3266133D01*
X3168560Y3267800D01*
Y3269258D01*
X3168870Y3270508D01*
X3169490Y3271967D01*
X3170420Y3273217D01*
X3171350Y3274050D01*
X3172590Y3274675D01*
X3173675D01*
X3174915Y3274258D01*
X3175845Y3273425D01*
G01X3184990Y3274675D02*
Y3262175D01*
G01X3181425Y3274675D02*
X3188555D01*
G01X3194135Y3262175D02*
Y3274675D01*
G01X3200645D02*
Y3262175D01*
G01Y3268425D02*
X3194135D01*
G01X3222190Y3274675D02*
Y3262175D01*
G01X3218625Y3274675D02*
X3225755D01*
G01X3234590Y3262175D02*
X3233350Y3262383D01*
X3232265Y3263216D01*
X3231335Y3264467D01*
X3230715Y3265925D01*
X3230405Y3267592D01*
Y3269258D01*
X3230715Y3270925D01*
X3231335Y3272383D01*
X3232265Y3273633D01*
X3233350Y3274467D01*
X3234590Y3274675D01*
X3235830Y3274467D01*
X3236915Y3273633D01*
X3237845Y3272383D01*
X3238465Y3270925D01*
X3238775Y3269258D01*
Y3267592D01*
X3238465Y3265925D01*
X3237845Y3264467D01*
X3236915Y3263216D01*
X3235830Y3262383D01*
X3234590Y3262175D01*
G01X3243890Y3274675D02*
Y3262175D01*
X3250090D01*
G01X3262490D02*
X3256290D01*
Y3274675D01*
X3262490D01*
G01X3260010Y3268633D02*
X3256290D01*
G01X3268690Y3262175D02*
Y3274675D01*
X3272565D01*
X3273805Y3274050D01*
X3274580Y3273217D01*
X3274890Y3271550D01*
X3274580Y3269883D01*
X3273650Y3268842D01*
X3272565Y3268217D01*
X3268690D01*
G01X3272565D02*
X3274890Y3262175D01*
G01X3280315D02*
X3284190Y3274675D01*
X3288065Y3262175D01*
G01X3286670Y3266550D02*
X3281710D01*
G01X3293025Y3262175D02*
Y3274675D01*
X3300155Y3262175D01*
Y3274675D01*
G01X3312400Y3273633D02*
X3311470Y3274258D01*
X3310385Y3274675D01*
X3309145D01*
X3307750Y3274050D01*
X3306665Y3273008D01*
X3305890Y3271758D01*
X3305270Y3269675D01*
X3305115Y3267800D01*
X3305425Y3265925D01*
X3305890Y3264675D01*
X3306820Y3263425D01*
X3307905Y3262592D01*
X3308990Y3262175D01*
X3310075D01*
X3311160Y3262592D01*
X3312090Y3263216D01*
X3312865Y3264050D01*
G01X3324490Y3262175D02*
X3318290D01*
Y3274675D01*
X3324490D01*
G01X3322010Y3268633D02*
X3318290D01*
G01X3346190Y3274675D02*
Y3262175D01*
G01X3342625Y3274675D02*
X3349755D01*
G01X3358590Y3262175D02*
X3357350Y3262383D01*
X3356265Y3263216D01*
X3355335Y3264467D01*
X3354715Y3265925D01*
X3354405Y3267592D01*
Y3269258D01*
X3354715Y3270925D01*
X3355335Y3272383D01*
X3356265Y3273633D01*
X3357350Y3274467D01*
X3358590Y3274675D01*
X3359830Y3274467D01*
X3360915Y3273633D01*
X3361845Y3272383D01*
X3362465Y3270925D01*
X3362775Y3269258D01*
Y3267592D01*
X3362465Y3265925D01*
X3361845Y3264467D01*
X3360915Y3263216D01*
X3359830Y3262383D01*
X3358590Y3262175D01*
G01X3384630Y3268842D02*
X3385250Y3269467D01*
X3385715Y3270508D01*
X3386025Y3271967D01*
X3385715Y3273217D01*
X3385095Y3274050D01*
X3384010Y3274675D01*
X3379825D01*
Y3262175D01*
X3384940D01*
X3386025Y3263008D01*
X3386645Y3264258D01*
X3386955Y3265717D01*
X3386645Y3267175D01*
X3385715Y3268425D01*
X3384630Y3268842D01*
X3379825D01*
G01X3398890Y3262175D02*
X3392690D01*
Y3274675D01*
X3398890D01*
G01X3396410Y3268633D02*
X3392690D01*
G01X3420280Y3262175D02*
X3420590Y3264883D01*
X3421055Y3267175D01*
X3421675Y3269258D01*
X3422450Y3271550D01*
X3423690Y3274675D01*
X3417490D01*
G01X3443685Y3266342D02*
X3447405D01*
G01X3445390Y3269050D02*
Y3263633D01*
G01X3455000Y3261758D02*
X3460580Y3274675D01*
G01X3468175Y3266342D02*
X3472205D01*
G01X3479180Y3264050D02*
X3480110Y3263008D01*
X3481195Y3262383D01*
X3482590Y3262175D01*
X3483985Y3262592D01*
X3485070Y3263425D01*
X3485845Y3264883D01*
X3486000Y3266550D01*
X3485690Y3268217D01*
X3484915Y3269258D01*
X3483830Y3270092D01*
X3482745Y3270300D01*
X3481660Y3270092D01*
X3480265Y3269258D01*
X3480730Y3274675D01*
X3484915D01*
G01X3503360Y3262175D02*
Y3274675D01*
X3507390Y3264258D01*
X3511420Y3274675D01*
Y3262175D01*
G01X3517930Y3274675D02*
X3521650D01*
G01X3519790D02*
Y3262175D01*
G01X3517930D02*
X3521650D01*
G01X3529090Y3274675D02*
Y3262175D01*
X3535290D01*
G01X3541335Y3263841D02*
X3542575Y3262800D01*
X3543970Y3262175D01*
X3545210D01*
X3546450Y3262800D01*
X3547380Y3263841D01*
X3547845Y3265300D01*
X3547535Y3266758D01*
X3546760Y3268008D01*
X3545365Y3268842D01*
X3543505Y3269258D01*
X3542420Y3270092D01*
X3541955Y3271550D01*
X3542265Y3273008D01*
X3543040Y3274050D01*
X3544125Y3274675D01*
X3545210D01*
X3546295Y3274258D01*
X3547225Y3273217D01*
G01X2786175Y3285092D02*
X2790205D01*
G01X2808960Y3280925D02*
Y3293425D01*
X2812990Y3283008D01*
X2817020Y3293425D01*
Y3280925D01*
G01X2822445D02*
Y3293425D01*
X2828335D01*
G01X2826165Y3287383D02*
X2822445D01*
G01X2838720Y3287175D02*
X2841820D01*
Y3283425D01*
X2840890Y3282175D01*
X2839805Y3281342D01*
X2838255Y3280925D01*
X2836705Y3281342D01*
X2835620Y3282175D01*
X2834690Y3283425D01*
X2834070Y3284883D01*
X2833760Y3286550D01*
Y3288008D01*
X2834070Y3289258D01*
X2834690Y3290717D01*
X2835620Y3291967D01*
X2836550Y3292800D01*
X2837790Y3293425D01*
X2838875D01*
X2840115Y3293008D01*
X2841045Y3292175D01*
G01X2845540Y3276758D02*
X2854840D01*
G01X2859335Y3282591D02*
X2860575Y3281550D01*
X2861970Y3280925D01*
X2863210D01*
X2864450Y3281550D01*
X2865380Y3282591D01*
X2865845Y3284050D01*
X2865535Y3285508D01*
X2864760Y3286758D01*
X2863365Y3287592D01*
X2861505Y3288008D01*
X2860420Y3288842D01*
X2859955Y3290300D01*
X2860265Y3291758D01*
X2861040Y3292800D01*
X2862125Y3293425D01*
X2863210D01*
X2864295Y3293008D01*
X2865225Y3291967D01*
G01X2874990Y3293425D02*
Y3280925D01*
G01X2871425Y3293425D02*
X2878555D01*
G01X2883980D02*
Y3284467D01*
X2884600Y3282591D01*
X2885840Y3281342D01*
X2887390Y3280925D01*
X2888940Y3281342D01*
X2890180Y3282591D01*
X2890800Y3284467D01*
Y3293425D01*
G01X2901030Y3287592D02*
X2901650Y3288217D01*
X2902115Y3289258D01*
X2902425Y3290717D01*
X2902115Y3291967D01*
X2901495Y3292800D01*
X2900410Y3293425D01*
X2896225D01*
Y3280925D01*
X2901340D01*
X2902425Y3281758D01*
X2903045Y3283008D01*
X2903355Y3284467D01*
X2903045Y3285925D01*
X2902115Y3287175D01*
X2901030Y3287592D01*
X2896225D01*
G01X2924590Y3280508D02*
X2924280Y3280717D01*
Y3281133D01*
X2924590Y3281342D01*
X2924900Y3281133D01*
Y3280717D01*
X2924590Y3280508D01*
G01Y3286133D02*
X2924280Y3286342D01*
Y3286758D01*
X2924590Y3286967D01*
X2924900Y3286758D01*
Y3286342D01*
X2924590Y3286133D01*
G01X2945360Y3280925D02*
Y3293425D01*
X2949390Y3283008D01*
X2953420Y3293425D01*
Y3280925D01*
G01X2957915D02*
X2961790Y3293425D01*
X2965665Y3280925D01*
G01X2964270Y3285300D02*
X2959310D01*
G01X2970625Y3280925D02*
Y3293425D01*
X2977755Y3280925D01*
Y3293425D01*
G01X2983180D02*
Y3284467D01*
X2983800Y3282591D01*
X2985040Y3281342D01*
X2986590Y3280925D01*
X2988140Y3281342D01*
X2989380Y3282591D01*
X2990000Y3284467D01*
Y3293425D01*
G01X2996045Y3280925D02*
Y3293425D01*
X3001935D01*
G01X2999765Y3287383D02*
X2996045D01*
G01X3007515Y3280925D02*
X3011390Y3293425D01*
X3015265Y3280925D01*
G01X3013870Y3285300D02*
X3008910D01*
G01X3027200Y3292383D02*
X3026270Y3293008D01*
X3025185Y3293425D01*
X3023945D01*
X3022550Y3292800D01*
X3021465Y3291758D01*
X3020690Y3290508D01*
X3020070Y3288425D01*
X3019915Y3286550D01*
X3020225Y3284675D01*
X3020690Y3283425D01*
X3021620Y3282175D01*
X3022705Y3281342D01*
X3023790Y3280925D01*
X3024875D01*
X3025960Y3281342D01*
X3026890Y3281966D01*
X3027665Y3282800D01*
G01X3036190Y3293425D02*
Y3280925D01*
G01X3032625Y3293425D02*
X3039755D01*
G01X3045180D02*
Y3284467D01*
X3045800Y3282591D01*
X3047040Y3281342D01*
X3048590Y3280925D01*
X3050140Y3281342D01*
X3051380Y3282591D01*
X3052000Y3284467D01*
Y3293425D01*
G01X3057890Y3280925D02*
Y3293425D01*
X3061765D01*
X3063005Y3292800D01*
X3063780Y3291967D01*
X3064090Y3290300D01*
X3063780Y3288633D01*
X3062850Y3287592D01*
X3061765Y3286967D01*
X3057890D01*
G01X3061765D02*
X3064090Y3280925D01*
G01X3071530Y3293425D02*
X3075250D01*
G01X3073390D02*
Y3280925D01*
G01X3071530D02*
X3075250D01*
G01X3082225D02*
Y3293425D01*
X3089355Y3280925D01*
Y3293425D01*
G01X3099120Y3287175D02*
X3102220D01*
Y3283425D01*
X3101290Y3282175D01*
X3100205Y3281342D01*
X3098655Y3280925D01*
X3097105Y3281342D01*
X3096020Y3282175D01*
X3095090Y3283425D01*
X3094470Y3284883D01*
X3094160Y3286550D01*
Y3288008D01*
X3094470Y3289258D01*
X3095090Y3290717D01*
X3096020Y3291967D01*
X3096950Y3292800D01*
X3098190Y3293425D01*
X3099275D01*
X3100515Y3293008D01*
X3101445Y3292175D01*
G01X3119735Y3282591D02*
X3120975Y3281550D01*
X3122370Y3280925D01*
X3123610D01*
X3124850Y3281550D01*
X3125780Y3282591D01*
X3126245Y3284050D01*
X3125935Y3285508D01*
X3125160Y3286758D01*
X3123765Y3287592D01*
X3121905Y3288008D01*
X3120820Y3288842D01*
X3120355Y3290300D01*
X3120665Y3291758D01*
X3121440Y3292800D01*
X3122525Y3293425D01*
X3123610D01*
X3124695Y3293008D01*
X3125625Y3291967D01*
G01X3135390Y3293425D02*
Y3280925D01*
G01X3131825Y3293425D02*
X3138955D01*
G01X3144380D02*
Y3284467D01*
X3145000Y3282591D01*
X3146240Y3281342D01*
X3147790Y3280925D01*
X3149340Y3281342D01*
X3150580Y3282591D01*
X3151200Y3284467D01*
Y3293425D01*
G01X3161430Y3287592D02*
X3162050Y3288217D01*
X3162515Y3289258D01*
X3162825Y3290717D01*
X3162515Y3291967D01*
X3161895Y3292800D01*
X3160810Y3293425D01*
X3156625D01*
Y3280925D01*
X3161740D01*
X3162825Y3281758D01*
X3163445Y3283008D01*
X3163755Y3284467D01*
X3163445Y3285925D01*
X3162515Y3287175D01*
X3161430Y3287592D01*
X3156625D01*
G01X3181890Y3293425D02*
Y3280925D01*
X3188090D01*
G01X3200490D02*
X3194290D01*
Y3293425D01*
X3200490D01*
G01X3198010Y3287383D02*
X3194290D01*
G01X3206225Y3280925D02*
Y3293425D01*
X3213355Y3280925D01*
Y3293425D01*
G01X3223120Y3287175D02*
X3226220D01*
Y3283425D01*
X3225290Y3282175D01*
X3224205Y3281342D01*
X3222655Y3280925D01*
X3221105Y3281342D01*
X3220020Y3282175D01*
X3219090Y3283425D01*
X3218470Y3284883D01*
X3218160Y3286550D01*
Y3288008D01*
X3218470Y3289258D01*
X3219090Y3290717D01*
X3220020Y3291967D01*
X3220950Y3292800D01*
X3222190Y3293425D01*
X3223275D01*
X3224515Y3293008D01*
X3225445Y3292175D01*
G01X3234590Y3293425D02*
Y3280925D01*
G01X3231025Y3293425D02*
X3238155D01*
G01X3243735Y3280925D02*
Y3293425D01*
G01X3250245D02*
Y3280925D01*
G01Y3287175D02*
X3243735D01*
G01X2946135Y3301341D02*
X2947375Y3300300D01*
X2948770Y3299675D01*
X2950010D01*
X2951250Y3300300D01*
X2952180Y3301341D01*
X2952645Y3302800D01*
X2952335Y3304258D01*
X2951560Y3305508D01*
X2950165Y3306342D01*
X2948305Y3306758D01*
X2947220Y3307592D01*
X2946755Y3309050D01*
X2947065Y3310508D01*
X2947840Y3311550D01*
X2948925Y3312175D01*
X2950010D01*
X2951095Y3311758D01*
X2952025Y3310717D01*
G01X2958380Y3312175D02*
Y3303217D01*
X2959000Y3301341D01*
X2960240Y3300092D01*
X2961790Y3299675D01*
X2963340Y3300092D01*
X2964580Y3301341D01*
X2965200Y3303217D01*
Y3312175D01*
G01X2971090Y3299675D02*
Y3312175D01*
X2974965D01*
X2976205Y3311550D01*
X2976980Y3310717D01*
X2977290Y3309050D01*
X2976980Y3307383D01*
X2976050Y3306342D01*
X2974965Y3305717D01*
X2971090D01*
G01X2974965D02*
X2977290Y3299675D01*
G01X2983645D02*
Y3312175D01*
X2989535D01*
G01X2987365Y3306133D02*
X2983645D01*
G01X2995115Y3299675D02*
X2998990Y3312175D01*
X3002865Y3299675D01*
G01X3001470Y3304050D02*
X2996510D01*
G01X3014800Y3311133D02*
X3013870Y3311758D01*
X3012785Y3312175D01*
X3011545D01*
X3010150Y3311550D01*
X3009065Y3310508D01*
X3008290Y3309258D01*
X3007670Y3307175D01*
X3007515Y3305300D01*
X3007825Y3303425D01*
X3008290Y3302175D01*
X3009220Y3300925D01*
X3010305Y3300092D01*
X3011390Y3299675D01*
X3012475D01*
X3013560Y3300092D01*
X3014490Y3300716D01*
X3015265Y3301550D01*
G01X3026890Y3299675D02*
X3020690D01*
Y3312175D01*
X3026890D01*
G01X3024410Y3306133D02*
X3020690D01*
G01X3048590Y3299675D02*
X3047350Y3299883D01*
X3046265Y3300716D01*
X3045335Y3301967D01*
X3044715Y3303425D01*
X3044405Y3305092D01*
Y3306758D01*
X3044715Y3308425D01*
X3045335Y3309883D01*
X3046265Y3311133D01*
X3047350Y3311967D01*
X3048590Y3312175D01*
X3049830Y3311967D01*
X3050915Y3311133D01*
X3051845Y3309883D01*
X3052465Y3308425D01*
X3052775Y3306758D01*
Y3305092D01*
X3052465Y3303425D01*
X3051845Y3301967D01*
X3050915Y3300716D01*
X3049830Y3299883D01*
X3048590Y3299675D01*
G01X3058045D02*
Y3312175D01*
X3063935D01*
G01X3061765Y3306133D02*
X3058045D01*
G01X3081760Y3299675D02*
Y3312175D01*
X3085790Y3301758D01*
X3089820Y3312175D01*
Y3299675D01*
G01X3094780Y3312175D02*
Y3303217D01*
X3095400Y3301341D01*
X3096640Y3300092D01*
X3098190Y3299675D01*
X3099740Y3300092D01*
X3100980Y3301341D01*
X3101600Y3303217D01*
Y3312175D01*
G01X3107335Y3301341D02*
X3108575Y3300300D01*
X3109970Y3299675D01*
X3111210D01*
X3112450Y3300300D01*
X3113380Y3301341D01*
X3113845Y3302800D01*
X3113535Y3304258D01*
X3112760Y3305508D01*
X3111365Y3306342D01*
X3109505Y3306758D01*
X3108420Y3307592D01*
X3107955Y3309050D01*
X3108265Y3310508D01*
X3109040Y3311550D01*
X3110125Y3312175D01*
X3111210D01*
X3112295Y3311758D01*
X3113225Y3310717D01*
G01X3122990Y3312175D02*
Y3299675D01*
G01X3119425Y3312175D02*
X3126555D01*
G01X3133375Y3303842D02*
X3137405D01*
G01X3144225Y3299675D02*
Y3312175D01*
X3151355Y3299675D01*
Y3312175D01*
G01X3160190Y3299675D02*
X3158950Y3299883D01*
X3157865Y3300716D01*
X3156935Y3301967D01*
X3156315Y3303425D01*
X3156005Y3305092D01*
Y3306758D01*
X3156315Y3308425D01*
X3156935Y3309883D01*
X3157865Y3311133D01*
X3158950Y3311967D01*
X3160190Y3312175D01*
X3161430Y3311967D01*
X3162515Y3311133D01*
X3163445Y3309883D01*
X3164065Y3308425D01*
X3164375Y3306758D01*
Y3305092D01*
X3164065Y3303425D01*
X3163445Y3301967D01*
X3162515Y3300716D01*
X3161430Y3299883D01*
X3160190Y3299675D01*
G01X3172590Y3312175D02*
Y3299675D01*
G01X3169025Y3312175D02*
X3176155D01*
G01X3182975Y3303842D02*
X3187005D01*
G01X3200800Y3311133D02*
X3199870Y3311758D01*
X3198785Y3312175D01*
X3197545D01*
X3196150Y3311550D01*
X3195065Y3310508D01*
X3194290Y3309258D01*
X3193670Y3307175D01*
X3193515Y3305300D01*
X3193825Y3303425D01*
X3194290Y3302175D01*
X3195220Y3300925D01*
X3196305Y3300092D01*
X3197390Y3299675D01*
X3198475D01*
X3199560Y3300092D01*
X3200490Y3300716D01*
X3201265Y3301550D01*
G01X3206380Y3312175D02*
Y3303217D01*
X3207000Y3301341D01*
X3208240Y3300092D01*
X3209790Y3299675D01*
X3211340Y3300092D01*
X3212580Y3301341D01*
X3213200Y3303217D01*
Y3312175D01*
G01X3222190D02*
Y3299675D01*
G01X3218625Y3312175D02*
X3225755D01*
G01X3232575Y3303842D02*
X3236605D01*
G01X3243890Y3312175D02*
Y3299675D01*
X3250090D01*
G01X3255515D02*
X3259390Y3312175D01*
X3263265Y3299675D01*
G01X3261870Y3304050D02*
X3256910D01*
G01X3271790Y3299675D02*
Y3305300D01*
X3268690Y3312175D01*
G01X3274890D02*
X3271790Y3305300D01*
G01X3287290Y3299675D02*
X3281090D01*
Y3312175D01*
X3287290D01*
G01X3284810Y3306133D02*
X3281090D01*
G01X3293490Y3299675D02*
Y3312175D01*
X3297365D01*
X3298605Y3311550D01*
X3299380Y3310717D01*
X3299690Y3309050D01*
X3299380Y3307383D01*
X3298450Y3306342D01*
X3297365Y3305717D01*
X3293490D01*
G01X3297365D02*
X3299690Y3299675D01*
G01X2786175Y3322592D02*
X2790205D01*
G01X2808960Y3318425D02*
Y3330925D01*
X2812990Y3320508D01*
X2817020Y3330925D01*
Y3318425D01*
G01X2821515D02*
X2825390Y3330925D01*
X2829265Y3318425D01*
G01X2827870Y3322800D02*
X2822910D01*
G01X2834535Y3318425D02*
X2841045Y3330925D01*
G01X2834535D02*
X2841045Y3318425D01*
G01X2845540Y3314258D02*
X2854840D01*
G01X2859180Y3318425D02*
Y3330925D01*
X2862280D01*
X2863520Y3330300D01*
X2864450Y3329467D01*
X2865225Y3328217D01*
X2865845Y3326758D01*
X2866000Y3324675D01*
X2865845Y3322592D01*
X2865225Y3321133D01*
X2864450Y3319883D01*
X2863520Y3319050D01*
X2862280Y3318425D01*
X2859180D01*
G01X2878090D02*
X2871890D01*
Y3330925D01*
X2878090D01*
G01X2875610Y3324883D02*
X2871890D01*
G01X2884290Y3318425D02*
Y3330925D01*
X2888010D01*
X2889250Y3330300D01*
X2890180Y3328842D01*
X2890490Y3327175D01*
X2890180Y3325508D01*
X2889405Y3324258D01*
X2888010Y3323633D01*
X2884290D01*
G01X2899790Y3330925D02*
Y3318425D01*
G01X2896225Y3330925D02*
X2903355D01*
G01X2908935Y3318425D02*
Y3330925D01*
G01X2915445D02*
Y3318425D01*
G01Y3324675D02*
X2908935D01*
G01X2924590Y3318008D02*
X2924280Y3318217D01*
Y3318633D01*
X2924590Y3318842D01*
X2924900Y3318633D01*
Y3318217D01*
X2924590Y3318008D01*
G01Y3323633D02*
X2924280Y3323842D01*
Y3324258D01*
X2924590Y3324467D01*
X2924900Y3324258D01*
Y3323842D01*
X2924590Y3323633D01*
G01X2945980Y3318425D02*
Y3330925D01*
X2949080D01*
X2950320Y3330300D01*
X2951250Y3329467D01*
X2952025Y3328217D01*
X2952645Y3326758D01*
X2952800Y3324675D01*
X2952645Y3322592D01*
X2952025Y3321133D01*
X2951250Y3319883D01*
X2950320Y3319050D01*
X2949080Y3318425D01*
X2945980D01*
G01X2964890D02*
X2958690D01*
Y3330925D01*
X2964890D01*
G01X2962410Y3324883D02*
X2958690D01*
G01X2971090Y3318425D02*
Y3330925D01*
X2974810D01*
X2976050Y3330300D01*
X2976980Y3328842D01*
X2977290Y3327175D01*
X2976980Y3325508D01*
X2976205Y3324258D01*
X2974810Y3323633D01*
X2971090D01*
G01X2986590Y3330925D02*
Y3318425D01*
G01X2983025Y3330925D02*
X2990155D01*
G01X2995735Y3318425D02*
Y3330925D01*
G01X3002245D02*
Y3318425D01*
G01Y3324675D02*
X2995735D01*
G01X3020845Y3318425D02*
Y3330925D01*
X3026735D01*
G01X3024565Y3324883D02*
X3020845D01*
G01X3033090Y3318425D02*
Y3330925D01*
X3036965D01*
X3038205Y3330300D01*
X3038980Y3329467D01*
X3039290Y3327800D01*
X3038980Y3326133D01*
X3038050Y3325092D01*
X3036965Y3324467D01*
X3033090D01*
G01X3036965D02*
X3039290Y3318425D01*
G01X3048590D02*
X3047350Y3318633D01*
X3046265Y3319466D01*
X3045335Y3320717D01*
X3044715Y3322175D01*
X3044405Y3323842D01*
Y3325508D01*
X3044715Y3327175D01*
X3045335Y3328633D01*
X3046265Y3329883D01*
X3047350Y3330717D01*
X3048590Y3330925D01*
X3049830Y3330717D01*
X3050915Y3329883D01*
X3051845Y3328633D01*
X3052465Y3327175D01*
X3052775Y3325508D01*
Y3323842D01*
X3052465Y3322175D01*
X3051845Y3320717D01*
X3050915Y3319466D01*
X3049830Y3318633D01*
X3048590Y3318425D01*
G01X3056960D02*
Y3330925D01*
X3060990Y3320508D01*
X3065020Y3330925D01*
Y3318425D01*
G01X3082535Y3320091D02*
X3083775Y3319050D01*
X3085170Y3318425D01*
X3086410D01*
X3087650Y3319050D01*
X3088580Y3320091D01*
X3089045Y3321550D01*
X3088735Y3323008D01*
X3087960Y3324258D01*
X3086565Y3325092D01*
X3084705Y3325508D01*
X3083620Y3326342D01*
X3083155Y3327800D01*
X3083465Y3329258D01*
X3084240Y3330300D01*
X3085325Y3330925D01*
X3086410D01*
X3087495Y3330508D01*
X3088425Y3329467D01*
G01X3098190Y3330925D02*
Y3318425D01*
G01X3094625Y3330925D02*
X3101755D01*
G01X3106715Y3318425D02*
X3110590Y3330925D01*
X3114465Y3318425D01*
G01X3113070Y3322800D02*
X3108110D01*
G01X3119890Y3318425D02*
Y3330925D01*
X3123765D01*
X3125005Y3330300D01*
X3125780Y3329467D01*
X3126090Y3327800D01*
X3125780Y3326133D01*
X3124850Y3325092D01*
X3123765Y3324467D01*
X3119890D01*
G01X3123765D02*
X3126090Y3318425D01*
G01X3135390Y3330925D02*
Y3318425D01*
G01X3131825Y3330925D02*
X3138955D01*
G01X3157090D02*
Y3318425D01*
X3163290D01*
G01X3168715D02*
X3172590Y3330925D01*
X3176465Y3318425D01*
G01X3175070Y3322800D02*
X3170110D01*
G01X3184990Y3318425D02*
Y3324050D01*
X3181890Y3330925D01*
G01X3188090D02*
X3184990Y3324050D01*
G01X3200490Y3318425D02*
X3194290D01*
Y3330925D01*
X3200490D01*
G01X3198010Y3324883D02*
X3194290D01*
G01X3206690Y3318425D02*
Y3330925D01*
X3210565D01*
X3211805Y3330300D01*
X3212580Y3329467D01*
X3212890Y3327800D01*
X3212580Y3326133D01*
X3211650Y3325092D01*
X3210565Y3324467D01*
X3206690D01*
G01X3210565D02*
X3212890Y3318425D01*
G01X3234590Y3330925D02*
Y3318425D01*
G01X3231025Y3330925D02*
X3238155D01*
G01X3246990Y3318425D02*
X3245750Y3318633D01*
X3244665Y3319466D01*
X3243735Y3320717D01*
X3243115Y3322175D01*
X3242805Y3323842D01*
Y3325508D01*
X3243115Y3327175D01*
X3243735Y3328633D01*
X3244665Y3329883D01*
X3245750Y3330717D01*
X3246990Y3330925D01*
X3248230Y3330717D01*
X3249315Y3329883D01*
X3250245Y3328633D01*
X3250865Y3327175D01*
X3251175Y3325508D01*
Y3323842D01*
X3250865Y3322175D01*
X3250245Y3320717D01*
X3249315Y3319466D01*
X3248230Y3318633D01*
X3246990Y3318425D01*
G01X3271790Y3330925D02*
Y3318425D01*
G01X3268225Y3330925D02*
X3275355D01*
G01X3280935Y3318425D02*
Y3330925D01*
G01X3287445D02*
Y3318425D01*
G01Y3324675D02*
X3280935D01*
G01X3299690Y3318425D02*
X3293490D01*
Y3330925D01*
X3299690D01*
G01X3297210Y3324883D02*
X3293490D01*
G01X2786175Y3341342D02*
X2790205D01*
G01X2808960Y3337175D02*
Y3349675D01*
X2812990Y3339258D01*
X2817020Y3349675D01*
Y3337175D01*
G01X2821825D02*
Y3349675D01*
X2828955Y3337175D01*
Y3349675D01*
G01X2841200Y3348633D02*
X2840270Y3349258D01*
X2839185Y3349675D01*
X2837945D01*
X2836550Y3349050D01*
X2835465Y3348008D01*
X2834690Y3346758D01*
X2834070Y3344675D01*
X2833915Y3342800D01*
X2834225Y3340925D01*
X2834690Y3339675D01*
X2835620Y3338425D01*
X2836705Y3337592D01*
X2837790Y3337175D01*
X2838875D01*
X2839960Y3337592D01*
X2840890Y3338216D01*
X2841665Y3339050D01*
G01X2845540Y3333008D02*
X2854840D01*
G01X2859490Y3349675D02*
Y3337175D01*
X2865690D01*
G01X2871115D02*
X2874990Y3349675D01*
X2878865Y3337175D01*
G01X2877470Y3341550D02*
X2872510D01*
G01X2887390Y3337175D02*
Y3342800D01*
X2884290Y3349675D01*
G01X2890490D02*
X2887390Y3342800D01*
G01X2902890Y3337175D02*
X2896690D01*
Y3349675D01*
X2902890D01*
G01X2900410Y3343633D02*
X2896690D01*
G01X2909090Y3337175D02*
Y3349675D01*
X2912965D01*
X2914205Y3349050D01*
X2914980Y3348217D01*
X2915290Y3346550D01*
X2914980Y3344883D01*
X2914050Y3343842D01*
X2912965Y3343217D01*
X2909090D01*
G01X2912965D02*
X2915290Y3337175D01*
G01X2924590Y3336758D02*
X2924280Y3336967D01*
Y3337383D01*
X2924590Y3337592D01*
X2924900Y3337383D01*
Y3336967D01*
X2924590Y3336758D01*
G01Y3342383D02*
X2924280Y3342592D01*
Y3343008D01*
X2924590Y3343217D01*
X2924900Y3343008D01*
Y3342592D01*
X2924590Y3342383D01*
G01X2945360Y3337175D02*
Y3349675D01*
X2949390Y3339258D01*
X2953420Y3349675D01*
Y3337175D01*
G01X2958380Y3349675D02*
Y3340717D01*
X2959000Y3338841D01*
X2960240Y3337592D01*
X2961790Y3337175D01*
X2963340Y3337592D01*
X2964580Y3338841D01*
X2965200Y3340717D01*
Y3349675D01*
G01X2970935Y3338841D02*
X2972175Y3337800D01*
X2973570Y3337175D01*
X2974810D01*
X2976050Y3337800D01*
X2976980Y3338841D01*
X2977445Y3340300D01*
X2977135Y3341758D01*
X2976360Y3343008D01*
X2974965Y3343842D01*
X2973105Y3344258D01*
X2972020Y3345092D01*
X2971555Y3346550D01*
X2971865Y3348008D01*
X2972640Y3349050D01*
X2973725Y3349675D01*
X2974810D01*
X2975895Y3349258D01*
X2976825Y3348217D01*
G01X2986590Y3349675D02*
Y3337175D01*
G01X2983025Y3349675D02*
X2990155D01*
G01X2996975Y3341342D02*
X3001005D01*
G01X3007825Y3337175D02*
Y3349675D01*
X3014955Y3337175D01*
Y3349675D01*
G01X3023790Y3337175D02*
X3022550Y3337383D01*
X3021465Y3338216D01*
X3020535Y3339467D01*
X3019915Y3340925D01*
X3019605Y3342592D01*
Y3344258D01*
X3019915Y3345925D01*
X3020535Y3347383D01*
X3021465Y3348633D01*
X3022550Y3349467D01*
X3023790Y3349675D01*
X3025030Y3349467D01*
X3026115Y3348633D01*
X3027045Y3347383D01*
X3027665Y3345925D01*
X3027975Y3344258D01*
Y3342592D01*
X3027665Y3340925D01*
X3027045Y3339467D01*
X3026115Y3338216D01*
X3025030Y3337383D01*
X3023790Y3337175D01*
G01X3036190Y3349675D02*
Y3337175D01*
G01X3032625Y3349675D02*
X3039755D01*
G01X3046575Y3341342D02*
X3050605D01*
G01X3064400Y3348633D02*
X3063470Y3349258D01*
X3062385Y3349675D01*
X3061145D01*
X3059750Y3349050D01*
X3058665Y3348008D01*
X3057890Y3346758D01*
X3057270Y3344675D01*
X3057115Y3342800D01*
X3057425Y3340925D01*
X3057890Y3339675D01*
X3058820Y3338425D01*
X3059905Y3337592D01*
X3060990Y3337175D01*
X3062075D01*
X3063160Y3337592D01*
X3064090Y3338216D01*
X3064865Y3339050D01*
G01X3069980Y3349675D02*
Y3340717D01*
X3070600Y3338841D01*
X3071840Y3337592D01*
X3073390Y3337175D01*
X3074940Y3337592D01*
X3076180Y3338841D01*
X3076800Y3340717D01*
Y3349675D01*
G01X3085790D02*
Y3337175D01*
G01X3082225Y3349675D02*
X3089355D01*
G01X3096175Y3341342D02*
X3100205D01*
G01X3107490Y3349675D02*
Y3337175D01*
X3113690D01*
G01X3119115D02*
X3122990Y3349675D01*
X3126865Y3337175D01*
G01X3125470Y3341550D02*
X3120510D01*
G01X3135390Y3337175D02*
Y3342800D01*
X3132290Y3349675D01*
G01X3138490D02*
X3135390Y3342800D01*
G01X3150890Y3337175D02*
X3144690D01*
Y3349675D01*
X3150890D01*
G01X3148410Y3343633D02*
X3144690D01*
G01X3157090Y3337175D02*
Y3349675D01*
X3160965D01*
X3162205Y3349050D01*
X3162980Y3348217D01*
X3163290Y3346550D01*
X3162980Y3344883D01*
X3162050Y3343842D01*
X3160965Y3343217D01*
X3157090D01*
G01X3160965D02*
X3163290Y3337175D01*
G01X2784625Y3355925D02*
Y3368425D01*
X2791755Y3355925D01*
Y3368425D01*
G01X2800590Y3355925D02*
X2799350Y3356133D01*
X2798265Y3356966D01*
X2797335Y3358217D01*
X2796715Y3359675D01*
X2796405Y3361342D01*
Y3363008D01*
X2796715Y3364675D01*
X2797335Y3366133D01*
X2798265Y3367383D01*
X2799350Y3368217D01*
X2800590Y3368425D01*
X2801830Y3368217D01*
X2802915Y3367383D01*
X2803845Y3366133D01*
X2804465Y3364675D01*
X2804775Y3363008D01*
Y3361342D01*
X2804465Y3359675D01*
X2803845Y3358217D01*
X2802915Y3356966D01*
X2801830Y3356133D01*
X2800590Y3355925D01*
G01X2812990Y3368425D02*
Y3355925D01*
G01X2809425Y3368425D02*
X2816555D01*
G01X2828490Y3355925D02*
X2822290D01*
Y3368425D01*
X2828490D01*
G01X2826010Y3362383D02*
X2822290D01*
G01X2834535Y3357591D02*
X2835775Y3356550D01*
X2837170Y3355925D01*
X2838410D01*
X2839650Y3356550D01*
X2840580Y3357591D01*
X2841045Y3359050D01*
X2840735Y3360508D01*
X2839960Y3361758D01*
X2838565Y3362592D01*
X2836705Y3363008D01*
X2835620Y3363842D01*
X2835155Y3365300D01*
X2835465Y3366758D01*
X2836240Y3367800D01*
X2837325Y3368425D01*
X2838410D01*
X2839495Y3368008D01*
X2840425Y3366967D01*
G01X2850190Y3355508D02*
X2849880Y3355717D01*
Y3356133D01*
X2850190Y3356342D01*
X2850500Y3356133D01*
Y3355717D01*
X2850190Y3355508D01*
G01Y3361133D02*
X2849880Y3361342D01*
Y3361758D01*
X2850190Y3361967D01*
X2850500Y3361758D01*
Y3361342D01*
X2850190Y3361133D01*
G01X2794545Y3430925D02*
Y3443425D01*
X2800435D01*
G01X2798265Y3437383D02*
X2794545D01*
G01X2808030Y3443425D02*
X2811750D01*
G01X2809890D02*
Y3430925D01*
G01X2808030D02*
X2811750D01*
G01X2823220Y3437175D02*
X2826320D01*
Y3433425D01*
X2825390Y3432175D01*
X2824305Y3431342D01*
X2822755Y3430925D01*
X2821205Y3431342D01*
X2820120Y3432175D01*
X2819190Y3433425D01*
X2818570Y3434883D01*
X2818260Y3436550D01*
Y3438008D01*
X2818570Y3439258D01*
X2819190Y3440717D01*
X2820120Y3441967D01*
X2821050Y3442800D01*
X2822290Y3443425D01*
X2823375D01*
X2824615Y3443008D01*
X2825545Y3442175D01*
G01X2831280Y3443425D02*
Y3434467D01*
X2831900Y3432591D01*
X2833140Y3431342D01*
X2834690Y3430925D01*
X2836240Y3431342D01*
X2837480Y3432591D01*
X2838100Y3434467D01*
Y3443425D01*
G01X2843990Y3430925D02*
Y3443425D01*
X2847865D01*
X2849105Y3442800D01*
X2849880Y3441967D01*
X2850190Y3440300D01*
X2849880Y3438633D01*
X2848950Y3437592D01*
X2847865Y3436967D01*
X2843990D01*
G01X2847865D02*
X2850190Y3430925D01*
G01X2862590D02*
X2856390D01*
Y3443425D01*
X2862590D01*
G01X2860110Y3437383D02*
X2856390D01*
G01X2955735Y3529304D02*
X2956355Y3529929D01*
X2956820Y3530970D01*
X2957130Y3532429D01*
X2956820Y3533679D01*
X2956200Y3534512D01*
X2955115Y3535137D01*
X2950930D01*
Y3522637D01*
X2956045D01*
X2957130Y3523470D01*
X2957750Y3524720D01*
X2958060Y3526179D01*
X2957750Y3527637D01*
X2956820Y3528887D01*
X2955735Y3529304D01*
X2950930D01*
G01X2963020Y3522637D02*
X2966895Y3535137D01*
X2970770Y3522637D01*
G01X2969375Y3527012D02*
X2964415D01*
G01X2982705Y3534095D02*
X2981775Y3534720D01*
X2980690Y3535137D01*
X2979450D01*
X2978055Y3534512D01*
X2976970Y3533470D01*
X2976195Y3532220D01*
X2975575Y3530137D01*
X2975420Y3528262D01*
X2975730Y3526387D01*
X2976195Y3525137D01*
X2977125Y3523887D01*
X2978210Y3523054D01*
X2979295Y3522637D01*
X2980380D01*
X2981465Y3523054D01*
X2982395Y3523678D01*
X2983170Y3524512D01*
G01X2988285Y3522637D02*
Y3535137D01*
G01X2994175D02*
X2988285Y3527428D01*
G01X2995105Y3522637D02*
X2990920Y3530970D01*
G01X3000685Y3522637D02*
Y3535137D01*
X3003785D01*
X3005025Y3534512D01*
X3005955Y3533679D01*
X3006730Y3532429D01*
X3007350Y3530970D01*
X3007505Y3528887D01*
X3007350Y3526804D01*
X3006730Y3525345D01*
X3005955Y3524095D01*
X3005025Y3523262D01*
X3003785Y3522637D01*
X3000685D01*
G01X3013395D02*
Y3535137D01*
X3017270D01*
X3018510Y3534512D01*
X3019285Y3533679D01*
X3019595Y3532012D01*
X3019285Y3530345D01*
X3018355Y3529304D01*
X3017270Y3528679D01*
X3013395D01*
G01X3017270D02*
X3019595Y3522637D01*
G01X3027035Y3535137D02*
X3030755D01*
G01X3028895D02*
Y3522637D01*
G01X3027035D02*
X3030755D01*
G01X3038195Y3535137D02*
Y3522637D01*
X3044395D01*
G01X3050595Y3535137D02*
Y3522637D01*
X3056795D01*
G01X3075240Y3524303D02*
X3076480Y3523262D01*
X3077875Y3522637D01*
X3079115D01*
X3080355Y3523262D01*
X3081285Y3524303D01*
X3081750Y3525762D01*
X3081440Y3527220D01*
X3080665Y3528470D01*
X3079270Y3529304D01*
X3077410Y3529720D01*
X3076325Y3530554D01*
X3075860Y3532012D01*
X3076170Y3533470D01*
X3076945Y3534512D01*
X3078030Y3535137D01*
X3079115D01*
X3080200Y3534720D01*
X3081130Y3533679D01*
G01X3090895Y3535137D02*
Y3522637D01*
G01X3087330Y3535137D02*
X3094460D01*
G01X3099885D02*
Y3526179D01*
X3100505Y3524303D01*
X3101745Y3523054D01*
X3103295Y3522637D01*
X3104845Y3523054D01*
X3106085Y3524303D01*
X3106705Y3526179D01*
Y3535137D01*
G01X3116935Y3529304D02*
X3117555Y3529929D01*
X3118020Y3530970D01*
X3118330Y3532429D01*
X3118020Y3533679D01*
X3117400Y3534512D01*
X3116315Y3535137D01*
X3112130D01*
Y3522637D01*
X3117245D01*
X3118330Y3523470D01*
X3118950Y3524720D01*
X3119260Y3526179D01*
X3118950Y3527637D01*
X3118020Y3528887D01*
X3116935Y3529304D01*
X3112130D01*
G01X3137395Y3535137D02*
Y3522637D01*
X3143595D01*
G01X3155995D02*
X3149795D01*
Y3535137D01*
X3155995D01*
G01X3153515Y3529095D02*
X3149795D01*
G01X3161730Y3522637D02*
Y3535137D01*
X3168860Y3522637D01*
Y3535137D01*
G01X3178625Y3528887D02*
X3181725D01*
Y3525137D01*
X3180795Y3523887D01*
X3179710Y3523054D01*
X3178160Y3522637D01*
X3176610Y3523054D01*
X3175525Y3523887D01*
X3174595Y3525137D01*
X3173975Y3526595D01*
X3173665Y3528262D01*
Y3529720D01*
X3173975Y3530970D01*
X3174595Y3532429D01*
X3175525Y3533679D01*
X3176455Y3534512D01*
X3177695Y3535137D01*
X3178780D01*
X3180020Y3534720D01*
X3180950Y3533887D01*
G01X3190095Y3535137D02*
Y3522637D01*
G01X3186530Y3535137D02*
X3193660D01*
G01X3199240Y3522637D02*
Y3535137D01*
G01X3205750D02*
Y3522637D01*
G01Y3528887D02*
X3199240D01*
G01X3227295Y3535137D02*
Y3522637D01*
G01X3223730Y3535137D02*
X3230860D01*
G01X3239695Y3522637D02*
X3238455Y3522845D01*
X3237370Y3523678D01*
X3236440Y3524929D01*
X3235820Y3526387D01*
X3235510Y3528054D01*
Y3529720D01*
X3235820Y3531387D01*
X3236440Y3532845D01*
X3237370Y3534095D01*
X3238455Y3534929D01*
X3239695Y3535137D01*
X3240935Y3534929D01*
X3242020Y3534095D01*
X3242950Y3532845D01*
X3243570Y3531387D01*
X3243880Y3529720D01*
Y3528054D01*
X3243570Y3526387D01*
X3242950Y3524929D01*
X3242020Y3523678D01*
X3240935Y3522845D01*
X3239695Y3522637D01*
G01X3248995Y3535137D02*
Y3522637D01*
X3255195D01*
G01X3267595D02*
X3261395D01*
Y3535137D01*
X3267595D01*
G01X3265115Y3529095D02*
X3261395D01*
G01X3273795Y3522637D02*
Y3535137D01*
X3277670D01*
X3278910Y3534512D01*
X3279685Y3533679D01*
X3279995Y3532012D01*
X3279685Y3530345D01*
X3278755Y3529304D01*
X3277670Y3528679D01*
X3273795D01*
G01X3277670D02*
X3279995Y3522637D01*
G01X3285420D02*
X3289295Y3535137D01*
X3293170Y3522637D01*
G01X3291775Y3527012D02*
X3286815D01*
G01X3298130Y3522637D02*
Y3535137D01*
X3305260Y3522637D01*
Y3535137D01*
G01X3317505Y3534095D02*
X3316575Y3534720D01*
X3315490Y3535137D01*
X3314250D01*
X3312855Y3534512D01*
X3311770Y3533470D01*
X3310995Y3532220D01*
X3310375Y3530137D01*
X3310220Y3528262D01*
X3310530Y3526387D01*
X3310995Y3525137D01*
X3311925Y3523887D01*
X3313010Y3523054D01*
X3314095Y3522637D01*
X3315180D01*
X3316265Y3523054D01*
X3317195Y3523678D01*
X3317970Y3524512D01*
G01X3329595Y3522637D02*
X3323395D01*
Y3535137D01*
X3329595D01*
G01X3327115Y3529095D02*
X3323395D01*
G01X3351295Y3535137D02*
Y3522637D01*
G01X3347730Y3535137D02*
X3354860D01*
G01X3363695Y3522637D02*
X3362455Y3522845D01*
X3361370Y3523678D01*
X3360440Y3524929D01*
X3359820Y3526387D01*
X3359510Y3528054D01*
Y3529720D01*
X3359820Y3531387D01*
X3360440Y3532845D01*
X3361370Y3534095D01*
X3362455Y3534929D01*
X3363695Y3535137D01*
X3364935Y3534929D01*
X3366020Y3534095D01*
X3366950Y3532845D01*
X3367570Y3531387D01*
X3367880Y3529720D01*
Y3528054D01*
X3367570Y3526387D01*
X3366950Y3524929D01*
X3366020Y3523678D01*
X3364935Y3522845D01*
X3363695Y3522637D01*
G01X3389735Y3529304D02*
X3390355Y3529929D01*
X3390820Y3530970D01*
X3391130Y3532429D01*
X3390820Y3533679D01*
X3390200Y3534512D01*
X3389115Y3535137D01*
X3384930D01*
Y3522637D01*
X3390045D01*
X3391130Y3523470D01*
X3391750Y3524720D01*
X3392060Y3526179D01*
X3391750Y3527637D01*
X3390820Y3528887D01*
X3389735Y3529304D01*
X3384930D01*
G01X3403995Y3522637D02*
X3397795D01*
Y3535137D01*
X3403995D01*
G01X3401515Y3529095D02*
X3397795D01*
G01X3425385Y3522637D02*
X3425695Y3525345D01*
X3426160Y3527637D01*
X3426780Y3529720D01*
X3427555Y3532012D01*
X3428795Y3535137D01*
X3422595D01*
G01X3448790Y3526804D02*
X3452510D01*
G01X3450495Y3529512D02*
Y3524095D01*
G01X3460105Y3522220D02*
X3465685Y3535137D01*
G01X3473280Y3526804D02*
X3477310D01*
G01X3484285Y3524512D02*
X3485215Y3523470D01*
X3486300Y3522845D01*
X3487695Y3522637D01*
X3489090Y3523054D01*
X3490175Y3523887D01*
X3490950Y3525345D01*
X3491105Y3527012D01*
X3490795Y3528679D01*
X3490020Y3529720D01*
X3488935Y3530554D01*
X3487850Y3530762D01*
X3486765Y3530554D01*
X3485370Y3529720D01*
X3485835Y3535137D01*
X3490020D01*
G01X3508465Y3522637D02*
Y3535137D01*
X3512495Y3524720D01*
X3516525Y3535137D01*
Y3522637D01*
G01X3523035Y3535137D02*
X3526755D01*
G01X3524895D02*
Y3522637D01*
G01X3523035D02*
X3526755D01*
G01X3534195Y3535137D02*
Y3522637D01*
X3540395D01*
G01X3546440Y3524303D02*
X3547680Y3523262D01*
X3549075Y3522637D01*
X3550315D01*
X3551555Y3523262D01*
X3552485Y3524303D01*
X3552950Y3525762D01*
X3552640Y3527220D01*
X3551865Y3528470D01*
X3550470Y3529304D01*
X3548610Y3529720D01*
X3547525Y3530554D01*
X3547060Y3532012D01*
X3547370Y3533470D01*
X3548145Y3534512D01*
X3549230Y3535137D01*
X3550315D01*
X3551400Y3534720D01*
X3552330Y3533679D01*
G01X2791280Y3545554D02*
X2795310D01*
G01X2814065Y3541387D02*
Y3553887D01*
X2818095Y3543470D01*
X2822125Y3553887D01*
Y3541387D01*
G01X2827550D02*
Y3553887D01*
X2833440D01*
G01X2831270Y3547845D02*
X2827550D01*
G01X2843825Y3547637D02*
X2846925D01*
Y3543887D01*
X2845995Y3542637D01*
X2844910Y3541804D01*
X2843360Y3541387D01*
X2841810Y3541804D01*
X2840725Y3542637D01*
X2839795Y3543887D01*
X2839175Y3545345D01*
X2838865Y3547012D01*
Y3548470D01*
X2839175Y3549720D01*
X2839795Y3551179D01*
X2840725Y3552429D01*
X2841655Y3553262D01*
X2842895Y3553887D01*
X2843980D01*
X2845220Y3553470D01*
X2846150Y3552637D01*
G01X2850645Y3537220D02*
X2859945D01*
G01X2864440Y3543053D02*
X2865680Y3542012D01*
X2867075Y3541387D01*
X2868315D01*
X2869555Y3542012D01*
X2870485Y3543053D01*
X2870950Y3544512D01*
X2870640Y3545970D01*
X2869865Y3547220D01*
X2868470Y3548054D01*
X2866610Y3548470D01*
X2865525Y3549304D01*
X2865060Y3550762D01*
X2865370Y3552220D01*
X2866145Y3553262D01*
X2867230Y3553887D01*
X2868315D01*
X2869400Y3553470D01*
X2870330Y3552429D01*
G01X2880095Y3553887D02*
Y3541387D01*
G01X2876530Y3553887D02*
X2883660D01*
G01X2889085D02*
Y3544929D01*
X2889705Y3543053D01*
X2890945Y3541804D01*
X2892495Y3541387D01*
X2894045Y3541804D01*
X2895285Y3543053D01*
X2895905Y3544929D01*
Y3553887D01*
G01X2906135Y3548054D02*
X2906755Y3548679D01*
X2907220Y3549720D01*
X2907530Y3551179D01*
X2907220Y3552429D01*
X2906600Y3553262D01*
X2905515Y3553887D01*
X2901330D01*
Y3541387D01*
X2906445D01*
X2907530Y3542220D01*
X2908150Y3543470D01*
X2908460Y3544929D01*
X2908150Y3546387D01*
X2907220Y3547637D01*
X2906135Y3548054D01*
X2901330D01*
G01X2929695Y3540970D02*
X2929385Y3541179D01*
Y3541595D01*
X2929695Y3541804D01*
X2930005Y3541595D01*
Y3541179D01*
X2929695Y3540970D01*
G01Y3546595D02*
X2929385Y3546804D01*
Y3547220D01*
X2929695Y3547429D01*
X2930005Y3547220D01*
Y3546804D01*
X2929695Y3546595D01*
G01X2950465Y3541387D02*
Y3553887D01*
X2954495Y3543470D01*
X2958525Y3553887D01*
Y3541387D01*
G01X2963020D02*
X2966895Y3553887D01*
X2970770Y3541387D01*
G01X2969375Y3545762D02*
X2964415D01*
G01X2975730Y3541387D02*
Y3553887D01*
X2982860Y3541387D01*
Y3553887D01*
G01X2988285D02*
Y3544929D01*
X2988905Y3543053D01*
X2990145Y3541804D01*
X2991695Y3541387D01*
X2993245Y3541804D01*
X2994485Y3543053D01*
X2995105Y3544929D01*
Y3553887D01*
G01X3001150Y3541387D02*
Y3553887D01*
X3007040D01*
G01X3004870Y3547845D02*
X3001150D01*
G01X3012620Y3541387D02*
X3016495Y3553887D01*
X3020370Y3541387D01*
G01X3018975Y3545762D02*
X3014015D01*
G01X3032305Y3552845D02*
X3031375Y3553470D01*
X3030290Y3553887D01*
X3029050D01*
X3027655Y3553262D01*
X3026570Y3552220D01*
X3025795Y3550970D01*
X3025175Y3548887D01*
X3025020Y3547012D01*
X3025330Y3545137D01*
X3025795Y3543887D01*
X3026725Y3542637D01*
X3027810Y3541804D01*
X3028895Y3541387D01*
X3029980D01*
X3031065Y3541804D01*
X3031995Y3542428D01*
X3032770Y3543262D01*
G01X3041295Y3553887D02*
Y3541387D01*
G01X3037730Y3553887D02*
X3044860D01*
G01X3050285D02*
Y3544929D01*
X3050905Y3543053D01*
X3052145Y3541804D01*
X3053695Y3541387D01*
X3055245Y3541804D01*
X3056485Y3543053D01*
X3057105Y3544929D01*
Y3553887D01*
G01X3062995Y3541387D02*
Y3553887D01*
X3066870D01*
X3068110Y3553262D01*
X3068885Y3552429D01*
X3069195Y3550762D01*
X3068885Y3549095D01*
X3067955Y3548054D01*
X3066870Y3547429D01*
X3062995D01*
G01X3066870D02*
X3069195Y3541387D01*
G01X3076635Y3553887D02*
X3080355D01*
G01X3078495D02*
Y3541387D01*
G01X3076635D02*
X3080355D01*
G01X3087330D02*
Y3553887D01*
X3094460Y3541387D01*
Y3553887D01*
G01X3104225Y3547637D02*
X3107325D01*
Y3543887D01*
X3106395Y3542637D01*
X3105310Y3541804D01*
X3103760Y3541387D01*
X3102210Y3541804D01*
X3101125Y3542637D01*
X3100195Y3543887D01*
X3099575Y3545345D01*
X3099265Y3547012D01*
Y3548470D01*
X3099575Y3549720D01*
X3100195Y3551179D01*
X3101125Y3552429D01*
X3102055Y3553262D01*
X3103295Y3553887D01*
X3104380D01*
X3105620Y3553470D01*
X3106550Y3552637D01*
G01X3124840Y3543053D02*
X3126080Y3542012D01*
X3127475Y3541387D01*
X3128715D01*
X3129955Y3542012D01*
X3130885Y3543053D01*
X3131350Y3544512D01*
X3131040Y3545970D01*
X3130265Y3547220D01*
X3128870Y3548054D01*
X3127010Y3548470D01*
X3125925Y3549304D01*
X3125460Y3550762D01*
X3125770Y3552220D01*
X3126545Y3553262D01*
X3127630Y3553887D01*
X3128715D01*
X3129800Y3553470D01*
X3130730Y3552429D01*
G01X3140495Y3553887D02*
Y3541387D01*
G01X3136930Y3553887D02*
X3144060D01*
G01X3149485D02*
Y3544929D01*
X3150105Y3543053D01*
X3151345Y3541804D01*
X3152895Y3541387D01*
X3154445Y3541804D01*
X3155685Y3543053D01*
X3156305Y3544929D01*
Y3553887D01*
G01X3166535Y3548054D02*
X3167155Y3548679D01*
X3167620Y3549720D01*
X3167930Y3551179D01*
X3167620Y3552429D01*
X3167000Y3553262D01*
X3165915Y3553887D01*
X3161730D01*
Y3541387D01*
X3166845D01*
X3167930Y3542220D01*
X3168550Y3543470D01*
X3168860Y3544929D01*
X3168550Y3546387D01*
X3167620Y3547637D01*
X3166535Y3548054D01*
X3161730D01*
G01X3186995Y3553887D02*
Y3541387D01*
X3193195D01*
G01X3205595D02*
X3199395D01*
Y3553887D01*
X3205595D01*
G01X3203115Y3547845D02*
X3199395D01*
G01X3211330Y3541387D02*
Y3553887D01*
X3218460Y3541387D01*
Y3553887D01*
G01X3228225Y3547637D02*
X3231325D01*
Y3543887D01*
X3230395Y3542637D01*
X3229310Y3541804D01*
X3227760Y3541387D01*
X3226210Y3541804D01*
X3225125Y3542637D01*
X3224195Y3543887D01*
X3223575Y3545345D01*
X3223265Y3547012D01*
Y3548470D01*
X3223575Y3549720D01*
X3224195Y3551179D01*
X3225125Y3552429D01*
X3226055Y3553262D01*
X3227295Y3553887D01*
X3228380D01*
X3229620Y3553470D01*
X3230550Y3552637D01*
G01X3239695Y3553887D02*
Y3541387D01*
G01X3236130Y3553887D02*
X3243260D01*
G01X3248840Y3541387D02*
Y3553887D01*
G01X3255350D02*
Y3541387D01*
G01Y3547637D02*
X3248840D01*
G01X2951240Y3561803D02*
X2952480Y3560762D01*
X2953875Y3560137D01*
X2955115D01*
X2956355Y3560762D01*
X2957285Y3561803D01*
X2957750Y3563262D01*
X2957440Y3564720D01*
X2956665Y3565970D01*
X2955270Y3566804D01*
X2953410Y3567220D01*
X2952325Y3568054D01*
X2951860Y3569512D01*
X2952170Y3570970D01*
X2952945Y3572012D01*
X2954030Y3572637D01*
X2955115D01*
X2956200Y3572220D01*
X2957130Y3571179D01*
G01X2963485Y3572637D02*
Y3563679D01*
X2964105Y3561803D01*
X2965345Y3560554D01*
X2966895Y3560137D01*
X2968445Y3560554D01*
X2969685Y3561803D01*
X2970305Y3563679D01*
Y3572637D01*
G01X2976195Y3560137D02*
Y3572637D01*
X2980070D01*
X2981310Y3572012D01*
X2982085Y3571179D01*
X2982395Y3569512D01*
X2982085Y3567845D01*
X2981155Y3566804D01*
X2980070Y3566179D01*
X2976195D01*
G01X2980070D02*
X2982395Y3560137D01*
G01X2988750D02*
Y3572637D01*
X2994640D01*
G01X2992470Y3566595D02*
X2988750D01*
G01X3000220Y3560137D02*
X3004095Y3572637D01*
X3007970Y3560137D01*
G01X3006575Y3564512D02*
X3001615D01*
G01X3019905Y3571595D02*
X3018975Y3572220D01*
X3017890Y3572637D01*
X3016650D01*
X3015255Y3572012D01*
X3014170Y3570970D01*
X3013395Y3569720D01*
X3012775Y3567637D01*
X3012620Y3565762D01*
X3012930Y3563887D01*
X3013395Y3562637D01*
X3014325Y3561387D01*
X3015410Y3560554D01*
X3016495Y3560137D01*
X3017580D01*
X3018665Y3560554D01*
X3019595Y3561178D01*
X3020370Y3562012D01*
G01X3031995Y3560137D02*
X3025795D01*
Y3572637D01*
X3031995D01*
G01X3029515Y3566595D02*
X3025795D01*
G01X3053695Y3560137D02*
X3052455Y3560345D01*
X3051370Y3561178D01*
X3050440Y3562429D01*
X3049820Y3563887D01*
X3049510Y3565554D01*
Y3567220D01*
X3049820Y3568887D01*
X3050440Y3570345D01*
X3051370Y3571595D01*
X3052455Y3572429D01*
X3053695Y3572637D01*
X3054935Y3572429D01*
X3056020Y3571595D01*
X3056950Y3570345D01*
X3057570Y3568887D01*
X3057880Y3567220D01*
Y3565554D01*
X3057570Y3563887D01*
X3056950Y3562429D01*
X3056020Y3561178D01*
X3054935Y3560345D01*
X3053695Y3560137D01*
G01X3063150D02*
Y3572637D01*
X3069040D01*
G01X3066870Y3566595D02*
X3063150D01*
G01X3086865Y3560137D02*
Y3572637D01*
X3090895Y3562220D01*
X3094925Y3572637D01*
Y3560137D01*
G01X3099885Y3572637D02*
Y3563679D01*
X3100505Y3561803D01*
X3101745Y3560554D01*
X3103295Y3560137D01*
X3104845Y3560554D01*
X3106085Y3561803D01*
X3106705Y3563679D01*
Y3572637D01*
G01X3112440Y3561803D02*
X3113680Y3560762D01*
X3115075Y3560137D01*
X3116315D01*
X3117555Y3560762D01*
X3118485Y3561803D01*
X3118950Y3563262D01*
X3118640Y3564720D01*
X3117865Y3565970D01*
X3116470Y3566804D01*
X3114610Y3567220D01*
X3113525Y3568054D01*
X3113060Y3569512D01*
X3113370Y3570970D01*
X3114145Y3572012D01*
X3115230Y3572637D01*
X3116315D01*
X3117400Y3572220D01*
X3118330Y3571179D01*
G01X3128095Y3572637D02*
Y3560137D01*
G01X3124530Y3572637D02*
X3131660D01*
G01X3138480Y3564304D02*
X3142510D01*
G01X3149330Y3560137D02*
Y3572637D01*
X3156460Y3560137D01*
Y3572637D01*
G01X3165295Y3560137D02*
X3164055Y3560345D01*
X3162970Y3561178D01*
X3162040Y3562429D01*
X3161420Y3563887D01*
X3161110Y3565554D01*
Y3567220D01*
X3161420Y3568887D01*
X3162040Y3570345D01*
X3162970Y3571595D01*
X3164055Y3572429D01*
X3165295Y3572637D01*
X3166535Y3572429D01*
X3167620Y3571595D01*
X3168550Y3570345D01*
X3169170Y3568887D01*
X3169480Y3567220D01*
Y3565554D01*
X3169170Y3563887D01*
X3168550Y3562429D01*
X3167620Y3561178D01*
X3166535Y3560345D01*
X3165295Y3560137D01*
G01X3177695Y3572637D02*
Y3560137D01*
G01X3174130Y3572637D02*
X3181260D01*
G01X3188080Y3564304D02*
X3192110D01*
G01X3205905Y3571595D02*
X3204975Y3572220D01*
X3203890Y3572637D01*
X3202650D01*
X3201255Y3572012D01*
X3200170Y3570970D01*
X3199395Y3569720D01*
X3198775Y3567637D01*
X3198620Y3565762D01*
X3198930Y3563887D01*
X3199395Y3562637D01*
X3200325Y3561387D01*
X3201410Y3560554D01*
X3202495Y3560137D01*
X3203580D01*
X3204665Y3560554D01*
X3205595Y3561178D01*
X3206370Y3562012D01*
G01X3211485Y3572637D02*
Y3563679D01*
X3212105Y3561803D01*
X3213345Y3560554D01*
X3214895Y3560137D01*
X3216445Y3560554D01*
X3217685Y3561803D01*
X3218305Y3563679D01*
Y3572637D01*
G01X3227295D02*
Y3560137D01*
G01X3223730Y3572637D02*
X3230860D01*
G01X3237680Y3564304D02*
X3241710D01*
G01X3248995Y3572637D02*
Y3560137D01*
X3255195D01*
G01X3260620D02*
X3264495Y3572637D01*
X3268370Y3560137D01*
G01X3266975Y3564512D02*
X3262015D01*
G01X3276895Y3560137D02*
Y3565762D01*
X3273795Y3572637D01*
G01X3279995D02*
X3276895Y3565762D01*
G01X3292395Y3560137D02*
X3286195D01*
Y3572637D01*
X3292395D01*
G01X3289915Y3566595D02*
X3286195D01*
G01X3298595Y3560137D02*
Y3572637D01*
X3302470D01*
X3303710Y3572012D01*
X3304485Y3571179D01*
X3304795Y3569512D01*
X3304485Y3567845D01*
X3303555Y3566804D01*
X3302470Y3566179D01*
X3298595D01*
G01X3302470D02*
X3304795Y3560137D01*
G01X2791280Y3583054D02*
X2795310D01*
G01X2814065Y3578887D02*
Y3591387D01*
X2818095Y3580970D01*
X2822125Y3591387D01*
Y3578887D01*
G01X2826620D02*
X2830495Y3591387D01*
X2834370Y3578887D01*
G01X2832975Y3583262D02*
X2828015D01*
G01X2839640Y3578887D02*
X2846150Y3591387D01*
G01X2839640D02*
X2846150Y3578887D01*
G01X2850645Y3574720D02*
X2859945D01*
G01X2864285Y3578887D02*
Y3591387D01*
X2867385D01*
X2868625Y3590762D01*
X2869555Y3589929D01*
X2870330Y3588679D01*
X2870950Y3587220D01*
X2871105Y3585137D01*
X2870950Y3583054D01*
X2870330Y3581595D01*
X2869555Y3580345D01*
X2868625Y3579512D01*
X2867385Y3578887D01*
X2864285D01*
G01X2883195D02*
X2876995D01*
Y3591387D01*
X2883195D01*
G01X2880715Y3585345D02*
X2876995D01*
G01X2889395Y3578887D02*
Y3591387D01*
X2893115D01*
X2894355Y3590762D01*
X2895285Y3589304D01*
X2895595Y3587637D01*
X2895285Y3585970D01*
X2894510Y3584720D01*
X2893115Y3584095D01*
X2889395D01*
G01X2904895Y3591387D02*
Y3578887D01*
G01X2901330Y3591387D02*
X2908460D01*
G01X2914040Y3578887D02*
Y3591387D01*
G01X2920550D02*
Y3578887D01*
G01Y3585137D02*
X2914040D01*
G01X2929695Y3578470D02*
X2929385Y3578679D01*
Y3579095D01*
X2929695Y3579304D01*
X2930005Y3579095D01*
Y3578679D01*
X2929695Y3578470D01*
G01Y3584095D02*
X2929385Y3584304D01*
Y3584720D01*
X2929695Y3584929D01*
X2930005Y3584720D01*
Y3584304D01*
X2929695Y3584095D01*
G01X2951085Y3578887D02*
Y3591387D01*
X2954185D01*
X2955425Y3590762D01*
X2956355Y3589929D01*
X2957130Y3588679D01*
X2957750Y3587220D01*
X2957905Y3585137D01*
X2957750Y3583054D01*
X2957130Y3581595D01*
X2956355Y3580345D01*
X2955425Y3579512D01*
X2954185Y3578887D01*
X2951085D01*
G01X2969995D02*
X2963795D01*
Y3591387D01*
X2969995D01*
G01X2967515Y3585345D02*
X2963795D01*
G01X2976195Y3578887D02*
Y3591387D01*
X2979915D01*
X2981155Y3590762D01*
X2982085Y3589304D01*
X2982395Y3587637D01*
X2982085Y3585970D01*
X2981310Y3584720D01*
X2979915Y3584095D01*
X2976195D01*
G01X2991695Y3591387D02*
Y3578887D01*
G01X2988130Y3591387D02*
X2995260D01*
G01X3000840Y3578887D02*
Y3591387D01*
G01X3007350D02*
Y3578887D01*
G01Y3585137D02*
X3000840D01*
G01X3025950Y3578887D02*
Y3591387D01*
X3031840D01*
G01X3029670Y3585345D02*
X3025950D01*
G01X3038195Y3578887D02*
Y3591387D01*
X3042070D01*
X3043310Y3590762D01*
X3044085Y3589929D01*
X3044395Y3588262D01*
X3044085Y3586595D01*
X3043155Y3585554D01*
X3042070Y3584929D01*
X3038195D01*
G01X3042070D02*
X3044395Y3578887D01*
G01X3053695D02*
X3052455Y3579095D01*
X3051370Y3579928D01*
X3050440Y3581179D01*
X3049820Y3582637D01*
X3049510Y3584304D01*
Y3585970D01*
X3049820Y3587637D01*
X3050440Y3589095D01*
X3051370Y3590345D01*
X3052455Y3591179D01*
X3053695Y3591387D01*
X3054935Y3591179D01*
X3056020Y3590345D01*
X3056950Y3589095D01*
X3057570Y3587637D01*
X3057880Y3585970D01*
Y3584304D01*
X3057570Y3582637D01*
X3056950Y3581179D01*
X3056020Y3579928D01*
X3054935Y3579095D01*
X3053695Y3578887D01*
G01X3062065D02*
Y3591387D01*
X3066095Y3580970D01*
X3070125Y3591387D01*
Y3578887D01*
G01X3087640Y3580553D02*
X3088880Y3579512D01*
X3090275Y3578887D01*
X3091515D01*
X3092755Y3579512D01*
X3093685Y3580553D01*
X3094150Y3582012D01*
X3093840Y3583470D01*
X3093065Y3584720D01*
X3091670Y3585554D01*
X3089810Y3585970D01*
X3088725Y3586804D01*
X3088260Y3588262D01*
X3088570Y3589720D01*
X3089345Y3590762D01*
X3090430Y3591387D01*
X3091515D01*
X3092600Y3590970D01*
X3093530Y3589929D01*
G01X3103295Y3591387D02*
Y3578887D01*
G01X3099730Y3591387D02*
X3106860D01*
G01X3111820Y3578887D02*
X3115695Y3591387D01*
X3119570Y3578887D01*
G01X3118175Y3583262D02*
X3113215D01*
G01X3124995Y3578887D02*
Y3591387D01*
X3128870D01*
X3130110Y3590762D01*
X3130885Y3589929D01*
X3131195Y3588262D01*
X3130885Y3586595D01*
X3129955Y3585554D01*
X3128870Y3584929D01*
X3124995D01*
G01X3128870D02*
X3131195Y3578887D01*
G01X3140495Y3591387D02*
Y3578887D01*
G01X3136930Y3591387D02*
X3144060D01*
G01X3162195D02*
Y3578887D01*
X3168395D01*
G01X3173820D02*
X3177695Y3591387D01*
X3181570Y3578887D01*
G01X3180175Y3583262D02*
X3175215D01*
G01X3190095Y3578887D02*
Y3584512D01*
X3186995Y3591387D01*
G01X3193195D02*
X3190095Y3584512D01*
G01X3205595Y3578887D02*
X3199395D01*
Y3591387D01*
X3205595D01*
G01X3203115Y3585345D02*
X3199395D01*
G01X3211795Y3578887D02*
Y3591387D01*
X3215670D01*
X3216910Y3590762D01*
X3217685Y3589929D01*
X3217995Y3588262D01*
X3217685Y3586595D01*
X3216755Y3585554D01*
X3215670Y3584929D01*
X3211795D01*
G01X3215670D02*
X3217995Y3578887D01*
G01X3239695Y3591387D02*
Y3578887D01*
G01X3236130Y3591387D02*
X3243260D01*
G01X3252095Y3578887D02*
X3250855Y3579095D01*
X3249770Y3579928D01*
X3248840Y3581179D01*
X3248220Y3582637D01*
X3247910Y3584304D01*
Y3585970D01*
X3248220Y3587637D01*
X3248840Y3589095D01*
X3249770Y3590345D01*
X3250855Y3591179D01*
X3252095Y3591387D01*
X3253335Y3591179D01*
X3254420Y3590345D01*
X3255350Y3589095D01*
X3255970Y3587637D01*
X3256280Y3585970D01*
Y3584304D01*
X3255970Y3582637D01*
X3255350Y3581179D01*
X3254420Y3579928D01*
X3253335Y3579095D01*
X3252095Y3578887D01*
G01X3276895Y3591387D02*
Y3578887D01*
G01X3273330Y3591387D02*
X3280460D01*
G01X3286040Y3578887D02*
Y3591387D01*
G01X3292550D02*
Y3578887D01*
G01Y3585137D02*
X3286040D01*
G01X3304795Y3578887D02*
X3298595D01*
Y3591387D01*
X3304795D01*
G01X3302315Y3585345D02*
X3298595D01*
G01X2791280Y3601804D02*
X2795310D01*
G01X2814065Y3597637D02*
Y3610137D01*
X2818095Y3599720D01*
X2822125Y3610137D01*
Y3597637D01*
G01X2826930D02*
Y3610137D01*
X2834060Y3597637D01*
Y3610137D01*
G01X2846305Y3609095D02*
X2845375Y3609720D01*
X2844290Y3610137D01*
X2843050D01*
X2841655Y3609512D01*
X2840570Y3608470D01*
X2839795Y3607220D01*
X2839175Y3605137D01*
X2839020Y3603262D01*
X2839330Y3601387D01*
X2839795Y3600137D01*
X2840725Y3598887D01*
X2841810Y3598054D01*
X2842895Y3597637D01*
X2843980D01*
X2845065Y3598054D01*
X2845995Y3598678D01*
X2846770Y3599512D01*
G01X2850645Y3593470D02*
X2859945D01*
G01X2864595Y3610137D02*
Y3597637D01*
X2870795D01*
G01X2876220D02*
X2880095Y3610137D01*
X2883970Y3597637D01*
G01X2882575Y3602012D02*
X2877615D01*
G01X2892495Y3597637D02*
Y3603262D01*
X2889395Y3610137D01*
G01X2895595D02*
X2892495Y3603262D01*
G01X2907995Y3597637D02*
X2901795D01*
Y3610137D01*
X2907995D01*
G01X2905515Y3604095D02*
X2901795D01*
G01X2914195Y3597637D02*
Y3610137D01*
X2918070D01*
X2919310Y3609512D01*
X2920085Y3608679D01*
X2920395Y3607012D01*
X2920085Y3605345D01*
X2919155Y3604304D01*
X2918070Y3603679D01*
X2914195D01*
G01X2918070D02*
X2920395Y3597637D01*
G01X2929695Y3597220D02*
X2929385Y3597429D01*
Y3597845D01*
X2929695Y3598054D01*
X2930005Y3597845D01*
Y3597429D01*
X2929695Y3597220D01*
G01Y3602845D02*
X2929385Y3603054D01*
Y3603470D01*
X2929695Y3603679D01*
X2930005Y3603470D01*
Y3603054D01*
X2929695Y3602845D01*
G01X2950465Y3597637D02*
Y3610137D01*
X2954495Y3599720D01*
X2958525Y3610137D01*
Y3597637D01*
G01X2963485Y3610137D02*
Y3601179D01*
X2964105Y3599303D01*
X2965345Y3598054D01*
X2966895Y3597637D01*
X2968445Y3598054D01*
X2969685Y3599303D01*
X2970305Y3601179D01*
Y3610137D01*
G01X2976040Y3599303D02*
X2977280Y3598262D01*
X2978675Y3597637D01*
X2979915D01*
X2981155Y3598262D01*
X2982085Y3599303D01*
X2982550Y3600762D01*
X2982240Y3602220D01*
X2981465Y3603470D01*
X2980070Y3604304D01*
X2978210Y3604720D01*
X2977125Y3605554D01*
X2976660Y3607012D01*
X2976970Y3608470D01*
X2977745Y3609512D01*
X2978830Y3610137D01*
X2979915D01*
X2981000Y3609720D01*
X2981930Y3608679D01*
G01X2991695Y3610137D02*
Y3597637D01*
G01X2988130Y3610137D02*
X2995260D01*
G01X3002080Y3601804D02*
X3006110D01*
G01X3012930Y3597637D02*
Y3610137D01*
X3020060Y3597637D01*
Y3610137D01*
G01X3028895Y3597637D02*
X3027655Y3597845D01*
X3026570Y3598678D01*
X3025640Y3599929D01*
X3025020Y3601387D01*
X3024710Y3603054D01*
Y3604720D01*
X3025020Y3606387D01*
X3025640Y3607845D01*
X3026570Y3609095D01*
X3027655Y3609929D01*
X3028895Y3610137D01*
X3030135Y3609929D01*
X3031220Y3609095D01*
X3032150Y3607845D01*
X3032770Y3606387D01*
X3033080Y3604720D01*
Y3603054D01*
X3032770Y3601387D01*
X3032150Y3599929D01*
X3031220Y3598678D01*
X3030135Y3597845D01*
X3028895Y3597637D01*
G01X3041295Y3610137D02*
Y3597637D01*
G01X3037730Y3610137D02*
X3044860D01*
G01X3051680Y3601804D02*
X3055710D01*
G01X3069505Y3609095D02*
X3068575Y3609720D01*
X3067490Y3610137D01*
X3066250D01*
X3064855Y3609512D01*
X3063770Y3608470D01*
X3062995Y3607220D01*
X3062375Y3605137D01*
X3062220Y3603262D01*
X3062530Y3601387D01*
X3062995Y3600137D01*
X3063925Y3598887D01*
X3065010Y3598054D01*
X3066095Y3597637D01*
X3067180D01*
X3068265Y3598054D01*
X3069195Y3598678D01*
X3069970Y3599512D01*
G01X3075085Y3610137D02*
Y3601179D01*
X3075705Y3599303D01*
X3076945Y3598054D01*
X3078495Y3597637D01*
X3080045Y3598054D01*
X3081285Y3599303D01*
X3081905Y3601179D01*
Y3610137D01*
G01X3090895D02*
Y3597637D01*
G01X3087330Y3610137D02*
X3094460D01*
G01X3101280Y3601804D02*
X3105310D01*
G01X3112595Y3610137D02*
Y3597637D01*
X3118795D01*
G01X3124220D02*
X3128095Y3610137D01*
X3131970Y3597637D01*
G01X3130575Y3602012D02*
X3125615D01*
G01X3140495Y3597637D02*
Y3603262D01*
X3137395Y3610137D01*
G01X3143595D02*
X3140495Y3603262D01*
G01X3155995Y3597637D02*
X3149795D01*
Y3610137D01*
X3155995D01*
G01X3153515Y3604095D02*
X3149795D01*
G01X3162195Y3597637D02*
Y3610137D01*
X3166070D01*
X3167310Y3609512D01*
X3168085Y3608679D01*
X3168395Y3607012D01*
X3168085Y3605345D01*
X3167155Y3604304D01*
X3166070Y3603679D01*
X3162195D01*
G01X3166070D02*
X3168395Y3597637D01*
G01X2789730Y3616387D02*
Y3628887D01*
X2796860Y3616387D01*
Y3628887D01*
G01X2805695Y3616387D02*
X2804455Y3616595D01*
X2803370Y3617428D01*
X2802440Y3618679D01*
X2801820Y3620137D01*
X2801510Y3621804D01*
Y3623470D01*
X2801820Y3625137D01*
X2802440Y3626595D01*
X2803370Y3627845D01*
X2804455Y3628679D01*
X2805695Y3628887D01*
X2806935Y3628679D01*
X2808020Y3627845D01*
X2808950Y3626595D01*
X2809570Y3625137D01*
X2809880Y3623470D01*
Y3621804D01*
X2809570Y3620137D01*
X2808950Y3618679D01*
X2808020Y3617428D01*
X2806935Y3616595D01*
X2805695Y3616387D01*
G01X2818095Y3628887D02*
Y3616387D01*
G01X2814530Y3628887D02*
X2821660D01*
G01X2833595Y3616387D02*
X2827395D01*
Y3628887D01*
X2833595D01*
G01X2831115Y3622845D02*
X2827395D01*
G01X2839640Y3618053D02*
X2840880Y3617012D01*
X2842275Y3616387D01*
X2843515D01*
X2844755Y3617012D01*
X2845685Y3618053D01*
X2846150Y3619512D01*
X2845840Y3620970D01*
X2845065Y3622220D01*
X2843670Y3623054D01*
X2841810Y3623470D01*
X2840725Y3624304D01*
X2840260Y3625762D01*
X2840570Y3627220D01*
X2841345Y3628262D01*
X2842430Y3628887D01*
X2843515D01*
X2844600Y3628470D01*
X2845530Y3627429D01*
G01X2855295Y3615970D02*
X2854985Y3616179D01*
Y3616595D01*
X2855295Y3616804D01*
X2855605Y3616595D01*
Y3616179D01*
X2855295Y3615970D01*
G01Y3621595D02*
X2854985Y3621804D01*
Y3622220D01*
X2855295Y3622429D01*
X2855605Y3622220D01*
Y3621804D01*
X2855295Y3621595D01*
G01X2797885Y2635432D02*
Y2647932D01*
X2803775D01*
G01X2801605Y2641890D02*
X2797885D01*
G01X2811370Y2647932D02*
X2815090D01*
G01X2813230D02*
Y2635432D01*
G01X2811370D02*
X2815090D01*
G01X2826560Y2641682D02*
X2829660D01*
Y2637932D01*
X2828730Y2636682D01*
X2827645Y2635849D01*
X2826095Y2635432D01*
X2824545Y2635849D01*
X2823460Y2636682D01*
X2822530Y2637932D01*
X2821910Y2639390D01*
X2821600Y2641057D01*
Y2642515D01*
X2821910Y2643765D01*
X2822530Y2645224D01*
X2823460Y2646474D01*
X2824390Y2647307D01*
X2825630Y2647932D01*
X2826715D01*
X2827955Y2647515D01*
X2828885Y2646682D01*
G01X2834620Y2647932D02*
Y2638974D01*
X2835240Y2637098D01*
X2836480Y2635849D01*
X2838030Y2635432D01*
X2839580Y2635849D01*
X2840820Y2637098D01*
X2841440Y2638974D01*
Y2647932D01*
G01X2847330Y2635432D02*
Y2647932D01*
X2851205D01*
X2852445Y2647307D01*
X2853220Y2646474D01*
X2853530Y2644807D01*
X2853220Y2643140D01*
X2852290Y2642099D01*
X2851205Y2641474D01*
X2847330D01*
G01X2851205D02*
X2853530Y2635432D01*
G01X2865930D02*
X2859730D01*
Y2647932D01*
X2865930D01*
G01X2863450Y2641890D02*
X2859730D01*
G01X2798881Y2924349D02*
Y2936849D01*
X2804771D01*
G01X2802601Y2930807D02*
X2798881D01*
G01X2812366Y2936849D02*
X2816086D01*
G01X2814226D02*
Y2924349D01*
G01X2812366D02*
X2816086D01*
G01X2827556Y2930599D02*
X2830656D01*
Y2926849D01*
X2829726Y2925599D01*
X2828641Y2924766D01*
X2827091Y2924349D01*
X2825541Y2924766D01*
X2824456Y2925599D01*
X2823526Y2926849D01*
X2822906Y2928307D01*
X2822596Y2929974D01*
Y2931432D01*
X2822906Y2932682D01*
X2823526Y2934141D01*
X2824456Y2935391D01*
X2825386Y2936224D01*
X2826626Y2936849D01*
X2827711D01*
X2828951Y2936432D01*
X2829881Y2935599D01*
G01X2835616Y2936849D02*
Y2927891D01*
X2836236Y2926015D01*
X2837476Y2924766D01*
X2839026Y2924349D01*
X2840576Y2924766D01*
X2841816Y2926015D01*
X2842436Y2927891D01*
Y2936849D01*
G01X2848326Y2924349D02*
Y2936849D01*
X2852201D01*
X2853441Y2936224D01*
X2854216Y2935391D01*
X2854526Y2933724D01*
X2854216Y2932057D01*
X2853286Y2931016D01*
X2852201Y2930391D01*
X2848326D01*
G01X2852201D02*
X2854526Y2924349D01*
G01X2866926D02*
X2860726D01*
Y2936849D01*
X2866926D01*
G01X2864446Y2930807D02*
X2860726D01*
G01X2798891Y3174919D02*
Y3187419D01*
X2804781D01*
G01X2802611Y3181377D02*
X2798891D01*
G01X2812376Y3187419D02*
X2816096D01*
G01X2814236D02*
Y3174919D01*
G01X2812376D02*
X2816096D01*
G01X2827566Y3181169D02*
X2830666D01*
Y3177419D01*
X2829736Y3176169D01*
X2828651Y3175336D01*
X2827101Y3174919D01*
X2825551Y3175336D01*
X2824466Y3176169D01*
X2823536Y3177419D01*
X2822916Y3178877D01*
X2822606Y3180544D01*
Y3182002D01*
X2822916Y3183252D01*
X2823536Y3184711D01*
X2824466Y3185961D01*
X2825396Y3186794D01*
X2826636Y3187419D01*
X2827721D01*
X2828961Y3187002D01*
X2829891Y3186169D01*
G01X2835626Y3187419D02*
Y3178461D01*
X2836246Y3176585D01*
X2837486Y3175336D01*
X2839036Y3174919D01*
X2840586Y3175336D01*
X2841826Y3176585D01*
X2842446Y3178461D01*
Y3187419D01*
G01X2848336Y3174919D02*
Y3187419D01*
X2852211D01*
X2853451Y3186794D01*
X2854226Y3185961D01*
X2854536Y3184294D01*
X2854226Y3182627D01*
X2853296Y3181586D01*
X2852211Y3180961D01*
X2848336D01*
G01X2852211D02*
X2854536Y3174919D01*
G01X2866936D02*
X2860736D01*
Y3187419D01*
X2866936D01*
G01X2864456Y3181377D02*
X2860736D01*
G01X2799650Y3716387D02*
Y3728887D01*
X2805540D01*
G01X2803370Y3722845D02*
X2799650D01*
G01X2813135Y3728887D02*
X2816855D01*
G01X2814995D02*
Y3716387D01*
G01X2813135D02*
X2816855D01*
G01X2828325Y3722637D02*
X2831425D01*
Y3718887D01*
X2830495Y3717637D01*
X2829410Y3716804D01*
X2827860Y3716387D01*
X2826310Y3716804D01*
X2825225Y3717637D01*
X2824295Y3718887D01*
X2823675Y3720345D01*
X2823365Y3722012D01*
Y3723470D01*
X2823675Y3724720D01*
X2824295Y3726179D01*
X2825225Y3727429D01*
X2826155Y3728262D01*
X2827395Y3728887D01*
X2828480D01*
X2829720Y3728470D01*
X2830650Y3727637D01*
G01X2836385Y3728887D02*
Y3719929D01*
X2837005Y3718053D01*
X2838245Y3716804D01*
X2839795Y3716387D01*
X2841345Y3716804D01*
X2842585Y3718053D01*
X2843205Y3719929D01*
Y3728887D01*
G01X2849095Y3716387D02*
Y3728887D01*
X2852970D01*
X2854210Y3728262D01*
X2854985Y3727429D01*
X2855295Y3725762D01*
X2854985Y3724095D01*
X2854055Y3723054D01*
X2852970Y3722429D01*
X2849095D01*
G01X2852970D02*
X2855295Y3716387D01*
G01X2867695D02*
X2861495D01*
Y3728887D01*
X2867695D01*
G01X2865215Y3722845D02*
X2861495D01*
G01X2890676Y2031229D02*
Y2043729D01*
X2896566D01*
G01X2894396Y2037687D02*
X2890676D01*
G01X2904161Y2043729D02*
X2907881D01*
G01X2906021D02*
Y2031229D01*
G01X2904161D02*
X2907881D01*
G01X2914856D02*
Y2043729D01*
X2921986Y2031229D01*
Y2043729D01*
G01X2928961D02*
X2932681D01*
G01X2930821D02*
Y2031229D01*
G01X2928961D02*
X2932681D01*
G01X2939966Y2032895D02*
X2941206Y2031854D01*
X2942601Y2031229D01*
X2943841D01*
X2945081Y2031854D01*
X2946011Y2032895D01*
X2946476Y2034354D01*
X2946166Y2035812D01*
X2945391Y2037062D01*
X2943996Y2037896D01*
X2942136Y2038312D01*
X2941051Y2039146D01*
X2940586Y2040604D01*
X2940896Y2042062D01*
X2941671Y2043104D01*
X2942756Y2043729D01*
X2943841D01*
X2944926Y2043312D01*
X2945856Y2042271D01*
G01X2952366Y2031229D02*
Y2043729D01*
G01X2958876D02*
Y2031229D01*
G01Y2037479D02*
X2952366D01*
G01X2971121Y2031229D02*
X2964921D01*
Y2043729D01*
X2971121D01*
G01X2968641Y2037687D02*
X2964921D01*
G01X2977011Y2031229D02*
Y2043729D01*
X2980111D01*
X2981351Y2043104D01*
X2982281Y2042271D01*
X2983056Y2041021D01*
X2983676Y2039562D01*
X2983831Y2037479D01*
X2983676Y2035396D01*
X2983056Y2033937D01*
X2982281Y2032687D01*
X2981351Y2031854D01*
X2980111Y2031229D01*
X2977011D01*
G01X2988171Y2027062D02*
X2997471D01*
G01X3001966Y2032895D02*
X3003206Y2031854D01*
X3004601Y2031229D01*
X3005841D01*
X3007081Y2031854D01*
X3008011Y2032895D01*
X3008476Y2034354D01*
X3008166Y2035812D01*
X3007391Y2037062D01*
X3005996Y2037896D01*
X3004136Y2038312D01*
X3003051Y2039146D01*
X3002586Y2040604D01*
X3002896Y2042062D01*
X3003671Y2043104D01*
X3004756Y2043729D01*
X3005841D01*
X3006926Y2043312D01*
X3007856Y2042271D01*
G01X3015761Y2043729D02*
X3019481D01*
G01X3017621D02*
Y2031229D01*
G01X3015761D02*
X3019481D01*
G01X3027076Y2043729D02*
X3032966D01*
X3027076Y2031229D01*
X3032966D01*
G01X3045521D02*
X3039321D01*
Y2043729D01*
X3045521D01*
G01X3043041Y2037687D02*
X3039321D01*
G01X2903076Y-187104D02*
X2904006Y-185855D01*
X2905091Y-185229D01*
X2906331Y-185021D01*
X2907881Y-185438D01*
X2908966Y-186479D01*
X2909276Y-187729D01*
X2909121Y-188980D01*
X2908501Y-190021D01*
X2905401Y-192104D01*
X2904006Y-193563D01*
X2903076Y-195646D01*
X2902766Y-197521D01*
X2909276D01*
G01X2915011Y-195646D02*
X2915941Y-196688D01*
X2917026Y-197313D01*
X2918421Y-197521D01*
X2919816Y-197104D01*
X2920901Y-196271D01*
X2921676Y-194813D01*
X2921831Y-193146D01*
X2921521Y-191479D01*
X2920746Y-190438D01*
X2919661Y-189604D01*
X2918576Y-189396D01*
X2917491Y-189604D01*
X2916096Y-190438D01*
X2916561Y-185021D01*
X2920746D01*
G01X2927411Y-195646D02*
X2928341Y-196688D01*
X2929426Y-197313D01*
X2930821Y-197521D01*
X2932216Y-197104D01*
X2933301Y-196271D01*
X2934076Y-194813D01*
X2934231Y-193146D01*
X2933921Y-191479D01*
X2933146Y-190438D01*
X2932061Y-189604D01*
X2930976Y-189396D01*
X2929891Y-189604D01*
X2928496Y-190438D01*
X2928961Y-185021D01*
X2933146D01*
G01X2943221Y-197938D02*
X2942911Y-197729D01*
Y-197313D01*
X2943221Y-197104D01*
X2943531Y-197313D01*
Y-197729D01*
X2943221Y-197938D01*
G01X2955621Y-185021D02*
X2954381Y-185438D01*
X2953451Y-186479D01*
X2952831Y-187729D01*
X2952366Y-189396D01*
X2952211Y-191271D01*
X2952366Y-193146D01*
X2952831Y-194813D01*
X2953451Y-196063D01*
X2954381Y-197104D01*
X2955621Y-197521D01*
X2956861Y-197104D01*
X2957791Y-196063D01*
X2958411Y-194813D01*
X2958876Y-193146D01*
X2959031Y-191271D01*
X2958876Y-189396D01*
X2958411Y-187729D01*
X2957791Y-186479D01*
X2956861Y-185438D01*
X2955621Y-185021D01*
G01X2965696Y-189188D02*
X2970346Y-197521D01*
G01Y-189188D02*
X2965696Y-197521D01*
G01X2977476Y-187104D02*
X2978406Y-185855D01*
X2979491Y-185229D01*
X2980731Y-185021D01*
X2982281Y-185438D01*
X2983366Y-186479D01*
X2983676Y-187729D01*
X2983521Y-188980D01*
X2982901Y-190021D01*
X2979801Y-192104D01*
X2978406Y-193563D01*
X2977476Y-195646D01*
X2977166Y-197521D01*
X2983676D01*
G01X2992821Y-185021D02*
X2991581Y-185438D01*
X2990651Y-186479D01*
X2990031Y-187729D01*
X2989566Y-189396D01*
X2989411Y-191271D01*
X2989566Y-193146D01*
X2990031Y-194813D01*
X2990651Y-196063D01*
X2991581Y-197104D01*
X2992821Y-197521D01*
X2994061Y-197104D01*
X2994991Y-196063D01*
X2995611Y-194813D01*
X2996076Y-193146D01*
X2996231Y-191271D01*
X2996076Y-189396D01*
X2995611Y-187729D01*
X2994991Y-186479D01*
X2994061Y-185438D01*
X2992821Y-185021D01*
G01X3005221D02*
X3003981Y-185438D01*
X3003051Y-186479D01*
X3002431Y-187729D01*
X3001966Y-189396D01*
X3001811Y-191271D01*
X3001966Y-193146D01*
X3002431Y-194813D01*
X3003051Y-196063D01*
X3003981Y-197104D01*
X3005221Y-197521D01*
X3006461Y-197104D01*
X3007391Y-196063D01*
X3008011Y-194813D01*
X3008476Y-193146D01*
X3008631Y-191271D01*
X3008476Y-189396D01*
X3008011Y-187729D01*
X3007391Y-186479D01*
X3006461Y-185438D01*
X3005221Y-185021D01*
G01X3017621Y-197938D02*
X3017311Y-197729D01*
Y-197313D01*
X3017621Y-197104D01*
X3017931Y-197313D01*
Y-197729D01*
X3017621Y-197938D01*
G01X3030021Y-185021D02*
X3028781Y-185438D01*
X3027851Y-186479D01*
X3027231Y-187729D01*
X3026766Y-189396D01*
X3026611Y-191271D01*
X3026766Y-193146D01*
X3027231Y-194813D01*
X3027851Y-196063D01*
X3028781Y-197104D01*
X3030021Y-197521D01*
X3031261Y-197104D01*
X3032191Y-196063D01*
X3032811Y-194813D01*
X3033276Y-193146D01*
X3033431Y-191271D01*
X3033276Y-189396D01*
X3032811Y-187729D01*
X3032191Y-186479D01*
X3031261Y-185438D01*
X3030021Y-185021D01*
G01X2906021Y-138421D02*
Y-125921D01*
X2904161Y-128421D01*
G01Y-138421D02*
X2907881D01*
G01X2918421D02*
X2919506Y-138213D01*
X2920746Y-137588D01*
X2921521Y-136546D01*
X2921831Y-135088D01*
X2921521Y-133630D01*
X2920591Y-132379D01*
X2919196Y-131754D01*
X2917646D01*
X2916716Y-131338D01*
X2915941Y-130296D01*
X2915631Y-128838D01*
X2916096Y-127379D01*
X2917181Y-126338D01*
X2918421Y-125921D01*
X2919661Y-126338D01*
X2920746Y-127379D01*
X2921211Y-128838D01*
X2920901Y-130296D01*
X2920126Y-131338D01*
X2919196Y-131754D01*
X2917646D01*
X2916251Y-132379D01*
X2915321Y-133630D01*
X2915011Y-135088D01*
X2915321Y-136546D01*
X2916096Y-137588D01*
X2917336Y-138213D01*
X2918421Y-138421D01*
G01X2928186Y-136963D02*
X2929271Y-138004D01*
X2930511Y-138421D01*
X2931751Y-138004D01*
X2932836Y-136755D01*
X2933611Y-134879D01*
X2933921Y-133004D01*
Y-130713D01*
X2933611Y-128838D01*
X2932836Y-127171D01*
X2931906Y-126338D01*
X2930821Y-125921D01*
X2929581Y-126338D01*
X2928651Y-127171D01*
X2928031Y-128421D01*
X2927721Y-130088D01*
X2928031Y-131546D01*
X2928806Y-133004D01*
X2929736Y-133838D01*
X2930821Y-134046D01*
X2932061Y-133630D01*
X2932991Y-132588D01*
X2933921Y-130713D01*
G01X2943221Y-138838D02*
X2942911Y-138629D01*
Y-138213D01*
X2943221Y-138004D01*
X2943531Y-138213D01*
Y-138629D01*
X2943221Y-138838D01*
G01X2955621Y-125921D02*
X2954381Y-126338D01*
X2953451Y-127379D01*
X2952831Y-128629D01*
X2952366Y-130296D01*
X2952211Y-132171D01*
X2952366Y-134046D01*
X2952831Y-135713D01*
X2953451Y-136963D01*
X2954381Y-138004D01*
X2955621Y-138421D01*
X2956861Y-138004D01*
X2957791Y-136963D01*
X2958411Y-135713D01*
X2958876Y-134046D01*
X2959031Y-132171D01*
X2958876Y-130296D01*
X2958411Y-128629D01*
X2957791Y-127379D01*
X2956861Y-126338D01*
X2955621Y-125921D01*
G01X2965696Y-130088D02*
X2970346Y-138421D01*
G01Y-130088D02*
X2965696Y-138421D01*
G01X2980421D02*
Y-125921D01*
X2978561Y-128421D01*
G01Y-138421D02*
X2982281D01*
G01X2989876Y-128004D02*
X2990806Y-126755D01*
X2991891Y-126129D01*
X2993131Y-125921D01*
X2994681Y-126338D01*
X2995766Y-127379D01*
X2996076Y-128629D01*
X2995921Y-129880D01*
X2995301Y-130921D01*
X2992201Y-133004D01*
X2990806Y-134463D01*
X2989876Y-136546D01*
X2989566Y-138421D01*
X2996076D01*
G01X3002276Y-133213D02*
X3003361Y-131754D01*
X3004291Y-130921D01*
X3005531Y-130504D01*
X3006616Y-130921D01*
X3007391Y-131754D01*
X3008011Y-133004D01*
X3008166Y-134463D01*
X3008011Y-135713D01*
X3007391Y-136963D01*
X3006461Y-138004D01*
X3005376Y-138421D01*
X3004136Y-138004D01*
X3003051Y-136755D01*
X3002431Y-134879D01*
X3002276Y-132796D01*
X3002586Y-130088D01*
X3003051Y-128629D01*
X3003826Y-127171D01*
X3004911Y-126129D01*
X3005996Y-125921D01*
X3007081Y-126338D01*
X3007856Y-127379D01*
G01X3017621Y-138838D02*
X3017311Y-138629D01*
Y-138213D01*
X3017621Y-138004D01*
X3017931Y-138213D01*
Y-138629D01*
X3017621Y-138838D01*
G01X3030021Y-125921D02*
X3028781Y-126338D01*
X3027851Y-127379D01*
X3027231Y-128629D01*
X3026766Y-130296D01*
X3026611Y-132171D01*
X3026766Y-134046D01*
X3027231Y-135713D01*
X3027851Y-136963D01*
X3028781Y-138004D01*
X3030021Y-138421D01*
X3031261Y-138004D01*
X3032191Y-136963D01*
X3032811Y-135713D01*
X3033276Y-134046D01*
X3033431Y-132171D01*
X3033276Y-130296D01*
X3032811Y-128629D01*
X3032191Y-127379D01*
X3031261Y-126338D01*
X3030021Y-125921D01*
G01X2904370Y2642099D02*
X2904990Y2642724D01*
X2905455Y2643765D01*
X2905765Y2645224D01*
X2905455Y2646474D01*
X2904835Y2647307D01*
X2903750Y2647932D01*
X2899565D01*
Y2635432D01*
X2904680D01*
X2905765Y2636265D01*
X2906385Y2637515D01*
X2906695Y2638974D01*
X2906385Y2640432D01*
X2905455Y2641682D01*
X2904370Y2642099D01*
X2899565D01*
G01X2912120Y2635432D02*
Y2647932D01*
X2915220D01*
X2916460Y2647307D01*
X2917390Y2646474D01*
X2918165Y2645224D01*
X2918785Y2643765D01*
X2918940Y2641682D01*
X2918785Y2639599D01*
X2918165Y2638140D01*
X2917390Y2636890D01*
X2916460Y2636057D01*
X2915220Y2635432D01*
X2912120D01*
G01X2923280Y2631265D02*
X2932580D01*
G01X2937075Y2637098D02*
X2938315Y2636057D01*
X2939710Y2635432D01*
X2940950D01*
X2942190Y2636057D01*
X2943120Y2637098D01*
X2943585Y2638557D01*
X2943275Y2640015D01*
X2942500Y2641265D01*
X2941105Y2642099D01*
X2939245Y2642515D01*
X2938160Y2643349D01*
X2937695Y2644807D01*
X2938005Y2646265D01*
X2938780Y2647307D01*
X2939865Y2647932D01*
X2940950D01*
X2942035Y2647515D01*
X2942965Y2646474D01*
G01X2950870Y2647932D02*
X2954590D01*
G01X2952730D02*
Y2635432D01*
G01X2950870D02*
X2954590D01*
G01X2962185Y2647932D02*
X2968075D01*
X2962185Y2635432D01*
X2968075D01*
G01X2980630D02*
X2974430D01*
Y2647932D01*
X2980630D01*
G01X2978150Y2641890D02*
X2974430D01*
G01X2905366Y2931016D02*
X2905986Y2931641D01*
X2906451Y2932682D01*
X2906761Y2934141D01*
X2906451Y2935391D01*
X2905831Y2936224D01*
X2904746Y2936849D01*
X2900561D01*
Y2924349D01*
X2905676D01*
X2906761Y2925182D01*
X2907381Y2926432D01*
X2907691Y2927891D01*
X2907381Y2929349D01*
X2906451Y2930599D01*
X2905366Y2931016D01*
X2900561D01*
G01X2913116Y2924349D02*
Y2936849D01*
X2916216D01*
X2917456Y2936224D01*
X2918386Y2935391D01*
X2919161Y2934141D01*
X2919781Y2932682D01*
X2919936Y2930599D01*
X2919781Y2928516D01*
X2919161Y2927057D01*
X2918386Y2925807D01*
X2917456Y2924974D01*
X2916216Y2924349D01*
X2913116D01*
G01X2924276Y2920182D02*
X2933576D01*
G01X2938071Y2926015D02*
X2939311Y2924974D01*
X2940706Y2924349D01*
X2941946D01*
X2943186Y2924974D01*
X2944116Y2926015D01*
X2944581Y2927474D01*
X2944271Y2928932D01*
X2943496Y2930182D01*
X2942101Y2931016D01*
X2940241Y2931432D01*
X2939156Y2932266D01*
X2938691Y2933724D01*
X2939001Y2935182D01*
X2939776Y2936224D01*
X2940861Y2936849D01*
X2941946D01*
X2943031Y2936432D01*
X2943961Y2935391D01*
G01X2951866Y2936849D02*
X2955586D01*
G01X2953726D02*
Y2924349D01*
G01X2951866D02*
X2955586D01*
G01X2963181Y2936849D02*
X2969071D01*
X2963181Y2924349D01*
X2969071D01*
G01X2981626D02*
X2975426D01*
Y2936849D01*
X2981626D01*
G01X2979146Y2930807D02*
X2975426D01*
G01X2905376Y3181586D02*
X2905996Y3182211D01*
X2906461Y3183252D01*
X2906771Y3184711D01*
X2906461Y3185961D01*
X2905841Y3186794D01*
X2904756Y3187419D01*
X2900571D01*
Y3174919D01*
X2905686D01*
X2906771Y3175752D01*
X2907391Y3177002D01*
X2907701Y3178461D01*
X2907391Y3179919D01*
X2906461Y3181169D01*
X2905376Y3181586D01*
X2900571D01*
G01X2913126Y3174919D02*
Y3187419D01*
X2916226D01*
X2917466Y3186794D01*
X2918396Y3185961D01*
X2919171Y3184711D01*
X2919791Y3183252D01*
X2919946Y3181169D01*
X2919791Y3179086D01*
X2919171Y3177627D01*
X2918396Y3176377D01*
X2917466Y3175544D01*
X2916226Y3174919D01*
X2913126D01*
G01X2924286Y3170752D02*
X2933586D01*
G01X2938081Y3176585D02*
X2939321Y3175544D01*
X2940716Y3174919D01*
X2941956D01*
X2943196Y3175544D01*
X2944126Y3176585D01*
X2944591Y3178044D01*
X2944281Y3179502D01*
X2943506Y3180752D01*
X2942111Y3181586D01*
X2940251Y3182002D01*
X2939166Y3182836D01*
X2938701Y3184294D01*
X2939011Y3185752D01*
X2939786Y3186794D01*
X2940871Y3187419D01*
X2941956D01*
X2943041Y3187002D01*
X2943971Y3185961D01*
G01X2951876Y3187419D02*
X2955596D01*
G01X2953736D02*
Y3174919D01*
G01X2951876D02*
X2955596D01*
G01X2963191Y3187419D02*
X2969081D01*
X2963191Y3174919D01*
X2969081D01*
G01X2981636D02*
X2975436D01*
Y3187419D01*
X2981636D01*
G01X2979156Y3181377D02*
X2975436D01*
G01X2901030Y3437592D02*
X2901650Y3438217D01*
X2902115Y3439258D01*
X2902425Y3440717D01*
X2902115Y3441967D01*
X2901495Y3442800D01*
X2900410Y3443425D01*
X2896225D01*
Y3430925D01*
X2901340D01*
X2902425Y3431758D01*
X2903045Y3433008D01*
X2903355Y3434467D01*
X2903045Y3435925D01*
X2902115Y3437175D01*
X2901030Y3437592D01*
X2896225D01*
G01X2908780Y3430925D02*
Y3443425D01*
X2911880D01*
X2913120Y3442800D01*
X2914050Y3441967D01*
X2914825Y3440717D01*
X2915445Y3439258D01*
X2915600Y3437175D01*
X2915445Y3435092D01*
X2914825Y3433633D01*
X2914050Y3432383D01*
X2913120Y3431550D01*
X2911880Y3430925D01*
X2908780D01*
G01X2919940Y3426758D02*
X2929240D01*
G01X2933735Y3432591D02*
X2934975Y3431550D01*
X2936370Y3430925D01*
X2937610D01*
X2938850Y3431550D01*
X2939780Y3432591D01*
X2940245Y3434050D01*
X2939935Y3435508D01*
X2939160Y3436758D01*
X2937765Y3437592D01*
X2935905Y3438008D01*
X2934820Y3438842D01*
X2934355Y3440300D01*
X2934665Y3441758D01*
X2935440Y3442800D01*
X2936525Y3443425D01*
X2937610D01*
X2938695Y3443008D01*
X2939625Y3441967D01*
G01X2947530Y3443425D02*
X2951250D01*
G01X2949390D02*
Y3430925D01*
G01X2947530D02*
X2951250D01*
G01X2958845Y3443425D02*
X2964735D01*
X2958845Y3430925D01*
X2964735D01*
G01X2977290D02*
X2971090D01*
Y3443425D01*
X2977290D01*
G01X2974810Y3437383D02*
X2971090D01*
G01X2906135Y3723054D02*
X2906755Y3723679D01*
X2907220Y3724720D01*
X2907530Y3726179D01*
X2907220Y3727429D01*
X2906600Y3728262D01*
X2905515Y3728887D01*
X2901330D01*
Y3716387D01*
X2906445D01*
X2907530Y3717220D01*
X2908150Y3718470D01*
X2908460Y3719929D01*
X2908150Y3721387D01*
X2907220Y3722637D01*
X2906135Y3723054D01*
X2901330D01*
G01X2913885Y3716387D02*
Y3728887D01*
X2916985D01*
X2918225Y3728262D01*
X2919155Y3727429D01*
X2919930Y3726179D01*
X2920550Y3724720D01*
X2920705Y3722637D01*
X2920550Y3720554D01*
X2919930Y3719095D01*
X2919155Y3717845D01*
X2918225Y3717012D01*
X2916985Y3716387D01*
X2913885D01*
G01X2925045Y3712220D02*
X2934345D01*
G01X2938840Y3718053D02*
X2940080Y3717012D01*
X2941475Y3716387D01*
X2942715D01*
X2943955Y3717012D01*
X2944885Y3718053D01*
X2945350Y3719512D01*
X2945040Y3720970D01*
X2944265Y3722220D01*
X2942870Y3723054D01*
X2941010Y3723470D01*
X2939925Y3724304D01*
X2939460Y3725762D01*
X2939770Y3727220D01*
X2940545Y3728262D01*
X2941630Y3728887D01*
X2942715D01*
X2943800Y3728470D01*
X2944730Y3727429D01*
G01X2952635Y3728887D02*
X2956355D01*
G01X2954495D02*
Y3716387D01*
G01X2952635D02*
X2956355D01*
G01X2963950Y3728887D02*
X2969840D01*
X2963950Y3716387D01*
X2969840D01*
G01X2982395D02*
X2976195D01*
Y3728887D01*
X2982395D01*
G01X2979915Y3722845D02*
X2976195D01*
G01X2915786Y-77863D02*
X2916871Y-78904D01*
X2918111Y-79321D01*
X2919351Y-78904D01*
X2920436Y-77655D01*
X2921211Y-75779D01*
X2921521Y-73904D01*
Y-71613D01*
X2921211Y-69738D01*
X2920436Y-68071D01*
X2919506Y-67238D01*
X2918421Y-66821D01*
X2917181Y-67238D01*
X2916251Y-68071D01*
X2915631Y-69321D01*
X2915321Y-70988D01*
X2915631Y-72446D01*
X2916406Y-73904D01*
X2917336Y-74738D01*
X2918421Y-74946D01*
X2919661Y-74530D01*
X2920591Y-73488D01*
X2921521Y-71613D01*
G01X2930511Y-79321D02*
X2930821Y-76613D01*
X2931286Y-74321D01*
X2931906Y-72238D01*
X2932681Y-69946D01*
X2933921Y-66821D01*
X2927721D01*
G01X2943221Y-79738D02*
X2942911Y-79529D01*
Y-79113D01*
X2943221Y-78904D01*
X2943531Y-79113D01*
Y-79529D01*
X2943221Y-79738D01*
G01X2955621Y-66821D02*
X2954381Y-67238D01*
X2953451Y-68279D01*
X2952831Y-69529D01*
X2952366Y-71196D01*
X2952211Y-73071D01*
X2952366Y-74946D01*
X2952831Y-76613D01*
X2953451Y-77863D01*
X2954381Y-78904D01*
X2955621Y-79321D01*
X2956861Y-78904D01*
X2957791Y-77863D01*
X2958411Y-76613D01*
X2958876Y-74946D01*
X2959031Y-73071D01*
X2958876Y-71196D01*
X2958411Y-69529D01*
X2957791Y-68279D01*
X2956861Y-67238D01*
X2955621Y-66821D01*
G01X2965696Y-70988D02*
X2970346Y-79321D01*
G01Y-70988D02*
X2965696Y-79321D01*
G01X2982281D02*
Y-66821D01*
X2976546Y-75779D01*
X2984296D01*
G01X2994681Y-79321D02*
Y-66821D01*
X2988946Y-75779D01*
X2996696D01*
G01X3005221Y-79738D02*
X3004911Y-79529D01*
Y-79113D01*
X3005221Y-78904D01*
X3005531Y-79113D01*
Y-79529D01*
X3005221Y-79738D01*
G01X3017621Y-66821D02*
X3016381Y-67238D01*
X3015451Y-68279D01*
X3014831Y-69529D01*
X3014366Y-71196D01*
X3014211Y-73071D01*
X3014366Y-74946D01*
X3014831Y-76613D01*
X3015451Y-77863D01*
X3016381Y-78904D01*
X3017621Y-79321D01*
X3018861Y-78904D01*
X3019791Y-77863D01*
X3020411Y-76613D01*
X3020876Y-74946D01*
X3021031Y-73071D01*
X3020876Y-71196D01*
X3020411Y-69529D01*
X3019791Y-68279D01*
X3018861Y-67238D01*
X3017621Y-66821D01*
G01X2915786Y-18763D02*
X2916871Y-19804D01*
X2918111Y-20221D01*
X2919351Y-19804D01*
X2920436Y-18555D01*
X2921211Y-16679D01*
X2921521Y-14804D01*
Y-12513D01*
X2921211Y-10638D01*
X2920436Y-8971D01*
X2919506Y-8138D01*
X2918421Y-7721D01*
X2917181Y-8138D01*
X2916251Y-8971D01*
X2915631Y-10221D01*
X2915321Y-11888D01*
X2915631Y-13346D01*
X2916406Y-14804D01*
X2917336Y-15638D01*
X2918421Y-15846D01*
X2919661Y-15430D01*
X2920591Y-14388D01*
X2921521Y-12513D01*
G01X2927876Y-15013D02*
X2928961Y-13554D01*
X2929891Y-12721D01*
X2931131Y-12304D01*
X2932216Y-12721D01*
X2932991Y-13554D01*
X2933611Y-14804D01*
X2933766Y-16263D01*
X2933611Y-17513D01*
X2932991Y-18763D01*
X2932061Y-19804D01*
X2930976Y-20221D01*
X2929736Y-19804D01*
X2928651Y-18555D01*
X2928031Y-16679D01*
X2927876Y-14596D01*
X2928186Y-11888D01*
X2928651Y-10429D01*
X2929426Y-8971D01*
X2930511Y-7929D01*
X2931596Y-7721D01*
X2932681Y-8138D01*
X2933456Y-9179D01*
G01X2943221Y-20638D02*
X2942911Y-20429D01*
Y-20013D01*
X2943221Y-19804D01*
X2943531Y-20013D01*
Y-20429D01*
X2943221Y-20638D01*
G01X2955621Y-7721D02*
X2954381Y-8138D01*
X2953451Y-9179D01*
X2952831Y-10429D01*
X2952366Y-12096D01*
X2952211Y-13971D01*
X2952366Y-15846D01*
X2952831Y-17513D01*
X2953451Y-18763D01*
X2954381Y-19804D01*
X2955621Y-20221D01*
X2956861Y-19804D01*
X2957791Y-18763D01*
X2958411Y-17513D01*
X2958876Y-15846D01*
X2959031Y-13971D01*
X2958876Y-12096D01*
X2958411Y-10429D01*
X2957791Y-9179D01*
X2956861Y-8138D01*
X2955621Y-7721D01*
G01X2965696Y-11888D02*
X2970346Y-20221D01*
G01Y-11888D02*
X2965696Y-20221D01*
G01X2982281D02*
Y-7721D01*
X2976546Y-16679D01*
X2984296D01*
G01X2992511Y-20221D02*
X2992821Y-17513D01*
X2993286Y-15221D01*
X2993906Y-13138D01*
X2994681Y-10846D01*
X2995921Y-7721D01*
X2989721D01*
G01X3005221Y-20638D02*
X3004911Y-20429D01*
Y-20013D01*
X3005221Y-19804D01*
X3005531Y-20013D01*
Y-20429D01*
X3005221Y-20638D01*
G01X3017621Y-7721D02*
X3016381Y-8138D01*
X3015451Y-9179D01*
X3014831Y-10429D01*
X3014366Y-12096D01*
X3014211Y-13971D01*
X3014366Y-15846D01*
X3014831Y-17513D01*
X3015451Y-18763D01*
X3016381Y-19804D01*
X3017621Y-20221D01*
X3018861Y-19804D01*
X3019791Y-18763D01*
X3020411Y-17513D01*
X3020876Y-15846D01*
X3021031Y-13971D01*
X3020876Y-12096D01*
X3020411Y-10429D01*
X3019791Y-9179D01*
X3018861Y-8138D01*
X3017621Y-7721D01*
G01X2921730Y2610432D02*
Y2622932D01*
X2919870Y2620432D01*
G01Y2610432D02*
X2923590D01*
G01X2933820D02*
X2934130Y2613140D01*
X2934595Y2615432D01*
X2935215Y2617515D01*
X2935990Y2619807D01*
X2937230Y2622932D01*
X2931030D01*
G01X2946530Y2610015D02*
X2946220Y2610224D01*
Y2610640D01*
X2946530Y2610849D01*
X2946840Y2610640D01*
Y2610224D01*
X2946530Y2610015D01*
G01X2958620Y2610432D02*
X2958930Y2613140D01*
X2959395Y2615432D01*
X2960015Y2617515D01*
X2960790Y2619807D01*
X2962030Y2622932D01*
X2955830D01*
G01X2922726Y2874349D02*
Y2886849D01*
X2920866Y2884349D01*
G01Y2874349D02*
X2924586D01*
G01X2934816D02*
X2935126Y2877057D01*
X2935591Y2879349D01*
X2936211Y2881432D01*
X2936986Y2883724D01*
X2938226Y2886849D01*
X2932026D01*
G01X2947526Y2873932D02*
X2947216Y2874141D01*
Y2874557D01*
X2947526Y2874766D01*
X2947836Y2874557D01*
Y2874141D01*
X2947526Y2873932D01*
G01X2959616Y2874349D02*
X2959926Y2877057D01*
X2960391Y2879349D01*
X2961011Y2881432D01*
X2961786Y2883724D01*
X2963026Y2886849D01*
X2956826D01*
G01X2922726Y2899349D02*
Y2911849D01*
X2920866Y2909349D01*
G01Y2899349D02*
X2924586D01*
G01X2931716Y2901224D02*
X2932646Y2900182D01*
X2933731Y2899557D01*
X2935126Y2899349D01*
X2936521Y2899766D01*
X2937606Y2900599D01*
X2938381Y2902057D01*
X2938536Y2903724D01*
X2938226Y2905391D01*
X2937451Y2906432D01*
X2936366Y2907266D01*
X2935281Y2907474D01*
X2934196Y2907266D01*
X2932801Y2906432D01*
X2933266Y2911849D01*
X2937451D01*
G01X2947526Y2898932D02*
X2947216Y2899141D01*
Y2899557D01*
X2947526Y2899766D01*
X2947836Y2899557D01*
Y2899141D01*
X2947526Y2898932D01*
G01X2959616Y2899349D02*
X2959926Y2902057D01*
X2960391Y2904349D01*
X2961011Y2906432D01*
X2961786Y2908724D01*
X2963026Y2911849D01*
X2956826D01*
G01X2922736Y3124919D02*
Y3137419D01*
X2920876Y3134919D01*
G01Y3124919D02*
X2924596D01*
G01X2934826D02*
X2935136Y3127627D01*
X2935601Y3129919D01*
X2936221Y3132002D01*
X2936996Y3134294D01*
X2938236Y3137419D01*
X2932036D01*
G01X2947536Y3124502D02*
X2947226Y3124711D01*
Y3125127D01*
X2947536Y3125336D01*
X2947846Y3125127D01*
Y3124711D01*
X2947536Y3124502D01*
G01X2959626Y3124919D02*
X2959936Y3127627D01*
X2960401Y3129919D01*
X2961021Y3132002D01*
X2961796Y3134294D01*
X2963036Y3137419D01*
X2956836D01*
G01X2922736Y3149919D02*
Y3162419D01*
X2920876Y3159919D01*
G01Y3149919D02*
X2924596D01*
G01X2931726Y3151794D02*
X2932656Y3150752D01*
X2933741Y3150127D01*
X2935136Y3149919D01*
X2936531Y3150336D01*
X2937616Y3151169D01*
X2938391Y3152627D01*
X2938546Y3154294D01*
X2938236Y3155961D01*
X2937461Y3157002D01*
X2936376Y3157836D01*
X2935291Y3158044D01*
X2934206Y3157836D01*
X2932811Y3157002D01*
X2933276Y3162419D01*
X2937461D01*
G01X2947536Y3149502D02*
X2947226Y3149711D01*
Y3150127D01*
X2947536Y3150336D01*
X2947846Y3150127D01*
Y3149711D01*
X2947536Y3149502D01*
G01X2959626Y3149919D02*
X2959936Y3152627D01*
X2960401Y3154919D01*
X2961021Y3157002D01*
X2961796Y3159294D01*
X2963036Y3162419D01*
X2956836D01*
G01X2918390Y3380925D02*
Y3393425D01*
X2916530Y3390925D01*
G01Y3380925D02*
X2920250D01*
G01X2930480D02*
X2930790Y3383633D01*
X2931255Y3385925D01*
X2931875Y3388008D01*
X2932650Y3390300D01*
X2933890Y3393425D01*
X2927690D01*
G01X2943190Y3380508D02*
X2942880Y3380717D01*
Y3381133D01*
X2943190Y3381342D01*
X2943500Y3381133D01*
Y3380717D01*
X2943190Y3380508D01*
G01X2955280Y3380925D02*
X2955590Y3383633D01*
X2956055Y3385925D01*
X2956675Y3388008D01*
X2957450Y3390300D01*
X2958690Y3393425D01*
X2952490D01*
G01X2918390Y3405925D02*
Y3418425D01*
X2916530Y3415925D01*
G01Y3405925D02*
X2920250D01*
G01X2927380Y3407800D02*
X2928310Y3406758D01*
X2929395Y3406133D01*
X2930790Y3405925D01*
X2932185Y3406342D01*
X2933270Y3407175D01*
X2934045Y3408633D01*
X2934200Y3410300D01*
X2933890Y3411967D01*
X2933115Y3413008D01*
X2932030Y3413842D01*
X2930945Y3414050D01*
X2929860Y3413842D01*
X2928465Y3413008D01*
X2928930Y3418425D01*
X2933115D01*
G01X2943190Y3405508D02*
X2942880Y3405717D01*
Y3406133D01*
X2943190Y3406342D01*
X2943500Y3406133D01*
Y3405717D01*
X2943190Y3405508D01*
G01X2955280Y3405925D02*
X2955590Y3408633D01*
X2956055Y3410925D01*
X2956675Y3413008D01*
X2957450Y3415300D01*
X2958690Y3418425D01*
X2952490D01*
G01X2914350Y3651804D02*
X2915280Y3653053D01*
X2916365Y3653679D01*
X2917605Y3653887D01*
X2919155Y3653470D01*
X2920240Y3652429D01*
X2920550Y3651179D01*
X2920395Y3649928D01*
X2919775Y3648887D01*
X2916675Y3646804D01*
X2915280Y3645345D01*
X2914350Y3643262D01*
X2914040Y3641387D01*
X2920550D01*
G01X2929695D02*
Y3653887D01*
X2927835Y3651387D01*
G01Y3641387D02*
X2931555D01*
G01X2942095Y3640970D02*
X2941785Y3641179D01*
Y3641595D01*
X2942095Y3641804D01*
X2942405Y3641595D01*
Y3641179D01*
X2942095Y3640970D01*
G01X2954495Y3641387D02*
X2955580Y3641595D01*
X2956820Y3642220D01*
X2957595Y3643262D01*
X2957905Y3644720D01*
X2957595Y3646178D01*
X2956665Y3647429D01*
X2955270Y3648054D01*
X2953720D01*
X2952790Y3648470D01*
X2952015Y3649512D01*
X2951705Y3650970D01*
X2952170Y3652429D01*
X2953255Y3653470D01*
X2954495Y3653887D01*
X2955735Y3653470D01*
X2956820Y3652429D01*
X2957285Y3650970D01*
X2956975Y3649512D01*
X2956200Y3648470D01*
X2955270Y3648054D01*
X2953720D01*
X2952325Y3647429D01*
X2951395Y3646178D01*
X2951085Y3644720D01*
X2951395Y3643262D01*
X2952170Y3642220D01*
X2953410Y3641595D01*
X2954495Y3641387D01*
G01X2966585D02*
X2966895Y3644095D01*
X2967360Y3646387D01*
X2967980Y3648470D01*
X2968755Y3650762D01*
X2969995Y3653887D01*
X2963795D01*
G01X2923495Y3666387D02*
Y3678887D01*
X2921635Y3676387D01*
G01Y3666387D02*
X2925355D01*
G01X2935585D02*
X2935895Y3669095D01*
X2936360Y3671387D01*
X2936980Y3673470D01*
X2937755Y3675762D01*
X2938995Y3678887D01*
X2932795D01*
G01X2948295Y3665970D02*
X2947985Y3666179D01*
Y3666595D01*
X2948295Y3666804D01*
X2948605Y3666595D01*
Y3666179D01*
X2948295Y3665970D01*
G01X2960385Y3666387D02*
X2960695Y3669095D01*
X2961160Y3671387D01*
X2961780Y3673470D01*
X2962555Y3675762D01*
X2963795Y3678887D01*
X2957595D01*
G01X2923495Y3691387D02*
Y3703887D01*
X2921635Y3701387D01*
G01Y3691387D02*
X2925355D01*
G01X2932485Y3693262D02*
X2933415Y3692220D01*
X2934500Y3691595D01*
X2935895Y3691387D01*
X2937290Y3691804D01*
X2938375Y3692637D01*
X2939150Y3694095D01*
X2939305Y3695762D01*
X2938995Y3697429D01*
X2938220Y3698470D01*
X2937135Y3699304D01*
X2936050Y3699512D01*
X2934965Y3699304D01*
X2933570Y3698470D01*
X2934035Y3703887D01*
X2938220D01*
G01X2948295Y3690970D02*
X2947985Y3691179D01*
Y3691595D01*
X2948295Y3691804D01*
X2948605Y3691595D01*
Y3691179D01*
X2948295Y3690970D01*
G01X2960385Y3691387D02*
X2960695Y3694095D01*
X2961160Y3696387D01*
X2961780Y3698470D01*
X2962555Y3700762D01*
X2963795Y3703887D01*
X2957595D01*
G01X2939811Y41379D02*
X2940741Y39920D01*
X2941981Y39087D01*
X2943376Y38879D01*
X2944616Y39087D01*
X2945856Y40129D01*
X2946631Y41379D01*
X2946786Y42629D01*
X2946476Y44087D01*
X2945391Y45129D01*
X2944306Y45546D01*
X2942911D01*
G01X2944306D02*
X2945236Y46171D01*
X2946011Y47212D01*
X2946321Y48462D01*
X2946011Y49712D01*
X2945236Y50754D01*
X2943841Y51379D01*
X2942446Y51171D01*
X2941051Y50337D01*
G01X2952986Y40337D02*
X2954071Y39296D01*
X2955311Y38879D01*
X2956551Y39296D01*
X2957636Y40545D01*
X2958411Y42421D01*
X2958721Y44296D01*
Y46587D01*
X2958411Y48462D01*
X2957636Y50129D01*
X2956706Y50962D01*
X2955621Y51379D01*
X2954381Y50962D01*
X2953451Y50129D01*
X2952831Y48879D01*
X2952521Y47212D01*
X2952831Y45754D01*
X2953606Y44296D01*
X2954536Y43462D01*
X2955621Y43254D01*
X2956861Y43670D01*
X2957791Y44712D01*
X2958721Y46587D01*
G01X2969881Y38879D02*
Y51379D01*
X2964146Y42421D01*
X2971896D01*
G01X2980421Y38462D02*
X2980111Y38671D01*
Y39087D01*
X2980421Y39296D01*
X2980731Y39087D01*
Y38671D01*
X2980421Y38462D01*
G01X2992821Y51379D02*
X2991581Y50962D01*
X2990651Y49921D01*
X2990031Y48671D01*
X2989566Y47004D01*
X2989411Y45129D01*
X2989566Y43254D01*
X2990031Y41587D01*
X2990651Y40337D01*
X2991581Y39296D01*
X2992821Y38879D01*
X2994061Y39296D01*
X2994991Y40337D01*
X2995611Y41587D01*
X2996076Y43254D01*
X2996231Y45129D01*
X2996076Y47004D01*
X2995611Y48671D01*
X2994991Y49921D01*
X2994061Y50962D01*
X2992821Y51379D01*
G01X2940276Y108396D02*
X2941206Y109645D01*
X2942291Y110271D01*
X2943531Y110479D01*
X2945081Y110062D01*
X2946166Y109021D01*
X2946476Y107771D01*
X2946321Y106520D01*
X2945701Y105479D01*
X2942601Y103396D01*
X2941206Y101937D01*
X2940276Y99854D01*
X2939966Y97979D01*
X2946476D01*
G01X2955621D02*
Y110479D01*
X2953761Y107979D01*
G01Y97979D02*
X2957481D01*
G01X2967711D02*
X2968021Y100687D01*
X2968486Y102979D01*
X2969106Y105062D01*
X2969881Y107354D01*
X2971121Y110479D01*
X2964921D01*
G01X2980421Y97562D02*
X2980111Y97771D01*
Y98187D01*
X2980421Y98396D01*
X2980731Y98187D01*
Y97771D01*
X2980421Y97562D01*
G01X2992821Y110479D02*
X2991581Y110062D01*
X2990651Y109021D01*
X2990031Y107771D01*
X2989566Y106104D01*
X2989411Y104229D01*
X2989566Y102354D01*
X2990031Y100687D01*
X2990651Y99437D01*
X2991581Y98396D01*
X2992821Y97979D01*
X2994061Y98396D01*
X2994991Y99437D01*
X2995611Y100687D01*
X2996076Y102354D01*
X2996231Y104229D01*
X2996076Y106104D01*
X2995611Y107771D01*
X2994991Y109021D01*
X2994061Y110062D01*
X2992821Y110479D01*
G01X2943221Y157079D02*
Y169579D01*
X2941361Y167079D01*
G01Y157079D02*
X2945081D01*
G01X2952211Y158954D02*
X2953141Y157912D01*
X2954226Y157287D01*
X2955621Y157079D01*
X2957016Y157496D01*
X2958101Y158329D01*
X2958876Y159787D01*
X2959031Y161454D01*
X2958721Y163121D01*
X2957946Y164162D01*
X2956861Y164996D01*
X2955776Y165204D01*
X2954691Y164996D01*
X2953296Y164162D01*
X2953761Y169579D01*
X2957946D01*
G01X2968021Y157079D02*
X2969106Y157287D01*
X2970346Y157912D01*
X2971121Y158954D01*
X2971431Y160412D01*
X2971121Y161870D01*
X2970191Y163121D01*
X2968796Y163746D01*
X2967246D01*
X2966316Y164162D01*
X2965541Y165204D01*
X2965231Y166662D01*
X2965696Y168121D01*
X2966781Y169162D01*
X2968021Y169579D01*
X2969261Y169162D01*
X2970346Y168121D01*
X2970811Y166662D01*
X2970501Y165204D01*
X2969726Y164162D01*
X2968796Y163746D01*
X2967246D01*
X2965851Y163121D01*
X2964921Y161870D01*
X2964611Y160412D01*
X2964921Y158954D01*
X2965696Y157912D01*
X2966936Y157287D01*
X2968021Y157079D01*
G01X2980421Y156662D02*
X2980111Y156871D01*
Y157287D01*
X2980421Y157496D01*
X2980731Y157287D01*
Y156871D01*
X2980421Y156662D01*
G01X2992821Y169579D02*
X2991581Y169162D01*
X2990651Y168121D01*
X2990031Y166871D01*
X2989566Y165204D01*
X2989411Y163329D01*
X2989566Y161454D01*
X2990031Y159787D01*
X2990651Y158537D01*
X2991581Y157496D01*
X2992821Y157079D01*
X2994061Y157496D01*
X2994991Y158537D01*
X2995611Y159787D01*
X2996076Y161454D01*
X2996231Y163329D01*
X2996076Y165204D01*
X2995611Y166871D01*
X2994991Y168121D01*
X2994061Y169162D01*
X2992821Y169579D01*
G01X2943221Y216179D02*
Y228679D01*
X2941361Y226179D01*
G01Y216179D02*
X2945081D01*
G01X2952211Y218679D02*
X2953141Y217220D01*
X2954381Y216387D01*
X2955776Y216179D01*
X2957016Y216387D01*
X2958256Y217429D01*
X2959031Y218679D01*
X2959186Y219929D01*
X2958876Y221387D01*
X2957791Y222429D01*
X2956706Y222846D01*
X2955311D01*
G01X2956706D02*
X2957636Y223471D01*
X2958411Y224512D01*
X2958721Y225762D01*
X2958411Y227012D01*
X2957636Y228054D01*
X2956241Y228679D01*
X2954846Y228471D01*
X2953451Y227637D01*
G01X2964611Y218054D02*
X2965541Y217012D01*
X2966626Y216387D01*
X2968021Y216179D01*
X2969416Y216596D01*
X2970501Y217429D01*
X2971276Y218887D01*
X2971431Y220554D01*
X2971121Y222221D01*
X2970346Y223262D01*
X2969261Y224096D01*
X2968176Y224304D01*
X2967091Y224096D01*
X2965696Y223262D01*
X2966161Y228679D01*
X2970346D01*
G01X2980421Y215762D02*
X2980111Y215971D01*
Y216387D01*
X2980421Y216596D01*
X2980731Y216387D01*
Y215971D01*
X2980421Y215762D01*
G01X2992821Y228679D02*
X2991581Y228262D01*
X2990651Y227221D01*
X2990031Y225971D01*
X2989566Y224304D01*
X2989411Y222429D01*
X2989566Y220554D01*
X2990031Y218887D01*
X2990651Y217637D01*
X2991581Y216596D01*
X2992821Y216179D01*
X2994061Y216596D01*
X2994991Y217637D01*
X2995611Y218887D01*
X2996076Y220554D01*
X2996231Y222429D01*
X2996076Y224304D01*
X2995611Y225971D01*
X2994991Y227221D01*
X2994061Y228262D01*
X2992821Y228679D01*
G01X2943221Y275279D02*
Y287779D01*
X2941361Y285279D01*
G01Y275279D02*
X2945081D01*
G01X2952676Y285696D02*
X2953606Y286945D01*
X2954691Y287571D01*
X2955931Y287779D01*
X2957481Y287362D01*
X2958566Y286321D01*
X2958876Y285071D01*
X2958721Y283820D01*
X2958101Y282779D01*
X2955001Y280696D01*
X2953606Y279237D01*
X2952676Y277154D01*
X2952366Y275279D01*
X2958876D01*
G01X2964611Y277154D02*
X2965541Y276112D01*
X2966626Y275487D01*
X2968021Y275279D01*
X2969416Y275696D01*
X2970501Y276529D01*
X2971276Y277987D01*
X2971431Y279654D01*
X2971121Y281321D01*
X2970346Y282362D01*
X2969261Y283196D01*
X2968176Y283404D01*
X2967091Y283196D01*
X2965696Y282362D01*
X2966161Y287779D01*
X2970346D01*
G01X2980421Y274862D02*
X2980111Y275071D01*
Y275487D01*
X2980421Y275696D01*
X2980731Y275487D01*
Y275071D01*
X2980421Y274862D01*
G01X2992821Y287779D02*
X2991581Y287362D01*
X2990651Y286321D01*
X2990031Y285071D01*
X2989566Y283404D01*
X2989411Y281529D01*
X2989566Y279654D01*
X2990031Y277987D01*
X2990651Y276737D01*
X2991581Y275696D01*
X2992821Y275279D01*
X2994061Y275696D01*
X2994991Y276737D01*
X2995611Y277987D01*
X2996076Y279654D01*
X2996231Y281529D01*
X2996076Y283404D01*
X2995611Y285071D01*
X2994991Y286321D01*
X2994061Y287362D01*
X2992821Y287779D01*
G01X2943221Y334379D02*
Y346879D01*
X2941361Y344379D01*
G01Y334379D02*
X2945081D01*
G01X2952676Y344796D02*
X2953606Y346045D01*
X2954691Y346671D01*
X2955931Y346879D01*
X2957481Y346462D01*
X2958566Y345421D01*
X2958876Y344171D01*
X2958721Y342920D01*
X2958101Y341879D01*
X2955001Y339796D01*
X2953606Y338337D01*
X2952676Y336254D01*
X2952366Y334379D01*
X2958876D01*
G01X2964611Y336254D02*
X2965541Y335212D01*
X2966626Y334587D01*
X2968021Y334379D01*
X2969416Y334796D01*
X2970501Y335629D01*
X2971276Y337087D01*
X2971431Y338754D01*
X2971121Y340421D01*
X2970346Y341462D01*
X2969261Y342296D01*
X2968176Y342504D01*
X2967091Y342296D01*
X2965696Y341462D01*
X2966161Y346879D01*
X2970346D01*
G01X2980421Y333962D02*
X2980111Y334171D01*
Y334587D01*
X2980421Y334796D01*
X2980731Y334587D01*
Y334171D01*
X2980421Y333962D01*
G01X2992821Y346879D02*
X2991581Y346462D01*
X2990651Y345421D01*
X2990031Y344171D01*
X2989566Y342504D01*
X2989411Y340629D01*
X2989566Y338754D01*
X2990031Y337087D01*
X2990651Y335837D01*
X2991581Y334796D01*
X2992821Y334379D01*
X2994061Y334796D01*
X2994991Y335837D01*
X2995611Y337087D01*
X2996076Y338754D01*
X2996231Y340629D01*
X2996076Y342504D01*
X2995611Y344171D01*
X2994991Y345421D01*
X2994061Y346462D01*
X2992821Y346879D01*
G01X2943221Y393479D02*
Y405979D01*
X2941361Y403479D01*
G01Y393479D02*
X2945081D01*
G01X2952676Y403896D02*
X2953606Y405145D01*
X2954691Y405771D01*
X2955931Y405979D01*
X2957481Y405562D01*
X2958566Y404521D01*
X2958876Y403271D01*
X2958721Y402020D01*
X2958101Y400979D01*
X2955001Y398896D01*
X2953606Y397437D01*
X2952676Y395354D01*
X2952366Y393479D01*
X2958876D01*
G01X2965076Y403896D02*
X2966006Y405145D01*
X2967091Y405771D01*
X2968331Y405979D01*
X2969881Y405562D01*
X2970966Y404521D01*
X2971276Y403271D01*
X2971121Y402020D01*
X2970501Y400979D01*
X2967401Y398896D01*
X2966006Y397437D01*
X2965076Y395354D01*
X2964766Y393479D01*
X2971276D01*
G01X2980421Y393062D02*
X2980111Y393271D01*
Y393687D01*
X2980421Y393896D01*
X2980731Y393687D01*
Y393271D01*
X2980421Y393062D01*
G01X2992821Y405979D02*
X2991581Y405562D01*
X2990651Y404521D01*
X2990031Y403271D01*
X2989566Y401604D01*
X2989411Y399729D01*
X2989566Y397854D01*
X2990031Y396187D01*
X2990651Y394937D01*
X2991581Y393896D01*
X2992821Y393479D01*
X2994061Y393896D01*
X2994991Y394937D01*
X2995611Y396187D01*
X2996076Y397854D01*
X2996231Y399729D01*
X2996076Y401604D01*
X2995611Y403271D01*
X2994991Y404521D01*
X2994061Y405562D01*
X2992821Y405979D01*
G01X2943221Y452579D02*
Y465079D01*
X2941361Y462579D01*
G01Y452579D02*
X2945081D01*
G01X2952676Y462996D02*
X2953606Y464245D01*
X2954691Y464871D01*
X2955931Y465079D01*
X2957481Y464662D01*
X2958566Y463621D01*
X2958876Y462371D01*
X2958721Y461120D01*
X2958101Y460079D01*
X2955001Y457996D01*
X2953606Y456537D01*
X2952676Y454454D01*
X2952366Y452579D01*
X2958876D01*
G01X2968021Y465079D02*
X2966781Y464662D01*
X2965851Y463621D01*
X2965231Y462371D01*
X2964766Y460704D01*
X2964611Y458829D01*
X2964766Y456954D01*
X2965231Y455287D01*
X2965851Y454037D01*
X2966781Y452996D01*
X2968021Y452579D01*
X2969261Y452996D01*
X2970191Y454037D01*
X2970811Y455287D01*
X2971276Y456954D01*
X2971431Y458829D01*
X2971276Y460704D01*
X2970811Y462371D01*
X2970191Y463621D01*
X2969261Y464662D01*
X2968021Y465079D01*
G01X2980421Y452162D02*
X2980111Y452371D01*
Y452787D01*
X2980421Y452996D01*
X2980731Y452787D01*
Y452371D01*
X2980421Y452162D01*
G01X2992821Y465079D02*
X2991581Y464662D01*
X2990651Y463621D01*
X2990031Y462371D01*
X2989566Y460704D01*
X2989411Y458829D01*
X2989566Y456954D01*
X2990031Y455287D01*
X2990651Y454037D01*
X2991581Y452996D01*
X2992821Y452579D01*
X2994061Y452996D01*
X2994991Y454037D01*
X2995611Y455287D01*
X2996076Y456954D01*
X2996231Y458829D01*
X2996076Y460704D01*
X2995611Y462371D01*
X2994991Y463621D01*
X2994061Y464662D01*
X2992821Y465079D01*
G01X2940276Y876696D02*
X2941206Y877945D01*
X2942291Y878571D01*
X2943531Y878779D01*
X2945081Y878362D01*
X2946166Y877321D01*
X2946476Y876071D01*
X2946321Y874820D01*
X2945701Y873779D01*
X2942601Y871696D01*
X2941206Y870237D01*
X2940276Y868154D01*
X2939966Y866279D01*
X2946476D01*
G01X2952676Y876696D02*
X2953606Y877945D01*
X2954691Y878571D01*
X2955931Y878779D01*
X2957481Y878362D01*
X2958566Y877321D01*
X2958876Y876071D01*
X2958721Y874820D01*
X2958101Y873779D01*
X2955001Y871696D01*
X2953606Y870237D01*
X2952676Y868154D01*
X2952366Y866279D01*
X2958876D01*
G01X2968021D02*
Y878779D01*
X2966161Y876279D01*
G01Y866279D02*
X2969881D01*
G01X2980421Y865862D02*
X2980111Y866071D01*
Y866487D01*
X2980421Y866696D01*
X2980731Y866487D01*
Y866071D01*
X2980421Y865862D01*
G01X2992821Y878779D02*
X2991581Y878362D01*
X2990651Y877321D01*
X2990031Y876071D01*
X2989566Y874404D01*
X2989411Y872529D01*
X2989566Y870654D01*
X2990031Y868987D01*
X2990651Y867737D01*
X2991581Y866696D01*
X2992821Y866279D01*
X2994061Y866696D01*
X2994991Y867737D01*
X2995611Y868987D01*
X2996076Y870654D01*
X2996231Y872529D01*
X2996076Y874404D01*
X2995611Y876071D01*
X2994991Y877321D01*
X2994061Y878362D01*
X2992821Y878779D01*
G01X2943221Y925379D02*
Y937879D01*
X2941361Y935379D01*
G01Y925379D02*
X2945081D01*
G01X2952676Y930587D02*
X2953761Y932046D01*
X2954691Y932879D01*
X2955931Y933296D01*
X2957016Y932879D01*
X2957791Y932046D01*
X2958411Y930796D01*
X2958566Y929337D01*
X2958411Y928087D01*
X2957791Y926837D01*
X2956861Y925796D01*
X2955776Y925379D01*
X2954536Y925796D01*
X2953451Y927045D01*
X2952831Y928921D01*
X2952676Y931004D01*
X2952986Y933712D01*
X2953451Y935171D01*
X2954226Y936629D01*
X2955311Y937671D01*
X2956396Y937879D01*
X2957481Y937462D01*
X2958256Y936421D01*
G01X2965076Y930587D02*
X2966161Y932046D01*
X2967091Y932879D01*
X2968331Y933296D01*
X2969416Y932879D01*
X2970191Y932046D01*
X2970811Y930796D01*
X2970966Y929337D01*
X2970811Y928087D01*
X2970191Y926837D01*
X2969261Y925796D01*
X2968176Y925379D01*
X2966936Y925796D01*
X2965851Y927045D01*
X2965231Y928921D01*
X2965076Y931004D01*
X2965386Y933712D01*
X2965851Y935171D01*
X2966626Y936629D01*
X2967711Y937671D01*
X2968796Y937879D01*
X2969881Y937462D01*
X2970656Y936421D01*
G01X2980421Y924962D02*
X2980111Y925171D01*
Y925587D01*
X2980421Y925796D01*
X2980731Y925587D01*
Y925171D01*
X2980421Y924962D01*
G01X2992821Y937879D02*
X2991581Y937462D01*
X2990651Y936421D01*
X2990031Y935171D01*
X2989566Y933504D01*
X2989411Y931629D01*
X2989566Y929754D01*
X2990031Y928087D01*
X2990651Y926837D01*
X2991581Y925796D01*
X2992821Y925379D01*
X2994061Y925796D01*
X2994991Y926837D01*
X2995611Y928087D01*
X2996076Y929754D01*
X2996231Y931629D01*
X2996076Y933504D01*
X2995611Y935171D01*
X2994991Y936421D01*
X2994061Y937462D01*
X2992821Y937879D01*
G01X2943221Y984479D02*
Y996979D01*
X2941361Y994479D01*
G01Y984479D02*
X2945081D01*
G01X2952211Y986354D02*
X2953141Y985312D01*
X2954226Y984687D01*
X2955621Y984479D01*
X2957016Y984896D01*
X2958101Y985729D01*
X2958876Y987187D01*
X2959031Y988854D01*
X2958721Y990521D01*
X2957946Y991562D01*
X2956861Y992396D01*
X2955776Y992604D01*
X2954691Y992396D01*
X2953296Y991562D01*
X2953761Y996979D01*
X2957946D01*
G01X2968021D02*
X2966781Y996562D01*
X2965851Y995521D01*
X2965231Y994271D01*
X2964766Y992604D01*
X2964611Y990729D01*
X2964766Y988854D01*
X2965231Y987187D01*
X2965851Y985937D01*
X2966781Y984896D01*
X2968021Y984479D01*
X2969261Y984896D01*
X2970191Y985937D01*
X2970811Y987187D01*
X2971276Y988854D01*
X2971431Y990729D01*
X2971276Y992604D01*
X2970811Y994271D01*
X2970191Y995521D01*
X2969261Y996562D01*
X2968021Y996979D01*
G01X2980421Y984062D02*
X2980111Y984271D01*
Y984687D01*
X2980421Y984896D01*
X2980731Y984687D01*
Y984271D01*
X2980421Y984062D01*
G01X2992821Y996979D02*
X2991581Y996562D01*
X2990651Y995521D01*
X2990031Y994271D01*
X2989566Y992604D01*
X2989411Y990729D01*
X2989566Y988854D01*
X2990031Y987187D01*
X2990651Y985937D01*
X2991581Y984896D01*
X2992821Y984479D01*
X2994061Y984896D01*
X2994991Y985937D01*
X2995611Y987187D01*
X2996076Y988854D01*
X2996231Y990729D01*
X2996076Y992604D01*
X2995611Y994271D01*
X2994991Y995521D01*
X2994061Y996562D01*
X2992821Y996979D01*
G01X2943221Y1043579D02*
Y1056079D01*
X2941361Y1053579D01*
G01Y1043579D02*
X2945081D01*
G01X2952676Y1053996D02*
X2953606Y1055245D01*
X2954691Y1055871D01*
X2955931Y1056079D01*
X2957481Y1055662D01*
X2958566Y1054621D01*
X2958876Y1053371D01*
X2958721Y1052120D01*
X2958101Y1051079D01*
X2955001Y1048996D01*
X2953606Y1047537D01*
X2952676Y1045454D01*
X2952366Y1043579D01*
X2958876D01*
G01X2965076Y1048787D02*
X2966161Y1050246D01*
X2967091Y1051079D01*
X2968331Y1051496D01*
X2969416Y1051079D01*
X2970191Y1050246D01*
X2970811Y1048996D01*
X2970966Y1047537D01*
X2970811Y1046287D01*
X2970191Y1045037D01*
X2969261Y1043996D01*
X2968176Y1043579D01*
X2966936Y1043996D01*
X2965851Y1045245D01*
X2965231Y1047121D01*
X2965076Y1049204D01*
X2965386Y1051912D01*
X2965851Y1053371D01*
X2966626Y1054829D01*
X2967711Y1055871D01*
X2968796Y1056079D01*
X2969881Y1055662D01*
X2970656Y1054621D01*
G01X2980421Y1043162D02*
X2980111Y1043371D01*
Y1043787D01*
X2980421Y1043996D01*
X2980731Y1043787D01*
Y1043371D01*
X2980421Y1043162D01*
G01X2992821Y1056079D02*
X2991581Y1055662D01*
X2990651Y1054621D01*
X2990031Y1053371D01*
X2989566Y1051704D01*
X2989411Y1049829D01*
X2989566Y1047954D01*
X2990031Y1046287D01*
X2990651Y1045037D01*
X2991581Y1043996D01*
X2992821Y1043579D01*
X2994061Y1043996D01*
X2994991Y1045037D01*
X2995611Y1046287D01*
X2996076Y1047954D01*
X2996231Y1049829D01*
X2996076Y1051704D01*
X2995611Y1053371D01*
X2994991Y1054621D01*
X2994061Y1055662D01*
X2992821Y1056079D01*
G01X2945081Y1398179D02*
Y1410679D01*
X2939346Y1401721D01*
X2947096D01*
G01X2955621Y1410679D02*
X2954381Y1410262D01*
X2953451Y1409221D01*
X2952831Y1407971D01*
X2952366Y1406304D01*
X2952211Y1404429D01*
X2952366Y1402554D01*
X2952831Y1400887D01*
X2953451Y1399637D01*
X2954381Y1398596D01*
X2955621Y1398179D01*
X2956861Y1398596D01*
X2957791Y1399637D01*
X2958411Y1400887D01*
X2958876Y1402554D01*
X2959031Y1404429D01*
X2958876Y1406304D01*
X2958411Y1407971D01*
X2957791Y1409221D01*
X2956861Y1410262D01*
X2955621Y1410679D01*
G01X2968021Y1397762D02*
X2967711Y1397971D01*
Y1398387D01*
X2968021Y1398596D01*
X2968331Y1398387D01*
Y1397971D01*
X2968021Y1397762D01*
G01X2980421Y1398179D02*
Y1410679D01*
X2978561Y1408179D01*
G01Y1398179D02*
X2982281D01*
G01X2989411Y1400054D02*
X2990341Y1399012D01*
X2991426Y1398387D01*
X2992821Y1398179D01*
X2994216Y1398596D01*
X2995301Y1399429D01*
X2996076Y1400887D01*
X2996231Y1402554D01*
X2995921Y1404221D01*
X2995146Y1405262D01*
X2994061Y1406096D01*
X2992976Y1406304D01*
X2991891Y1406096D01*
X2990496Y1405262D01*
X2990961Y1410679D01*
X2995146D01*
G01X2943221Y1634579D02*
Y1647079D01*
X2941361Y1644579D01*
G01Y1634579D02*
X2945081D01*
G01X2952986Y1636037D02*
X2954071Y1634996D01*
X2955311Y1634579D01*
X2956551Y1634996D01*
X2957636Y1636245D01*
X2958411Y1638121D01*
X2958721Y1639996D01*
Y1642287D01*
X2958411Y1644162D01*
X2957636Y1645829D01*
X2956706Y1646662D01*
X2955621Y1647079D01*
X2954381Y1646662D01*
X2953451Y1645829D01*
X2952831Y1644579D01*
X2952521Y1642912D01*
X2952831Y1641454D01*
X2953606Y1639996D01*
X2954536Y1639162D01*
X2955621Y1638954D01*
X2956861Y1639370D01*
X2957791Y1640412D01*
X2958721Y1642287D01*
G01X2968021Y1634162D02*
X2967711Y1634371D01*
Y1634787D01*
X2968021Y1634996D01*
X2968331Y1634787D01*
Y1634371D01*
X2968021Y1634162D01*
G01X2977476Y1639787D02*
X2978561Y1641246D01*
X2979491Y1642079D01*
X2980731Y1642496D01*
X2981816Y1642079D01*
X2982591Y1641246D01*
X2983211Y1639996D01*
X2983366Y1638537D01*
X2983211Y1637287D01*
X2982591Y1636037D01*
X2981661Y1634996D01*
X2980576Y1634579D01*
X2979336Y1634996D01*
X2978251Y1636245D01*
X2977631Y1638121D01*
X2977476Y1640204D01*
X2977786Y1642912D01*
X2978251Y1644371D01*
X2979026Y1645829D01*
X2980111Y1646871D01*
X2981196Y1647079D01*
X2982281Y1646662D01*
X2983056Y1645621D01*
G01X2992821Y1634579D02*
X2993906Y1634787D01*
X2995146Y1635412D01*
X2995921Y1636454D01*
X2996231Y1637912D01*
X2995921Y1639370D01*
X2994991Y1640621D01*
X2993596Y1641246D01*
X2992046D01*
X2991116Y1641662D01*
X2990341Y1642704D01*
X2990031Y1644162D01*
X2990496Y1645621D01*
X2991581Y1646662D01*
X2992821Y1647079D01*
X2994061Y1646662D01*
X2995146Y1645621D01*
X2995611Y1644162D01*
X2995301Y1642704D01*
X2994526Y1641662D01*
X2993596Y1641246D01*
X2992046D01*
X2990651Y1640621D01*
X2989721Y1639370D01*
X2989411Y1637912D01*
X2989721Y1636454D01*
X2990496Y1635412D01*
X2991736Y1634787D01*
X2992821Y1634579D01*
G01X2943221Y1693679D02*
Y1706179D01*
X2941361Y1703679D01*
G01Y1693679D02*
X2945081D01*
G01X2957481D02*
Y1706179D01*
X2951746Y1697221D01*
X2959496D01*
G01X2968021Y1693262D02*
X2967711Y1693471D01*
Y1693887D01*
X2968021Y1694096D01*
X2968331Y1693887D01*
Y1693471D01*
X2968021Y1693262D01*
G01X2980421Y1693679D02*
Y1706179D01*
X2978561Y1703679D01*
G01Y1693679D02*
X2982281D01*
G01X2992511D02*
X2992821Y1696387D01*
X2993286Y1698679D01*
X2993906Y1700762D01*
X2994681Y1703054D01*
X2995921Y1706179D01*
X2989721D01*
G01X2946476Y516887D02*
X2947561Y518346D01*
X2948491Y519179D01*
X2949731Y519596D01*
X2950816Y519179D01*
X2951591Y518346D01*
X2952211Y517096D01*
X2952366Y515637D01*
X2952211Y514387D01*
X2951591Y513137D01*
X2950661Y512096D01*
X2949576Y511679D01*
X2948336Y512096D01*
X2947251Y513345D01*
X2946631Y515221D01*
X2946476Y517304D01*
X2946786Y520012D01*
X2947251Y521471D01*
X2948026Y522929D01*
X2949111Y523971D01*
X2950196Y524179D01*
X2951281Y523762D01*
X2952056Y522721D01*
G01X2958411Y513554D02*
X2959341Y512512D01*
X2960426Y511887D01*
X2961821Y511679D01*
X2963216Y512096D01*
X2964301Y512929D01*
X2965076Y514387D01*
X2965231Y516054D01*
X2964921Y517721D01*
X2964146Y518762D01*
X2963061Y519596D01*
X2961976Y519804D01*
X2960891Y519596D01*
X2959496Y518762D01*
X2959961Y524179D01*
X2964146D01*
G01X2974221Y511262D02*
X2973911Y511471D01*
Y511887D01*
X2974221Y512096D01*
X2974531Y511887D01*
Y511471D01*
X2974221Y511262D01*
G01X2986621Y524179D02*
X2985381Y523762D01*
X2984451Y522721D01*
X2983831Y521471D01*
X2983366Y519804D01*
X2983211Y517929D01*
X2983366Y516054D01*
X2983831Y514387D01*
X2984451Y513137D01*
X2985381Y512096D01*
X2986621Y511679D01*
X2987861Y512096D01*
X2988791Y513137D01*
X2989411Y514387D01*
X2989876Y516054D01*
X2990031Y517929D01*
X2989876Y519804D01*
X2989411Y521471D01*
X2988791Y522721D01*
X2987861Y523762D01*
X2986621Y524179D01*
G01X2951281Y570779D02*
Y583279D01*
X2945546Y574321D01*
X2953296D01*
G01X2958876Y575987D02*
X2959961Y577446D01*
X2960891Y578279D01*
X2962131Y578696D01*
X2963216Y578279D01*
X2963991Y577446D01*
X2964611Y576196D01*
X2964766Y574737D01*
X2964611Y573487D01*
X2963991Y572237D01*
X2963061Y571196D01*
X2961976Y570779D01*
X2960736Y571196D01*
X2959651Y572445D01*
X2959031Y574321D01*
X2958876Y576404D01*
X2959186Y579112D01*
X2959651Y580571D01*
X2960426Y582029D01*
X2961511Y583071D01*
X2962596Y583279D01*
X2963681Y582862D01*
X2964456Y581821D01*
G01X2974221Y570362D02*
X2973911Y570571D01*
Y570987D01*
X2974221Y571196D01*
X2974531Y570987D01*
Y570571D01*
X2974221Y570362D01*
G01X2986621Y583279D02*
X2985381Y582862D01*
X2984451Y581821D01*
X2983831Y580571D01*
X2983366Y578904D01*
X2983211Y577029D01*
X2983366Y575154D01*
X2983831Y573487D01*
X2984451Y572237D01*
X2985381Y571196D01*
X2986621Y570779D01*
X2987861Y571196D01*
X2988791Y572237D01*
X2989411Y573487D01*
X2989876Y575154D01*
X2990031Y577029D01*
X2989876Y578904D01*
X2989411Y580571D01*
X2988791Y581821D01*
X2987861Y582862D01*
X2986621Y583279D01*
G01X2951281Y629879D02*
Y642379D01*
X2945546Y633421D01*
X2953296D01*
G01X2963681Y629879D02*
Y642379D01*
X2957946Y633421D01*
X2965696D01*
G01X2974221Y629462D02*
X2973911Y629671D01*
Y630087D01*
X2974221Y630296D01*
X2974531Y630087D01*
Y629671D01*
X2974221Y629462D01*
G01X2986621Y642379D02*
X2985381Y641962D01*
X2984451Y640921D01*
X2983831Y639671D01*
X2983366Y638004D01*
X2983211Y636129D01*
X2983366Y634254D01*
X2983831Y632587D01*
X2984451Y631337D01*
X2985381Y630296D01*
X2986621Y629879D01*
X2987861Y630296D01*
X2988791Y631337D01*
X2989411Y632587D01*
X2989876Y634254D01*
X2990031Y636129D01*
X2989876Y638004D01*
X2989411Y639671D01*
X2988791Y640921D01*
X2987861Y641962D01*
X2986621Y642379D01*
G01X2951281Y688979D02*
Y701479D01*
X2945546Y692521D01*
X2953296D01*
G01X2961821Y688979D02*
Y701479D01*
X2959961Y698979D01*
G01Y688979D02*
X2963681D01*
G01X2974221Y688562D02*
X2973911Y688771D01*
Y689187D01*
X2974221Y689396D01*
X2974531Y689187D01*
Y688771D01*
X2974221Y688562D01*
G01X2986621Y701479D02*
X2985381Y701062D01*
X2984451Y700021D01*
X2983831Y698771D01*
X2983366Y697104D01*
X2983211Y695229D01*
X2983366Y693354D01*
X2983831Y691687D01*
X2984451Y690437D01*
X2985381Y689396D01*
X2986621Y688979D01*
X2987861Y689396D01*
X2988791Y690437D01*
X2989411Y691687D01*
X2989876Y693354D01*
X2990031Y695229D01*
X2989876Y697104D01*
X2989411Y698771D01*
X2988791Y700021D01*
X2987861Y701062D01*
X2986621Y701479D01*
G01X2951281Y748079D02*
Y760579D01*
X2945546Y751621D01*
X2953296D01*
G01X2961821Y760579D02*
X2960581Y760162D01*
X2959651Y759121D01*
X2959031Y757871D01*
X2958566Y756204D01*
X2958411Y754329D01*
X2958566Y752454D01*
X2959031Y750787D01*
X2959651Y749537D01*
X2960581Y748496D01*
X2961821Y748079D01*
X2963061Y748496D01*
X2963991Y749537D01*
X2964611Y750787D01*
X2965076Y752454D01*
X2965231Y754329D01*
X2965076Y756204D01*
X2964611Y757871D01*
X2963991Y759121D01*
X2963061Y760162D01*
X2961821Y760579D01*
G01X2974221Y747662D02*
X2973911Y747871D01*
Y748287D01*
X2974221Y748496D01*
X2974531Y748287D01*
Y747871D01*
X2974221Y747662D01*
G01X2986621Y760579D02*
X2985381Y760162D01*
X2984451Y759121D01*
X2983831Y757871D01*
X2983366Y756204D01*
X2983211Y754329D01*
X2983366Y752454D01*
X2983831Y750787D01*
X2984451Y749537D01*
X2985381Y748496D01*
X2986621Y748079D01*
X2987861Y748496D01*
X2988791Y749537D01*
X2989411Y750787D01*
X2989876Y752454D01*
X2990031Y754329D01*
X2989876Y756204D01*
X2989411Y757871D01*
X2988791Y759121D01*
X2987861Y760162D01*
X2986621Y760579D01*
G01X2946011Y809679D02*
X2946941Y808220D01*
X2948181Y807387D01*
X2949576Y807179D01*
X2950816Y807387D01*
X2952056Y808429D01*
X2952831Y809679D01*
X2952986Y810929D01*
X2952676Y812387D01*
X2951591Y813429D01*
X2950506Y813846D01*
X2949111D01*
G01X2950506D02*
X2951436Y814471D01*
X2952211Y815512D01*
X2952521Y816762D01*
X2952211Y818012D01*
X2951436Y819054D01*
X2950041Y819679D01*
X2948646Y819471D01*
X2947251Y818637D01*
G01X2961821Y819679D02*
X2960581Y819262D01*
X2959651Y818221D01*
X2959031Y816971D01*
X2958566Y815304D01*
X2958411Y813429D01*
X2958566Y811554D01*
X2959031Y809887D01*
X2959651Y808637D01*
X2960581Y807596D01*
X2961821Y807179D01*
X2963061Y807596D01*
X2963991Y808637D01*
X2964611Y809887D01*
X2965076Y811554D01*
X2965231Y813429D01*
X2965076Y815304D01*
X2964611Y816971D01*
X2963991Y818221D01*
X2963061Y819262D01*
X2961821Y819679D01*
G01X2974221Y806762D02*
X2973911Y806971D01*
Y807387D01*
X2974221Y807596D01*
X2974531Y807387D01*
Y806971D01*
X2974221Y806762D01*
G01X2986621Y819679D02*
X2985381Y819262D01*
X2984451Y818221D01*
X2983831Y816971D01*
X2983366Y815304D01*
X2983211Y813429D01*
X2983366Y811554D01*
X2983831Y809887D01*
X2984451Y808637D01*
X2985381Y807596D01*
X2986621Y807179D01*
X2987861Y807596D01*
X2988791Y808637D01*
X2989411Y809887D01*
X2989876Y811554D01*
X2990031Y813429D01*
X2989876Y815304D01*
X2989411Y816971D01*
X2988791Y818221D01*
X2987861Y819262D01*
X2986621Y819679D01*
G01X2949111Y1102679D02*
X2949421Y1105387D01*
X2949886Y1107679D01*
X2950506Y1109762D01*
X2951281Y1112054D01*
X2952521Y1115179D01*
X2946321D01*
G01X2959186Y1104137D02*
X2960271Y1103096D01*
X2961511Y1102679D01*
X2962751Y1103096D01*
X2963836Y1104345D01*
X2964611Y1106221D01*
X2964921Y1108096D01*
Y1110387D01*
X2964611Y1112262D01*
X2963836Y1113929D01*
X2962906Y1114762D01*
X2961821Y1115179D01*
X2960581Y1114762D01*
X2959651Y1113929D01*
X2959031Y1112679D01*
X2958721Y1111012D01*
X2959031Y1109554D01*
X2959806Y1108096D01*
X2960736Y1107262D01*
X2961821Y1107054D01*
X2963061Y1107470D01*
X2963991Y1108512D01*
X2964921Y1110387D01*
G01X2974221Y1102262D02*
X2973911Y1102471D01*
Y1102887D01*
X2974221Y1103096D01*
X2974531Y1102887D01*
Y1102471D01*
X2974221Y1102262D01*
G01X2986621Y1115179D02*
X2985381Y1114762D01*
X2984451Y1113721D01*
X2983831Y1112471D01*
X2983366Y1110804D01*
X2983211Y1108929D01*
X2983366Y1107054D01*
X2983831Y1105387D01*
X2984451Y1104137D01*
X2985381Y1103096D01*
X2986621Y1102679D01*
X2987861Y1103096D01*
X2988791Y1104137D01*
X2989411Y1105387D01*
X2989876Y1107054D01*
X2990031Y1108929D01*
X2989876Y1110804D01*
X2989411Y1112471D01*
X2988791Y1113721D01*
X2987861Y1114762D01*
X2986621Y1115179D01*
G01X2946476Y1166987D02*
X2947561Y1168446D01*
X2948491Y1169279D01*
X2949731Y1169696D01*
X2950816Y1169279D01*
X2951591Y1168446D01*
X2952211Y1167196D01*
X2952366Y1165737D01*
X2952211Y1164487D01*
X2951591Y1163237D01*
X2950661Y1162196D01*
X2949576Y1161779D01*
X2948336Y1162196D01*
X2947251Y1163445D01*
X2946631Y1165321D01*
X2946476Y1167404D01*
X2946786Y1170112D01*
X2947251Y1171571D01*
X2948026Y1173029D01*
X2949111Y1174071D01*
X2950196Y1174279D01*
X2951281Y1173862D01*
X2952056Y1172821D01*
G01X2961511Y1161779D02*
X2961821Y1164487D01*
X2962286Y1166779D01*
X2962906Y1168862D01*
X2963681Y1171154D01*
X2964921Y1174279D01*
X2958721D01*
G01X2974221Y1161362D02*
X2973911Y1161571D01*
Y1161987D01*
X2974221Y1162196D01*
X2974531Y1161987D01*
Y1161571D01*
X2974221Y1161362D01*
G01X2986621Y1174279D02*
X2985381Y1173862D01*
X2984451Y1172821D01*
X2983831Y1171571D01*
X2983366Y1169904D01*
X2983211Y1168029D01*
X2983366Y1166154D01*
X2983831Y1164487D01*
X2984451Y1163237D01*
X2985381Y1162196D01*
X2986621Y1161779D01*
X2987861Y1162196D01*
X2988791Y1163237D01*
X2989411Y1164487D01*
X2989876Y1166154D01*
X2990031Y1168029D01*
X2989876Y1169904D01*
X2989411Y1171571D01*
X2988791Y1172821D01*
X2987861Y1173862D01*
X2986621Y1174279D01*
G01X2951281Y1220879D02*
Y1233379D01*
X2945546Y1224421D01*
X2953296D01*
G01X2963681Y1220879D02*
Y1233379D01*
X2957946Y1224421D01*
X2965696D01*
G01X2974221Y1220462D02*
X2973911Y1220671D01*
Y1221087D01*
X2974221Y1221296D01*
X2974531Y1221087D01*
Y1220671D01*
X2974221Y1220462D01*
G01X2986621Y1233379D02*
X2985381Y1232962D01*
X2984451Y1231921D01*
X2983831Y1230671D01*
X2983366Y1229004D01*
X2983211Y1227129D01*
X2983366Y1225254D01*
X2983831Y1223587D01*
X2984451Y1222337D01*
X2985381Y1221296D01*
X2986621Y1220879D01*
X2987861Y1221296D01*
X2988791Y1222337D01*
X2989411Y1223587D01*
X2989876Y1225254D01*
X2990031Y1227129D01*
X2989876Y1229004D01*
X2989411Y1230671D01*
X2988791Y1231921D01*
X2987861Y1232962D01*
X2986621Y1233379D01*
G01X2951281Y1279979D02*
Y1292479D01*
X2945546Y1283521D01*
X2953296D01*
G01X2958876Y1290396D02*
X2959806Y1291645D01*
X2960891Y1292271D01*
X2962131Y1292479D01*
X2963681Y1292062D01*
X2964766Y1291021D01*
X2965076Y1289771D01*
X2964921Y1288520D01*
X2964301Y1287479D01*
X2961201Y1285396D01*
X2959806Y1283937D01*
X2958876Y1281854D01*
X2958566Y1279979D01*
X2965076D01*
G01X2974221Y1279562D02*
X2973911Y1279771D01*
Y1280187D01*
X2974221Y1280396D01*
X2974531Y1280187D01*
Y1279771D01*
X2974221Y1279562D01*
G01X2986621Y1292479D02*
X2985381Y1292062D01*
X2984451Y1291021D01*
X2983831Y1289771D01*
X2983366Y1288104D01*
X2983211Y1286229D01*
X2983366Y1284354D01*
X2983831Y1282687D01*
X2984451Y1281437D01*
X2985381Y1280396D01*
X2986621Y1279979D01*
X2987861Y1280396D01*
X2988791Y1281437D01*
X2989411Y1282687D01*
X2989876Y1284354D01*
X2990031Y1286229D01*
X2989876Y1288104D01*
X2989411Y1289771D01*
X2988791Y1291021D01*
X2987861Y1292062D01*
X2986621Y1292479D01*
G01X2951281Y1339079D02*
Y1351579D01*
X2945546Y1342621D01*
X2953296D01*
G01X2961821Y1339079D02*
Y1351579D01*
X2959961Y1349079D01*
G01Y1339079D02*
X2963681D01*
G01X2974221Y1338662D02*
X2973911Y1338871D01*
Y1339287D01*
X2974221Y1339496D01*
X2974531Y1339287D01*
Y1338871D01*
X2974221Y1338662D01*
G01X2986621Y1351579D02*
X2985381Y1351162D01*
X2984451Y1350121D01*
X2983831Y1348871D01*
X2983366Y1347204D01*
X2983211Y1345329D01*
X2983366Y1343454D01*
X2983831Y1341787D01*
X2984451Y1340537D01*
X2985381Y1339496D01*
X2986621Y1339079D01*
X2987861Y1339496D01*
X2988791Y1340537D01*
X2989411Y1341787D01*
X2989876Y1343454D01*
X2990031Y1345329D01*
X2989876Y1347204D01*
X2989411Y1348871D01*
X2988791Y1350121D01*
X2987861Y1351162D01*
X2986621Y1351579D01*
G01X2951281Y1457279D02*
Y1469779D01*
X2945546Y1460821D01*
X2953296D01*
G01X2961821Y1469779D02*
X2960581Y1469362D01*
X2959651Y1468321D01*
X2959031Y1467071D01*
X2958566Y1465404D01*
X2958411Y1463529D01*
X2958566Y1461654D01*
X2959031Y1459987D01*
X2959651Y1458737D01*
X2960581Y1457696D01*
X2961821Y1457279D01*
X2963061Y1457696D01*
X2963991Y1458737D01*
X2964611Y1459987D01*
X2965076Y1461654D01*
X2965231Y1463529D01*
X2965076Y1465404D01*
X2964611Y1467071D01*
X2963991Y1468321D01*
X2963061Y1469362D01*
X2961821Y1469779D01*
G01X2974221Y1456862D02*
X2973911Y1457071D01*
Y1457487D01*
X2974221Y1457696D01*
X2974531Y1457487D01*
Y1457071D01*
X2974221Y1456862D01*
G01X2986621Y1469779D02*
X2985381Y1469362D01*
X2984451Y1468321D01*
X2983831Y1467071D01*
X2983366Y1465404D01*
X2983211Y1463529D01*
X2983366Y1461654D01*
X2983831Y1459987D01*
X2984451Y1458737D01*
X2985381Y1457696D01*
X2986621Y1457279D01*
X2987861Y1457696D01*
X2988791Y1458737D01*
X2989411Y1459987D01*
X2989876Y1461654D01*
X2990031Y1463529D01*
X2989876Y1465404D01*
X2989411Y1467071D01*
X2988791Y1468321D01*
X2987861Y1469362D01*
X2986621Y1469779D01*
G01X2951281Y1516379D02*
Y1528879D01*
X2945546Y1519921D01*
X2953296D01*
G01X2961821Y1528879D02*
X2960581Y1528462D01*
X2959651Y1527421D01*
X2959031Y1526171D01*
X2958566Y1524504D01*
X2958411Y1522629D01*
X2958566Y1520754D01*
X2959031Y1519087D01*
X2959651Y1517837D01*
X2960581Y1516796D01*
X2961821Y1516379D01*
X2963061Y1516796D01*
X2963991Y1517837D01*
X2964611Y1519087D01*
X2965076Y1520754D01*
X2965231Y1522629D01*
X2965076Y1524504D01*
X2964611Y1526171D01*
X2963991Y1527421D01*
X2963061Y1528462D01*
X2961821Y1528879D01*
G01X2974221Y1515962D02*
X2973911Y1516171D01*
Y1516587D01*
X2974221Y1516796D01*
X2974531Y1516587D01*
Y1516171D01*
X2974221Y1515962D01*
G01X2986621Y1528879D02*
X2985381Y1528462D01*
X2984451Y1527421D01*
X2983831Y1526171D01*
X2983366Y1524504D01*
X2983211Y1522629D01*
X2983366Y1520754D01*
X2983831Y1519087D01*
X2984451Y1517837D01*
X2985381Y1516796D01*
X2986621Y1516379D01*
X2987861Y1516796D01*
X2988791Y1517837D01*
X2989411Y1519087D01*
X2989876Y1520754D01*
X2990031Y1522629D01*
X2989876Y1524504D01*
X2989411Y1526171D01*
X2988791Y1527421D01*
X2987861Y1528462D01*
X2986621Y1528879D01*
G01X2946476Y1585896D02*
X2947406Y1587145D01*
X2948491Y1587771D01*
X2949731Y1587979D01*
X2951281Y1587562D01*
X2952366Y1586521D01*
X2952676Y1585271D01*
X2952521Y1584020D01*
X2951901Y1582979D01*
X2948801Y1580896D01*
X2947406Y1579437D01*
X2946476Y1577354D01*
X2946166Y1575479D01*
X2952676D01*
G01X2958876Y1585896D02*
X2959806Y1587145D01*
X2960891Y1587771D01*
X2962131Y1587979D01*
X2963681Y1587562D01*
X2964766Y1586521D01*
X2965076Y1585271D01*
X2964921Y1584020D01*
X2964301Y1582979D01*
X2961201Y1580896D01*
X2959806Y1579437D01*
X2958876Y1577354D01*
X2958566Y1575479D01*
X2965076D01*
G01X2974221Y1575062D02*
X2973911Y1575271D01*
Y1575687D01*
X2974221Y1575896D01*
X2974531Y1575687D01*
Y1575271D01*
X2974221Y1575062D01*
G01X2986621Y1587979D02*
X2985381Y1587562D01*
X2984451Y1586521D01*
X2983831Y1585271D01*
X2983366Y1583604D01*
X2983211Y1581729D01*
X2983366Y1579854D01*
X2983831Y1578187D01*
X2984451Y1576937D01*
X2985381Y1575896D01*
X2986621Y1575479D01*
X2987861Y1575896D01*
X2988791Y1576937D01*
X2989411Y1578187D01*
X2989876Y1579854D01*
X2990031Y1581729D01*
X2989876Y1583604D01*
X2989411Y1585271D01*
X2988791Y1586521D01*
X2987861Y1587562D01*
X2986621Y1587979D01*
G01X2949421Y1752779D02*
Y1765279D01*
X2947561Y1762779D01*
G01Y1752779D02*
X2951281D01*
G01X2961821Y1765279D02*
X2960581Y1764862D01*
X2959651Y1763821D01*
X2959031Y1762571D01*
X2958566Y1760904D01*
X2958411Y1759029D01*
X2958566Y1757154D01*
X2959031Y1755487D01*
X2959651Y1754237D01*
X2960581Y1753196D01*
X2961821Y1752779D01*
X2963061Y1753196D01*
X2963991Y1754237D01*
X2964611Y1755487D01*
X2965076Y1757154D01*
X2965231Y1759029D01*
X2965076Y1760904D01*
X2964611Y1762571D01*
X2963991Y1763821D01*
X2963061Y1764862D01*
X2961821Y1765279D01*
G01X2974221Y1752362D02*
X2973911Y1752571D01*
Y1752987D01*
X2974221Y1753196D01*
X2974531Y1752987D01*
Y1752571D01*
X2974221Y1752362D01*
G01X2986621Y1765279D02*
X2985381Y1764862D01*
X2984451Y1763821D01*
X2983831Y1762571D01*
X2983366Y1760904D01*
X2983211Y1759029D01*
X2983366Y1757154D01*
X2983831Y1755487D01*
X2984451Y1754237D01*
X2985381Y1753196D01*
X2986621Y1752779D01*
X2987861Y1753196D01*
X2988791Y1754237D01*
X2989411Y1755487D01*
X2989876Y1757154D01*
X2990031Y1759029D01*
X2989876Y1760904D01*
X2989411Y1762571D01*
X2988791Y1763821D01*
X2987861Y1764862D01*
X2986621Y1765279D01*
G01X2949421Y1811879D02*
Y1824379D01*
X2947561Y1821879D01*
G01Y1811879D02*
X2951281D01*
G01X2961821Y1824379D02*
X2960581Y1823962D01*
X2959651Y1822921D01*
X2959031Y1821671D01*
X2958566Y1820004D01*
X2958411Y1818129D01*
X2958566Y1816254D01*
X2959031Y1814587D01*
X2959651Y1813337D01*
X2960581Y1812296D01*
X2961821Y1811879D01*
X2963061Y1812296D01*
X2963991Y1813337D01*
X2964611Y1814587D01*
X2965076Y1816254D01*
X2965231Y1818129D01*
X2965076Y1820004D01*
X2964611Y1821671D01*
X2963991Y1822921D01*
X2963061Y1823962D01*
X2961821Y1824379D01*
G01X2974221Y1811462D02*
X2973911Y1811671D01*
Y1812087D01*
X2974221Y1812296D01*
X2974531Y1812087D01*
Y1811671D01*
X2974221Y1811462D01*
G01X2986621Y1824379D02*
X2985381Y1823962D01*
X2984451Y1822921D01*
X2983831Y1821671D01*
X2983366Y1820004D01*
X2983211Y1818129D01*
X2983366Y1816254D01*
X2983831Y1814587D01*
X2984451Y1813337D01*
X2985381Y1812296D01*
X2986621Y1811879D01*
X2987861Y1812296D01*
X2988791Y1813337D01*
X2989411Y1814587D01*
X2989876Y1816254D01*
X2990031Y1818129D01*
X2989876Y1820004D01*
X2989411Y1821671D01*
X2988791Y1822921D01*
X2987861Y1823962D01*
X2986621Y1824379D01*
G01X2946786Y1872437D02*
X2947871Y1871396D01*
X2949111Y1870979D01*
X2950351Y1871396D01*
X2951436Y1872645D01*
X2952211Y1874521D01*
X2952521Y1876396D01*
Y1878687D01*
X2952211Y1880562D01*
X2951436Y1882229D01*
X2950506Y1883062D01*
X2949421Y1883479D01*
X2948181Y1883062D01*
X2947251Y1882229D01*
X2946631Y1880979D01*
X2946321Y1879312D01*
X2946631Y1877854D01*
X2947406Y1876396D01*
X2948336Y1875562D01*
X2949421Y1875354D01*
X2950661Y1875770D01*
X2951591Y1876812D01*
X2952521Y1878687D01*
G01X2961821Y1870562D02*
X2961511Y1870771D01*
Y1871187D01*
X2961821Y1871396D01*
X2962131Y1871187D01*
Y1870771D01*
X2961821Y1870562D01*
G01X2974221Y1870979D02*
X2975306Y1871187D01*
X2976546Y1871812D01*
X2977321Y1872854D01*
X2977631Y1874312D01*
X2977321Y1875770D01*
X2976391Y1877021D01*
X2974996Y1877646D01*
X2973446D01*
X2972516Y1878062D01*
X2971741Y1879104D01*
X2971431Y1880562D01*
X2971896Y1882021D01*
X2972981Y1883062D01*
X2974221Y1883479D01*
X2975461Y1883062D01*
X2976546Y1882021D01*
X2977011Y1880562D01*
X2976701Y1879104D01*
X2975926Y1878062D01*
X2974996Y1877646D01*
X2973446D01*
X2972051Y1877021D01*
X2971121Y1875770D01*
X2970811Y1874312D01*
X2971121Y1872854D01*
X2971896Y1871812D01*
X2973136Y1871187D01*
X2974221Y1870979D01*
G01X2988481D02*
Y1883479D01*
X2982746Y1874521D01*
X2990496D01*
G01X2955621Y1930079D02*
X2956706Y1930287D01*
X2957946Y1930912D01*
X2958721Y1931954D01*
X2959031Y1933412D01*
X2958721Y1934870D01*
X2957791Y1936121D01*
X2956396Y1936746D01*
X2954846D01*
X2953916Y1937162D01*
X2953141Y1938204D01*
X2952831Y1939662D01*
X2953296Y1941121D01*
X2954381Y1942162D01*
X2955621Y1942579D01*
X2956861Y1942162D01*
X2957946Y1941121D01*
X2958411Y1939662D01*
X2958101Y1938204D01*
X2957326Y1937162D01*
X2956396Y1936746D01*
X2954846D01*
X2953451Y1936121D01*
X2952521Y1934870D01*
X2952211Y1933412D01*
X2952521Y1931954D01*
X2953296Y1930912D01*
X2954536Y1930287D01*
X2955621Y1930079D01*
G01X2968021Y1929662D02*
X2967711Y1929871D01*
Y1930287D01*
X2968021Y1930496D01*
X2968331Y1930287D01*
Y1929871D01*
X2968021Y1929662D01*
G01X2980421Y1942579D02*
X2979181Y1942162D01*
X2978251Y1941121D01*
X2977631Y1939871D01*
X2977166Y1938204D01*
X2977011Y1936329D01*
X2977166Y1934454D01*
X2977631Y1932787D01*
X2978251Y1931537D01*
X2979181Y1930496D01*
X2980421Y1930079D01*
X2981661Y1930496D01*
X2982591Y1931537D01*
X2983211Y1932787D01*
X2983676Y1934454D01*
X2983831Y1936329D01*
X2983676Y1938204D01*
X2983211Y1939871D01*
X2982591Y1941121D01*
X2981661Y1942162D01*
X2980421Y1942579D01*
G01X2955621Y1989179D02*
X2956706Y1989387D01*
X2957946Y1990012D01*
X2958721Y1991054D01*
X2959031Y1992512D01*
X2958721Y1993970D01*
X2957791Y1995221D01*
X2956396Y1995846D01*
X2954846D01*
X2953916Y1996262D01*
X2953141Y1997304D01*
X2952831Y1998762D01*
X2953296Y2000221D01*
X2954381Y2001262D01*
X2955621Y2001679D01*
X2956861Y2001262D01*
X2957946Y2000221D01*
X2958411Y1998762D01*
X2958101Y1997304D01*
X2957326Y1996262D01*
X2956396Y1995846D01*
X2954846D01*
X2953451Y1995221D01*
X2952521Y1993970D01*
X2952211Y1992512D01*
X2952521Y1991054D01*
X2953296Y1990012D01*
X2954536Y1989387D01*
X2955621Y1989179D01*
G01X2968021Y1988762D02*
X2967711Y1988971D01*
Y1989387D01*
X2968021Y1989596D01*
X2968331Y1989387D01*
Y1988971D01*
X2968021Y1988762D01*
G01X2980421Y2001679D02*
X2979181Y2001262D01*
X2978251Y2000221D01*
X2977631Y1998971D01*
X2977166Y1997304D01*
X2977011Y1995429D01*
X2977166Y1993554D01*
X2977631Y1991887D01*
X2978251Y1990637D01*
X2979181Y1989596D01*
X2980421Y1989179D01*
X2981661Y1989596D01*
X2982591Y1990637D01*
X2983211Y1991887D01*
X2983676Y1993554D01*
X2983831Y1995429D01*
X2983676Y1997304D01*
X2983211Y1998971D01*
X2982591Y2000221D01*
X2981661Y2001262D01*
X2980421Y2001679D01*
G01X3011080Y3487592D02*
X3011700Y3488217D01*
X3012165Y3489258D01*
X3012475Y3490717D01*
X3012165Y3491967D01*
X3011545Y3492800D01*
X3010460Y3493425D01*
X3006275D01*
Y3480925D01*
X3011390D01*
X3012475Y3481758D01*
X3013095Y3483008D01*
X3013405Y3484467D01*
X3013095Y3485925D01*
X3012165Y3487175D01*
X3011080Y3487592D01*
X3006275D01*
G01X3018365Y3480925D02*
X3022240Y3493425D01*
X3026115Y3480925D01*
G01X3024720Y3485300D02*
X3019760D01*
G01X3038050Y3492383D02*
X3037120Y3493008D01*
X3036035Y3493425D01*
X3034795D01*
X3033400Y3492800D01*
X3032315Y3491758D01*
X3031540Y3490508D01*
X3030920Y3488425D01*
X3030765Y3486550D01*
X3031075Y3484675D01*
X3031540Y3483425D01*
X3032470Y3482175D01*
X3033555Y3481342D01*
X3034640Y3480925D01*
X3035725D01*
X3036810Y3481342D01*
X3037740Y3481966D01*
X3038515Y3482800D01*
G01X3043630Y3480925D02*
Y3493425D01*
G01X3049520D02*
X3043630Y3485716D01*
G01X3050450Y3480925D02*
X3046265Y3489258D01*
G01X3056030Y3480925D02*
Y3493425D01*
X3059130D01*
X3060370Y3492800D01*
X3061300Y3491967D01*
X3062075Y3490717D01*
X3062695Y3489258D01*
X3062850Y3487175D01*
X3062695Y3485092D01*
X3062075Y3483633D01*
X3061300Y3482383D01*
X3060370Y3481550D01*
X3059130Y3480925D01*
X3056030D01*
G01X3068740D02*
Y3493425D01*
X3072615D01*
X3073855Y3492800D01*
X3074630Y3491967D01*
X3074940Y3490300D01*
X3074630Y3488633D01*
X3073700Y3487592D01*
X3072615Y3486967D01*
X3068740D01*
G01X3072615D02*
X3074940Y3480925D01*
G01X3082380Y3493425D02*
X3086100D01*
G01X3084240D02*
Y3480925D01*
G01X3082380D02*
X3086100D01*
G01X3093540Y3493425D02*
Y3480925D01*
X3099740D01*
G01X3105940Y3493425D02*
Y3480925D01*
X3112140D01*
G01X3121440Y3480508D02*
X3121130Y3480717D01*
Y3481133D01*
X3121440Y3481342D01*
X3121750Y3481133D01*
Y3480717D01*
X3121440Y3480508D01*
G01Y3486133D02*
X3121130Y3486342D01*
Y3486758D01*
X3121440Y3486967D01*
X3121750Y3486758D01*
Y3486342D01*
X3121440Y3486133D01*
G01X3147480Y3487592D02*
X3148100Y3488217D01*
X3148565Y3489258D01*
X3148875Y3490717D01*
X3148565Y3491967D01*
X3147945Y3492800D01*
X3146860Y3493425D01*
X3142675D01*
Y3480925D01*
X3147790D01*
X3148875Y3481758D01*
X3149495Y3483008D01*
X3149805Y3484467D01*
X3149495Y3485925D01*
X3148565Y3487175D01*
X3147480Y3487592D01*
X3142675D01*
G01X3158640Y3480925D02*
X3157400Y3481133D01*
X3156315Y3481966D01*
X3155385Y3483217D01*
X3154765Y3484675D01*
X3154455Y3486342D01*
Y3488008D01*
X3154765Y3489675D01*
X3155385Y3491133D01*
X3156315Y3492383D01*
X3157400Y3493217D01*
X3158640Y3493425D01*
X3159880Y3493217D01*
X3160965Y3492383D01*
X3161895Y3491133D01*
X3162515Y3489675D01*
X3162825Y3488008D01*
Y3486342D01*
X3162515Y3484675D01*
X3161895Y3483217D01*
X3160965Y3481966D01*
X3159880Y3481133D01*
X3158640Y3480925D01*
G01X3171040Y3493425D02*
Y3480925D01*
G01X3167475Y3493425D02*
X3174605D01*
G01X3183440D02*
Y3480925D01*
G01X3179875Y3493425D02*
X3187005D01*
G01X3195840Y3480925D02*
X3194600Y3481133D01*
X3193515Y3481966D01*
X3192585Y3483217D01*
X3191965Y3484675D01*
X3191655Y3486342D01*
Y3488008D01*
X3191965Y3489675D01*
X3192585Y3491133D01*
X3193515Y3492383D01*
X3194600Y3493217D01*
X3195840Y3493425D01*
X3197080Y3493217D01*
X3198165Y3492383D01*
X3199095Y3491133D01*
X3199715Y3489675D01*
X3200025Y3488008D01*
Y3486342D01*
X3199715Y3484675D01*
X3199095Y3483217D01*
X3198165Y3481966D01*
X3197080Y3481133D01*
X3195840Y3480925D01*
G01X3204210D02*
Y3493425D01*
X3208240Y3483008D01*
X3212270Y3493425D01*
Y3480925D01*
G01X3233040Y3493425D02*
Y3480925D01*
G01X3230870Y3489258D02*
X3235210D01*
G01X3245440Y3480925D02*
X3244510Y3481133D01*
X3243580Y3481966D01*
X3242960Y3483425D01*
X3242650Y3485092D01*
X3242960Y3486758D01*
X3243580Y3488217D01*
X3244510Y3489050D01*
X3245440Y3489258D01*
X3246370Y3489050D01*
X3247300Y3488217D01*
X3247920Y3486758D01*
X3248075Y3485092D01*
X3247920Y3483425D01*
X3247300Y3481966D01*
X3246370Y3481133D01*
X3245440Y3480925D01*
G01X3271170Y3487175D02*
X3274270D01*
Y3483425D01*
X3273340Y3482175D01*
X3272255Y3481342D01*
X3270705Y3480925D01*
X3269155Y3481342D01*
X3268070Y3482175D01*
X3267140Y3483425D01*
X3266520Y3484883D01*
X3266210Y3486550D01*
Y3488008D01*
X3266520Y3489258D01*
X3267140Y3490717D01*
X3268070Y3491967D01*
X3269000Y3492800D01*
X3270240Y3493425D01*
X3271325D01*
X3272565Y3493008D01*
X3273495Y3492175D01*
G01X3279075Y3480925D02*
Y3493425D01*
X3286205Y3480925D01*
Y3493425D01*
G01X3291630Y3480925D02*
Y3493425D01*
X3294730D01*
X3295970Y3492800D01*
X3296900Y3491967D01*
X3297675Y3490717D01*
X3298295Y3489258D01*
X3298450Y3487175D01*
X3298295Y3485092D01*
X3297675Y3483633D01*
X3296900Y3482383D01*
X3295970Y3481550D01*
X3294730Y3480925D01*
X3291630D01*
G01X3307440D02*
Y3493425D01*
X3305580Y3490925D01*
G01Y3480925D02*
X3309300D01*
G01X3015416Y2981016D02*
X3016036Y2981641D01*
X3016501Y2982682D01*
X3016811Y2984141D01*
X3016501Y2985391D01*
X3015881Y2986224D01*
X3014796Y2986849D01*
X3010611D01*
Y2974349D01*
X3015726D01*
X3016811Y2975182D01*
X3017431Y2976432D01*
X3017741Y2977891D01*
X3017431Y2979349D01*
X3016501Y2980599D01*
X3015416Y2981016D01*
X3010611D01*
G01X3022701Y2974349D02*
X3026576Y2986849D01*
X3030451Y2974349D01*
G01X3029056Y2978724D02*
X3024096D01*
G01X3042386Y2985807D02*
X3041456Y2986432D01*
X3040371Y2986849D01*
X3039131D01*
X3037736Y2986224D01*
X3036651Y2985182D01*
X3035876Y2983932D01*
X3035256Y2981849D01*
X3035101Y2979974D01*
X3035411Y2978099D01*
X3035876Y2976849D01*
X3036806Y2975599D01*
X3037891Y2974766D01*
X3038976Y2974349D01*
X3040061D01*
X3041146Y2974766D01*
X3042076Y2975390D01*
X3042851Y2976224D01*
G01X3047966Y2974349D02*
Y2986849D01*
G01X3053856D02*
X3047966Y2979140D01*
G01X3054786Y2974349D02*
X3050601Y2982682D01*
G01X3060366Y2974349D02*
Y2986849D01*
X3063466D01*
X3064706Y2986224D01*
X3065636Y2985391D01*
X3066411Y2984141D01*
X3067031Y2982682D01*
X3067186Y2980599D01*
X3067031Y2978516D01*
X3066411Y2977057D01*
X3065636Y2975807D01*
X3064706Y2974974D01*
X3063466Y2974349D01*
X3060366D01*
G01X3073076D02*
Y2986849D01*
X3076951D01*
X3078191Y2986224D01*
X3078966Y2985391D01*
X3079276Y2983724D01*
X3078966Y2982057D01*
X3078036Y2981016D01*
X3076951Y2980391D01*
X3073076D01*
G01X3076951D02*
X3079276Y2974349D01*
G01X3086716Y2986849D02*
X3090436D01*
G01X3088576D02*
Y2974349D01*
G01X3086716D02*
X3090436D01*
G01X3097876Y2986849D02*
Y2974349D01*
X3104076D01*
G01X3110276Y2986849D02*
Y2974349D01*
X3116476D01*
G01X3125776Y2973932D02*
X3125466Y2974141D01*
Y2974557D01*
X3125776Y2974766D01*
X3126086Y2974557D01*
Y2974141D01*
X3125776Y2973932D01*
G01Y2979557D02*
X3125466Y2979766D01*
Y2980182D01*
X3125776Y2980391D01*
X3126086Y2980182D01*
Y2979766D01*
X3125776Y2979557D01*
G01X3151816Y2981016D02*
X3152436Y2981641D01*
X3152901Y2982682D01*
X3153211Y2984141D01*
X3152901Y2985391D01*
X3152281Y2986224D01*
X3151196Y2986849D01*
X3147011D01*
Y2974349D01*
X3152126D01*
X3153211Y2975182D01*
X3153831Y2976432D01*
X3154141Y2977891D01*
X3153831Y2979349D01*
X3152901Y2980599D01*
X3151816Y2981016D01*
X3147011D01*
G01X3162976Y2974349D02*
X3161736Y2974557D01*
X3160651Y2975390D01*
X3159721Y2976641D01*
X3159101Y2978099D01*
X3158791Y2979766D01*
Y2981432D01*
X3159101Y2983099D01*
X3159721Y2984557D01*
X3160651Y2985807D01*
X3161736Y2986641D01*
X3162976Y2986849D01*
X3164216Y2986641D01*
X3165301Y2985807D01*
X3166231Y2984557D01*
X3166851Y2983099D01*
X3167161Y2981432D01*
Y2979766D01*
X3166851Y2978099D01*
X3166231Y2976641D01*
X3165301Y2975390D01*
X3164216Y2974557D01*
X3162976Y2974349D01*
G01X3175376Y2986849D02*
Y2974349D01*
G01X3171811Y2986849D02*
X3178941D01*
G01X3187776D02*
Y2974349D01*
G01X3184211Y2986849D02*
X3191341D01*
G01X3200176Y2974349D02*
X3198936Y2974557D01*
X3197851Y2975390D01*
X3196921Y2976641D01*
X3196301Y2978099D01*
X3195991Y2979766D01*
Y2981432D01*
X3196301Y2983099D01*
X3196921Y2984557D01*
X3197851Y2985807D01*
X3198936Y2986641D01*
X3200176Y2986849D01*
X3201416Y2986641D01*
X3202501Y2985807D01*
X3203431Y2984557D01*
X3204051Y2983099D01*
X3204361Y2981432D01*
Y2979766D01*
X3204051Y2978099D01*
X3203431Y2976641D01*
X3202501Y2975390D01*
X3201416Y2974557D01*
X3200176Y2974349D01*
G01X3208546D02*
Y2986849D01*
X3212576Y2976432D01*
X3216606Y2986849D01*
Y2974349D01*
G01X3237376Y2986849D02*
Y2974349D01*
G01X3235206Y2982682D02*
X3239546D01*
G01X3249776Y2974349D02*
X3248846Y2974557D01*
X3247916Y2975390D01*
X3247296Y2976849D01*
X3246986Y2978516D01*
X3247296Y2980182D01*
X3247916Y2981641D01*
X3248846Y2982474D01*
X3249776Y2982682D01*
X3250706Y2982474D01*
X3251636Y2981641D01*
X3252256Y2980182D01*
X3252411Y2978516D01*
X3252256Y2976849D01*
X3251636Y2975390D01*
X3250706Y2974557D01*
X3249776Y2974349D01*
G01X3275506Y2980599D02*
X3278606D01*
Y2976849D01*
X3277676Y2975599D01*
X3276591Y2974766D01*
X3275041Y2974349D01*
X3273491Y2974766D01*
X3272406Y2975599D01*
X3271476Y2976849D01*
X3270856Y2978307D01*
X3270546Y2979974D01*
Y2981432D01*
X3270856Y2982682D01*
X3271476Y2984141D01*
X3272406Y2985391D01*
X3273336Y2986224D01*
X3274576Y2986849D01*
X3275661D01*
X3276901Y2986432D01*
X3277831Y2985599D01*
G01X3283411Y2974349D02*
Y2986849D01*
X3290541Y2974349D01*
Y2986849D01*
G01X3295966Y2974349D02*
Y2986849D01*
X3299066D01*
X3300306Y2986224D01*
X3301236Y2985391D01*
X3302011Y2984141D01*
X3302631Y2982682D01*
X3302786Y2980599D01*
X3302631Y2978516D01*
X3302011Y2977057D01*
X3301236Y2975807D01*
X3300306Y2974974D01*
X3299066Y2974349D01*
X3295966D01*
G01X3308366Y2976849D02*
X3309296Y2975390D01*
X3310536Y2974557D01*
X3311931Y2974349D01*
X3313171Y2974557D01*
X3314411Y2975599D01*
X3315186Y2976849D01*
X3315341Y2978099D01*
X3315031Y2979557D01*
X3313946Y2980599D01*
X3312861Y2981016D01*
X3311466D01*
G01X3312861D02*
X3313791Y2981641D01*
X3314566Y2982682D01*
X3314876Y2983932D01*
X3314566Y2985182D01*
X3313791Y2986224D01*
X3312396Y2986849D01*
X3311001Y2986641D01*
X3309606Y2985807D01*
G01X3015426Y3231586D02*
X3016046Y3232211D01*
X3016511Y3233252D01*
X3016821Y3234711D01*
X3016511Y3235961D01*
X3015891Y3236794D01*
X3014806Y3237419D01*
X3010621D01*
Y3224919D01*
X3015736D01*
X3016821Y3225752D01*
X3017441Y3227002D01*
X3017751Y3228461D01*
X3017441Y3229919D01*
X3016511Y3231169D01*
X3015426Y3231586D01*
X3010621D01*
G01X3022711Y3224919D02*
X3026586Y3237419D01*
X3030461Y3224919D01*
G01X3029066Y3229294D02*
X3024106D01*
G01X3042396Y3236377D02*
X3041466Y3237002D01*
X3040381Y3237419D01*
X3039141D01*
X3037746Y3236794D01*
X3036661Y3235752D01*
X3035886Y3234502D01*
X3035266Y3232419D01*
X3035111Y3230544D01*
X3035421Y3228669D01*
X3035886Y3227419D01*
X3036816Y3226169D01*
X3037901Y3225336D01*
X3038986Y3224919D01*
X3040071D01*
X3041156Y3225336D01*
X3042086Y3225960D01*
X3042861Y3226794D01*
G01X3047976Y3224919D02*
Y3237419D01*
G01X3053866D02*
X3047976Y3229710D01*
G01X3054796Y3224919D02*
X3050611Y3233252D01*
G01X3060376Y3224919D02*
Y3237419D01*
X3063476D01*
X3064716Y3236794D01*
X3065646Y3235961D01*
X3066421Y3234711D01*
X3067041Y3233252D01*
X3067196Y3231169D01*
X3067041Y3229086D01*
X3066421Y3227627D01*
X3065646Y3226377D01*
X3064716Y3225544D01*
X3063476Y3224919D01*
X3060376D01*
G01X3073086D02*
Y3237419D01*
X3076961D01*
X3078201Y3236794D01*
X3078976Y3235961D01*
X3079286Y3234294D01*
X3078976Y3232627D01*
X3078046Y3231586D01*
X3076961Y3230961D01*
X3073086D01*
G01X3076961D02*
X3079286Y3224919D01*
G01X3086726Y3237419D02*
X3090446D01*
G01X3088586D02*
Y3224919D01*
G01X3086726D02*
X3090446D01*
G01X3097886Y3237419D02*
Y3224919D01*
X3104086D01*
G01X3110286Y3237419D02*
Y3224919D01*
X3116486D01*
G01X3125786Y3224502D02*
X3125476Y3224711D01*
Y3225127D01*
X3125786Y3225336D01*
X3126096Y3225127D01*
Y3224711D01*
X3125786Y3224502D01*
G01Y3230127D02*
X3125476Y3230336D01*
Y3230752D01*
X3125786Y3230961D01*
X3126096Y3230752D01*
Y3230336D01*
X3125786Y3230127D01*
G01X3151826Y3231586D02*
X3152446Y3232211D01*
X3152911Y3233252D01*
X3153221Y3234711D01*
X3152911Y3235961D01*
X3152291Y3236794D01*
X3151206Y3237419D01*
X3147021D01*
Y3224919D01*
X3152136D01*
X3153221Y3225752D01*
X3153841Y3227002D01*
X3154151Y3228461D01*
X3153841Y3229919D01*
X3152911Y3231169D01*
X3151826Y3231586D01*
X3147021D01*
G01X3162986Y3224919D02*
X3161746Y3225127D01*
X3160661Y3225960D01*
X3159731Y3227211D01*
X3159111Y3228669D01*
X3158801Y3230336D01*
Y3232002D01*
X3159111Y3233669D01*
X3159731Y3235127D01*
X3160661Y3236377D01*
X3161746Y3237211D01*
X3162986Y3237419D01*
X3164226Y3237211D01*
X3165311Y3236377D01*
X3166241Y3235127D01*
X3166861Y3233669D01*
X3167171Y3232002D01*
Y3230336D01*
X3166861Y3228669D01*
X3166241Y3227211D01*
X3165311Y3225960D01*
X3164226Y3225127D01*
X3162986Y3224919D01*
G01X3175386Y3237419D02*
Y3224919D01*
G01X3171821Y3237419D02*
X3178951D01*
G01X3187786D02*
Y3224919D01*
G01X3184221Y3237419D02*
X3191351D01*
G01X3200186Y3224919D02*
X3198946Y3225127D01*
X3197861Y3225960D01*
X3196931Y3227211D01*
X3196311Y3228669D01*
X3196001Y3230336D01*
Y3232002D01*
X3196311Y3233669D01*
X3196931Y3235127D01*
X3197861Y3236377D01*
X3198946Y3237211D01*
X3200186Y3237419D01*
X3201426Y3237211D01*
X3202511Y3236377D01*
X3203441Y3235127D01*
X3204061Y3233669D01*
X3204371Y3232002D01*
Y3230336D01*
X3204061Y3228669D01*
X3203441Y3227211D01*
X3202511Y3225960D01*
X3201426Y3225127D01*
X3200186Y3224919D01*
G01X3208556D02*
Y3237419D01*
X3212586Y3227002D01*
X3216616Y3237419D01*
Y3224919D01*
G01X3237386Y3237419D02*
Y3224919D01*
G01X3235216Y3233252D02*
X3239556D01*
G01X3249786Y3224919D02*
X3248856Y3225127D01*
X3247926Y3225960D01*
X3247306Y3227419D01*
X3246996Y3229086D01*
X3247306Y3230752D01*
X3247926Y3232211D01*
X3248856Y3233044D01*
X3249786Y3233252D01*
X3250716Y3233044D01*
X3251646Y3232211D01*
X3252266Y3230752D01*
X3252421Y3229086D01*
X3252266Y3227419D01*
X3251646Y3225960D01*
X3250716Y3225127D01*
X3249786Y3224919D01*
G01X3275516Y3231169D02*
X3278616D01*
Y3227419D01*
X3277686Y3226169D01*
X3276601Y3225336D01*
X3275051Y3224919D01*
X3273501Y3225336D01*
X3272416Y3226169D01*
X3271486Y3227419D01*
X3270866Y3228877D01*
X3270556Y3230544D01*
Y3232002D01*
X3270866Y3233252D01*
X3271486Y3234711D01*
X3272416Y3235961D01*
X3273346Y3236794D01*
X3274586Y3237419D01*
X3275671D01*
X3276911Y3237002D01*
X3277841Y3236169D01*
G01X3283421Y3224919D02*
Y3237419D01*
X3290551Y3224919D01*
Y3237419D01*
G01X3295976Y3224919D02*
Y3237419D01*
X3299076D01*
X3300316Y3236794D01*
X3301246Y3235961D01*
X3302021Y3234711D01*
X3302641Y3233252D01*
X3302796Y3231169D01*
X3302641Y3229086D01*
X3302021Y3227627D01*
X3301246Y3226377D01*
X3300316Y3225544D01*
X3299076Y3224919D01*
X3295976D01*
G01X3308841Y3235336D02*
X3309771Y3236585D01*
X3310856Y3237211D01*
X3312096Y3237419D01*
X3313646Y3237002D01*
X3314731Y3235961D01*
X3315041Y3234711D01*
X3314886Y3233460D01*
X3314266Y3232419D01*
X3311166Y3230336D01*
X3309771Y3228877D01*
X3308841Y3226794D01*
X3308531Y3224919D01*
X3315041D01*
G01X3016185Y3773054D02*
X3016805Y3773679D01*
X3017270Y3774720D01*
X3017580Y3776179D01*
X3017270Y3777429D01*
X3016650Y3778262D01*
X3015565Y3778887D01*
X3011380D01*
Y3766387D01*
X3016495D01*
X3017580Y3767220D01*
X3018200Y3768470D01*
X3018510Y3769929D01*
X3018200Y3771387D01*
X3017270Y3772637D01*
X3016185Y3773054D01*
X3011380D01*
G01X3023470Y3766387D02*
X3027345Y3778887D01*
X3031220Y3766387D01*
G01X3029825Y3770762D02*
X3024865D01*
G01X3043155Y3777845D02*
X3042225Y3778470D01*
X3041140Y3778887D01*
X3039900D01*
X3038505Y3778262D01*
X3037420Y3777220D01*
X3036645Y3775970D01*
X3036025Y3773887D01*
X3035870Y3772012D01*
X3036180Y3770137D01*
X3036645Y3768887D01*
X3037575Y3767637D01*
X3038660Y3766804D01*
X3039745Y3766387D01*
X3040830D01*
X3041915Y3766804D01*
X3042845Y3767428D01*
X3043620Y3768262D01*
G01X3048735Y3766387D02*
Y3778887D01*
G01X3054625D02*
X3048735Y3771178D01*
G01X3055555Y3766387D02*
X3051370Y3774720D01*
G01X3061135Y3766387D02*
Y3778887D01*
X3064235D01*
X3065475Y3778262D01*
X3066405Y3777429D01*
X3067180Y3776179D01*
X3067800Y3774720D01*
X3067955Y3772637D01*
X3067800Y3770554D01*
X3067180Y3769095D01*
X3066405Y3767845D01*
X3065475Y3767012D01*
X3064235Y3766387D01*
X3061135D01*
G01X3073845D02*
Y3778887D01*
X3077720D01*
X3078960Y3778262D01*
X3079735Y3777429D01*
X3080045Y3775762D01*
X3079735Y3774095D01*
X3078805Y3773054D01*
X3077720Y3772429D01*
X3073845D01*
G01X3077720D02*
X3080045Y3766387D01*
G01X3087485Y3778887D02*
X3091205D01*
G01X3089345D02*
Y3766387D01*
G01X3087485D02*
X3091205D01*
G01X3098645Y3778887D02*
Y3766387D01*
X3104845D01*
G01X3111045Y3778887D02*
Y3766387D01*
X3117245D01*
G01X3126545Y3765970D02*
X3126235Y3766179D01*
Y3766595D01*
X3126545Y3766804D01*
X3126855Y3766595D01*
Y3766179D01*
X3126545Y3765970D01*
G01Y3771595D02*
X3126235Y3771804D01*
Y3772220D01*
X3126545Y3772429D01*
X3126855Y3772220D01*
Y3771804D01*
X3126545Y3771595D01*
G01X3152585Y3773054D02*
X3153205Y3773679D01*
X3153670Y3774720D01*
X3153980Y3776179D01*
X3153670Y3777429D01*
X3153050Y3778262D01*
X3151965Y3778887D01*
X3147780D01*
Y3766387D01*
X3152895D01*
X3153980Y3767220D01*
X3154600Y3768470D01*
X3154910Y3769929D01*
X3154600Y3771387D01*
X3153670Y3772637D01*
X3152585Y3773054D01*
X3147780D01*
G01X3163745Y3766387D02*
X3162505Y3766595D01*
X3161420Y3767428D01*
X3160490Y3768679D01*
X3159870Y3770137D01*
X3159560Y3771804D01*
Y3773470D01*
X3159870Y3775137D01*
X3160490Y3776595D01*
X3161420Y3777845D01*
X3162505Y3778679D01*
X3163745Y3778887D01*
X3164985Y3778679D01*
X3166070Y3777845D01*
X3167000Y3776595D01*
X3167620Y3775137D01*
X3167930Y3773470D01*
Y3771804D01*
X3167620Y3770137D01*
X3167000Y3768679D01*
X3166070Y3767428D01*
X3164985Y3766595D01*
X3163745Y3766387D01*
G01X3176145Y3778887D02*
Y3766387D01*
G01X3172580Y3778887D02*
X3179710D01*
G01X3188545D02*
Y3766387D01*
G01X3184980Y3778887D02*
X3192110D01*
G01X3200945Y3766387D02*
X3199705Y3766595D01*
X3198620Y3767428D01*
X3197690Y3768679D01*
X3197070Y3770137D01*
X3196760Y3771804D01*
Y3773470D01*
X3197070Y3775137D01*
X3197690Y3776595D01*
X3198620Y3777845D01*
X3199705Y3778679D01*
X3200945Y3778887D01*
X3202185Y3778679D01*
X3203270Y3777845D01*
X3204200Y3776595D01*
X3204820Y3775137D01*
X3205130Y3773470D01*
Y3771804D01*
X3204820Y3770137D01*
X3204200Y3768679D01*
X3203270Y3767428D01*
X3202185Y3766595D01*
X3200945Y3766387D01*
G01X3209315D02*
Y3778887D01*
X3213345Y3768470D01*
X3217375Y3778887D01*
Y3766387D01*
G01X3238145Y3778887D02*
Y3766387D01*
G01X3235975Y3774720D02*
X3240315D01*
G01X3250545Y3766387D02*
X3249615Y3766595D01*
X3248685Y3767428D01*
X3248065Y3768887D01*
X3247755Y3770554D01*
X3248065Y3772220D01*
X3248685Y3773679D01*
X3249615Y3774512D01*
X3250545Y3774720D01*
X3251475Y3774512D01*
X3252405Y3773679D01*
X3253025Y3772220D01*
X3253180Y3770554D01*
X3253025Y3768887D01*
X3252405Y3767428D01*
X3251475Y3766595D01*
X3250545Y3766387D01*
G01X3276275Y3772637D02*
X3279375D01*
Y3768887D01*
X3278445Y3767637D01*
X3277360Y3766804D01*
X3275810Y3766387D01*
X3274260Y3766804D01*
X3273175Y3767637D01*
X3272245Y3768887D01*
X3271625Y3770345D01*
X3271315Y3772012D01*
Y3773470D01*
X3271625Y3774720D01*
X3272245Y3776179D01*
X3273175Y3777429D01*
X3274105Y3778262D01*
X3275345Y3778887D01*
X3276430D01*
X3277670Y3778470D01*
X3278600Y3777637D01*
G01X3284180Y3766387D02*
Y3778887D01*
X3291310Y3766387D01*
Y3778887D01*
G01X3296735Y3766387D02*
Y3778887D01*
X3299835D01*
X3301075Y3778262D01*
X3302005Y3777429D01*
X3302780Y3776179D01*
X3303400Y3774720D01*
X3303555Y3772637D01*
X3303400Y3770554D01*
X3302780Y3769095D01*
X3302005Y3767845D01*
X3301075Y3767012D01*
X3299835Y3766387D01*
X3296735D01*
G01X3309135Y3768262D02*
X3310065Y3767220D01*
X3311150Y3766595D01*
X3312545Y3766387D01*
X3313940Y3766804D01*
X3315025Y3767637D01*
X3315800Y3769095D01*
X3315955Y3770762D01*
X3315645Y3772429D01*
X3314870Y3773470D01*
X3313785Y3774304D01*
X3312700Y3774512D01*
X3311615Y3774304D01*
X3310220Y3773470D01*
X3310685Y3778887D01*
X3314870D01*
G01X3034105Y2660432D02*
X3037980Y2672932D01*
X3041855Y2660432D01*
G01X3040460Y2664807D02*
X3035500D01*
G01X3047280Y2672932D02*
Y2660432D01*
X3053480D01*
G01X3059680Y2672932D02*
Y2660432D01*
X3065880D01*
G01X3084170Y2672932D02*
Y2663974D01*
X3084790Y2662098D01*
X3086030Y2660849D01*
X3087580Y2660432D01*
X3089130Y2660849D01*
X3090370Y2662098D01*
X3090990Y2663974D01*
Y2672932D01*
G01X3096415Y2660432D02*
Y2672932D01*
X3103545Y2660432D01*
Y2672932D01*
G01X3110520D02*
X3114240D01*
G01X3112380D02*
Y2660432D01*
G01X3110520D02*
X3114240D01*
G01X3124780Y2672932D02*
Y2660432D01*
G01X3121215Y2672932D02*
X3128345D01*
G01X3133925Y2662098D02*
X3135165Y2661057D01*
X3136560Y2660432D01*
X3137800D01*
X3139040Y2661057D01*
X3139970Y2662098D01*
X3140435Y2663557D01*
X3140125Y2665015D01*
X3139350Y2666265D01*
X3137955Y2667099D01*
X3136095Y2667515D01*
X3135010Y2668349D01*
X3134545Y2669807D01*
X3134855Y2671265D01*
X3135630Y2672307D01*
X3136715Y2672932D01*
X3137800D01*
X3138885Y2672515D01*
X3139815Y2671474D01*
G01X3158105Y2660432D02*
X3161980Y2672932D01*
X3165855Y2660432D01*
G01X3164460Y2664807D02*
X3159500D01*
G01X3171280Y2660432D02*
Y2672932D01*
X3175155D01*
X3176395Y2672307D01*
X3177170Y2671474D01*
X3177480Y2669807D01*
X3177170Y2668140D01*
X3176240Y2667099D01*
X3175155Y2666474D01*
X3171280D01*
G01X3175155D02*
X3177480Y2660432D01*
G01X3189880D02*
X3183680D01*
Y2672932D01*
X3189880D01*
G01X3187400Y2666890D02*
X3183680D01*
G01X3209720Y2672932D02*
X3213440D01*
G01X3211580D02*
Y2660432D01*
G01X3209720D02*
X3213440D01*
G01X3220415D02*
Y2672932D01*
X3227545Y2660432D01*
Y2672932D01*
G01X3244750Y2660432D02*
Y2672932D01*
X3248780Y2662515D01*
X3252810Y2672932D01*
Y2660432D01*
G01X3259320Y2672932D02*
X3263040D01*
G01X3261180D02*
Y2660432D01*
G01X3259320D02*
X3263040D01*
G01X3270480Y2672932D02*
Y2660432D01*
X3276680D01*
G01X3282725Y2662098D02*
X3283965Y2661057D01*
X3285360Y2660432D01*
X3286600D01*
X3287840Y2661057D01*
X3288770Y2662098D01*
X3289235Y2663557D01*
X3288925Y2665015D01*
X3288150Y2666265D01*
X3286755Y2667099D01*
X3284895Y2667515D01*
X3283810Y2668349D01*
X3283345Y2669807D01*
X3283655Y2671265D01*
X3284430Y2672307D01*
X3285515Y2672932D01*
X3286600D01*
X3287685Y2672515D01*
X3288615Y2671474D01*
G01X3033020Y2692099D02*
X3033640Y2692724D01*
X3034105Y2693765D01*
X3034415Y2695224D01*
X3034105Y2696474D01*
X3033485Y2697307D01*
X3032400Y2697932D01*
X3028215D01*
Y2685432D01*
X3033330D01*
X3034415Y2686265D01*
X3035035Y2687515D01*
X3035345Y2688974D01*
X3035035Y2690432D01*
X3034105Y2691682D01*
X3033020Y2692099D01*
X3028215D01*
G01X3040305Y2685432D02*
X3044180Y2697932D01*
X3048055Y2685432D01*
G01X3046660Y2689807D02*
X3041700D01*
G01X3059990Y2696890D02*
X3059060Y2697515D01*
X3057975Y2697932D01*
X3056735D01*
X3055340Y2697307D01*
X3054255Y2696265D01*
X3053480Y2695015D01*
X3052860Y2692932D01*
X3052705Y2691057D01*
X3053015Y2689182D01*
X3053480Y2687932D01*
X3054410Y2686682D01*
X3055495Y2685849D01*
X3056580Y2685432D01*
X3057665D01*
X3058750Y2685849D01*
X3059680Y2686473D01*
X3060455Y2687307D01*
G01X3065570Y2685432D02*
Y2697932D01*
G01X3071460D02*
X3065570Y2690223D01*
G01X3072390Y2685432D02*
X3068205Y2693765D01*
G01X3077970Y2685432D02*
Y2697932D01*
X3081070D01*
X3082310Y2697307D01*
X3083240Y2696474D01*
X3084015Y2695224D01*
X3084635Y2693765D01*
X3084790Y2691682D01*
X3084635Y2689599D01*
X3084015Y2688140D01*
X3083240Y2686890D01*
X3082310Y2686057D01*
X3081070Y2685432D01*
X3077970D01*
G01X3090680D02*
Y2697932D01*
X3094555D01*
X3095795Y2697307D01*
X3096570Y2696474D01*
X3096880Y2694807D01*
X3096570Y2693140D01*
X3095640Y2692099D01*
X3094555Y2691474D01*
X3090680D01*
G01X3094555D02*
X3096880Y2685432D01*
G01X3104320Y2697932D02*
X3108040D01*
G01X3106180D02*
Y2685432D01*
G01X3104320D02*
X3108040D01*
G01X3115480Y2697932D02*
Y2685432D01*
X3121680D01*
G01X3127880Y2697932D02*
Y2685432D01*
X3134080D01*
G01X3143380Y2685015D02*
X3143070Y2685224D01*
Y2685640D01*
X3143380Y2685849D01*
X3143690Y2685640D01*
Y2685224D01*
X3143380Y2685015D01*
G01Y2690640D02*
X3143070Y2690849D01*
Y2691265D01*
X3143380Y2691474D01*
X3143690Y2691265D01*
Y2690849D01*
X3143380Y2690640D01*
G01X3168180Y2697932D02*
Y2685432D01*
G01X3164615Y2697932D02*
X3171745D01*
G01X3180580Y2685432D02*
X3179340Y2685640D01*
X3178255Y2686473D01*
X3177325Y2687724D01*
X3176705Y2689182D01*
X3176395Y2690849D01*
Y2692515D01*
X3176705Y2694182D01*
X3177325Y2695640D01*
X3178255Y2696890D01*
X3179340Y2697724D01*
X3180580Y2697932D01*
X3181820Y2697724D01*
X3182905Y2696890D01*
X3183835Y2695640D01*
X3184455Y2694182D01*
X3184765Y2692515D01*
Y2690849D01*
X3184455Y2689182D01*
X3183835Y2687724D01*
X3182905Y2686473D01*
X3181820Y2685640D01*
X3180580Y2685432D01*
G01X3189880D02*
Y2697932D01*
X3193600D01*
X3194840Y2697307D01*
X3195770Y2695849D01*
X3196080Y2694182D01*
X3195770Y2692515D01*
X3194995Y2691265D01*
X3193600Y2690640D01*
X3189880D01*
G01X3217780Y2697932D02*
Y2685432D01*
G01X3215610Y2693765D02*
X3219950D01*
G01X3230180Y2685432D02*
X3229250Y2685640D01*
X3228320Y2686473D01*
X3227700Y2687932D01*
X3227390Y2689599D01*
X3227700Y2691265D01*
X3228320Y2692724D01*
X3229250Y2693557D01*
X3230180Y2693765D01*
X3231110Y2693557D01*
X3232040Y2692724D01*
X3232660Y2691265D01*
X3232815Y2689599D01*
X3232660Y2687932D01*
X3232040Y2686473D01*
X3231110Y2685640D01*
X3230180Y2685432D01*
G01X3255910Y2691682D02*
X3259010D01*
Y2687932D01*
X3258080Y2686682D01*
X3256995Y2685849D01*
X3255445Y2685432D01*
X3253895Y2685849D01*
X3252810Y2686682D01*
X3251880Y2687932D01*
X3251260Y2689390D01*
X3250950Y2691057D01*
Y2692515D01*
X3251260Y2693765D01*
X3251880Y2695224D01*
X3252810Y2696474D01*
X3253740Y2697307D01*
X3254980Y2697932D01*
X3256065D01*
X3257305Y2697515D01*
X3258235Y2696682D01*
G01X3263815Y2685432D02*
Y2697932D01*
X3270945Y2685432D01*
Y2697932D01*
G01X3276370Y2685432D02*
Y2697932D01*
X3279470D01*
X3280710Y2697307D01*
X3281640Y2696474D01*
X3282415Y2695224D01*
X3283035Y2693765D01*
X3283190Y2691682D01*
X3283035Y2689599D01*
X3282415Y2688140D01*
X3281640Y2686890D01*
X3280710Y2686057D01*
X3279470Y2685432D01*
X3276370D01*
G01X3288770Y2687307D02*
X3289700Y2686265D01*
X3290785Y2685640D01*
X3292180Y2685432D01*
X3293575Y2685849D01*
X3294660Y2686682D01*
X3295435Y2688140D01*
X3295590Y2689807D01*
X3295280Y2691474D01*
X3294505Y2692515D01*
X3293420Y2693349D01*
X3292335Y2693557D01*
X3291250Y2693349D01*
X3289855Y2692515D01*
X3290320Y2697932D01*
X3294505D01*
G01X3035101Y2949349D02*
X3038976Y2961849D01*
X3042851Y2949349D01*
G01X3041456Y2953724D02*
X3036496D01*
G01X3048276Y2961849D02*
Y2949349D01*
X3054476D01*
G01X3060676Y2961849D02*
Y2949349D01*
X3066876D01*
G01X3085166Y2961849D02*
Y2952891D01*
X3085786Y2951015D01*
X3087026Y2949766D01*
X3088576Y2949349D01*
X3090126Y2949766D01*
X3091366Y2951015D01*
X3091986Y2952891D01*
Y2961849D01*
G01X3097411Y2949349D02*
Y2961849D01*
X3104541Y2949349D01*
Y2961849D01*
G01X3111516D02*
X3115236D01*
G01X3113376D02*
Y2949349D01*
G01X3111516D02*
X3115236D01*
G01X3125776Y2961849D02*
Y2949349D01*
G01X3122211Y2961849D02*
X3129341D01*
G01X3134921Y2951015D02*
X3136161Y2949974D01*
X3137556Y2949349D01*
X3138796D01*
X3140036Y2949974D01*
X3140966Y2951015D01*
X3141431Y2952474D01*
X3141121Y2953932D01*
X3140346Y2955182D01*
X3138951Y2956016D01*
X3137091Y2956432D01*
X3136006Y2957266D01*
X3135541Y2958724D01*
X3135851Y2960182D01*
X3136626Y2961224D01*
X3137711Y2961849D01*
X3138796D01*
X3139881Y2961432D01*
X3140811Y2960391D01*
G01X3159101Y2949349D02*
X3162976Y2961849D01*
X3166851Y2949349D01*
G01X3165456Y2953724D02*
X3160496D01*
G01X3172276Y2949349D02*
Y2961849D01*
X3176151D01*
X3177391Y2961224D01*
X3178166Y2960391D01*
X3178476Y2958724D01*
X3178166Y2957057D01*
X3177236Y2956016D01*
X3176151Y2955391D01*
X3172276D01*
G01X3176151D02*
X3178476Y2949349D01*
G01X3190876D02*
X3184676D01*
Y2961849D01*
X3190876D01*
G01X3188396Y2955807D02*
X3184676D01*
G01X3210716Y2961849D02*
X3214436D01*
G01X3212576D02*
Y2949349D01*
G01X3210716D02*
X3214436D01*
G01X3221411D02*
Y2961849D01*
X3228541Y2949349D01*
Y2961849D01*
G01X3245746Y2949349D02*
Y2961849D01*
X3249776Y2951432D01*
X3253806Y2961849D01*
Y2949349D01*
G01X3260316Y2961849D02*
X3264036D01*
G01X3262176D02*
Y2949349D01*
G01X3260316D02*
X3264036D01*
G01X3271476Y2961849D02*
Y2949349D01*
X3277676D01*
G01X3283721Y2951015D02*
X3284961Y2949974D01*
X3286356Y2949349D01*
X3287596D01*
X3288836Y2949974D01*
X3289766Y2951015D01*
X3290231Y2952474D01*
X3289921Y2953932D01*
X3289146Y2955182D01*
X3287751Y2956016D01*
X3285891Y2956432D01*
X3284806Y2957266D01*
X3284341Y2958724D01*
X3284651Y2960182D01*
X3285426Y2961224D01*
X3286511Y2961849D01*
X3287596D01*
X3288681Y2961432D01*
X3289611Y2960391D01*
G01X3035111Y3199919D02*
X3038986Y3212419D01*
X3042861Y3199919D01*
G01X3041466Y3204294D02*
X3036506D01*
G01X3048286Y3212419D02*
Y3199919D01*
X3054486D01*
G01X3060686Y3212419D02*
Y3199919D01*
X3066886D01*
G01X3085176Y3212419D02*
Y3203461D01*
X3085796Y3201585D01*
X3087036Y3200336D01*
X3088586Y3199919D01*
X3090136Y3200336D01*
X3091376Y3201585D01*
X3091996Y3203461D01*
Y3212419D01*
G01X3097421Y3199919D02*
Y3212419D01*
X3104551Y3199919D01*
Y3212419D01*
G01X3111526D02*
X3115246D01*
G01X3113386D02*
Y3199919D01*
G01X3111526D02*
X3115246D01*
G01X3125786Y3212419D02*
Y3199919D01*
G01X3122221Y3212419D02*
X3129351D01*
G01X3134931Y3201585D02*
X3136171Y3200544D01*
X3137566Y3199919D01*
X3138806D01*
X3140046Y3200544D01*
X3140976Y3201585D01*
X3141441Y3203044D01*
X3141131Y3204502D01*
X3140356Y3205752D01*
X3138961Y3206586D01*
X3137101Y3207002D01*
X3136016Y3207836D01*
X3135551Y3209294D01*
X3135861Y3210752D01*
X3136636Y3211794D01*
X3137721Y3212419D01*
X3138806D01*
X3139891Y3212002D01*
X3140821Y3210961D01*
G01X3159111Y3199919D02*
X3162986Y3212419D01*
X3166861Y3199919D01*
G01X3165466Y3204294D02*
X3160506D01*
G01X3172286Y3199919D02*
Y3212419D01*
X3176161D01*
X3177401Y3211794D01*
X3178176Y3210961D01*
X3178486Y3209294D01*
X3178176Y3207627D01*
X3177246Y3206586D01*
X3176161Y3205961D01*
X3172286D01*
G01X3176161D02*
X3178486Y3199919D01*
G01X3190886D02*
X3184686D01*
Y3212419D01*
X3190886D01*
G01X3188406Y3206377D02*
X3184686D01*
G01X3210726Y3212419D02*
X3214446D01*
G01X3212586D02*
Y3199919D01*
G01X3210726D02*
X3214446D01*
G01X3221421D02*
Y3212419D01*
X3228551Y3199919D01*
Y3212419D01*
G01X3245756Y3199919D02*
Y3212419D01*
X3249786Y3202002D01*
X3253816Y3212419D01*
Y3199919D01*
G01X3260326Y3212419D02*
X3264046D01*
G01X3262186D02*
Y3199919D01*
G01X3260326D02*
X3264046D01*
G01X3271486Y3212419D02*
Y3199919D01*
X3277686D01*
G01X3283731Y3201585D02*
X3284971Y3200544D01*
X3286366Y3199919D01*
X3287606D01*
X3288846Y3200544D01*
X3289776Y3201585D01*
X3290241Y3203044D01*
X3289931Y3204502D01*
X3289156Y3205752D01*
X3287761Y3206586D01*
X3285901Y3207002D01*
X3284816Y3207836D01*
X3284351Y3209294D01*
X3284661Y3210752D01*
X3285436Y3211794D01*
X3286521Y3212419D01*
X3287606D01*
X3288691Y3212002D01*
X3289621Y3210961D01*
G01X3030765Y3455925D02*
X3034640Y3468425D01*
X3038515Y3455925D01*
G01X3037120Y3460300D02*
X3032160D01*
G01X3043940Y3468425D02*
Y3455925D01*
X3050140D01*
G01X3056340Y3468425D02*
Y3455925D01*
X3062540D01*
G01X3080830Y3468425D02*
Y3459467D01*
X3081450Y3457591D01*
X3082690Y3456342D01*
X3084240Y3455925D01*
X3085790Y3456342D01*
X3087030Y3457591D01*
X3087650Y3459467D01*
Y3468425D01*
G01X3093075Y3455925D02*
Y3468425D01*
X3100205Y3455925D01*
Y3468425D01*
G01X3107180D02*
X3110900D01*
G01X3109040D02*
Y3455925D01*
G01X3107180D02*
X3110900D01*
G01X3121440Y3468425D02*
Y3455925D01*
G01X3117875Y3468425D02*
X3125005D01*
G01X3130585Y3457591D02*
X3131825Y3456550D01*
X3133220Y3455925D01*
X3134460D01*
X3135700Y3456550D01*
X3136630Y3457591D01*
X3137095Y3459050D01*
X3136785Y3460508D01*
X3136010Y3461758D01*
X3134615Y3462592D01*
X3132755Y3463008D01*
X3131670Y3463842D01*
X3131205Y3465300D01*
X3131515Y3466758D01*
X3132290Y3467800D01*
X3133375Y3468425D01*
X3134460D01*
X3135545Y3468008D01*
X3136475Y3466967D01*
G01X3154765Y3455925D02*
X3158640Y3468425D01*
X3162515Y3455925D01*
G01X3161120Y3460300D02*
X3156160D01*
G01X3167940Y3455925D02*
Y3468425D01*
X3171815D01*
X3173055Y3467800D01*
X3173830Y3466967D01*
X3174140Y3465300D01*
X3173830Y3463633D01*
X3172900Y3462592D01*
X3171815Y3461967D01*
X3167940D01*
G01X3171815D02*
X3174140Y3455925D01*
G01X3186540D02*
X3180340D01*
Y3468425D01*
X3186540D01*
G01X3184060Y3462383D02*
X3180340D01*
G01X3206380Y3468425D02*
X3210100D01*
G01X3208240D02*
Y3455925D01*
G01X3206380D02*
X3210100D01*
G01X3217075D02*
Y3468425D01*
X3224205Y3455925D01*
Y3468425D01*
G01X3241410Y3455925D02*
Y3468425D01*
X3245440Y3458008D01*
X3249470Y3468425D01*
Y3455925D01*
G01X3255980Y3468425D02*
X3259700D01*
G01X3257840D02*
Y3455925D01*
G01X3255980D02*
X3259700D01*
G01X3267140Y3468425D02*
Y3455925D01*
X3273340D01*
G01X3279385Y3457591D02*
X3280625Y3456550D01*
X3282020Y3455925D01*
X3283260D01*
X3284500Y3456550D01*
X3285430Y3457591D01*
X3285895Y3459050D01*
X3285585Y3460508D01*
X3284810Y3461758D01*
X3283415Y3462592D01*
X3281555Y3463008D01*
X3280470Y3463842D01*
X3280005Y3465300D01*
X3280315Y3466758D01*
X3281090Y3467800D01*
X3282175Y3468425D01*
X3283260D01*
X3284345Y3468008D01*
X3285275Y3466967D01*
G01X3035870Y3741387D02*
X3039745Y3753887D01*
X3043620Y3741387D01*
G01X3042225Y3745762D02*
X3037265D01*
G01X3049045Y3753887D02*
Y3741387D01*
X3055245D01*
G01X3061445Y3753887D02*
Y3741387D01*
X3067645D01*
G01X3085935Y3753887D02*
Y3744929D01*
X3086555Y3743053D01*
X3087795Y3741804D01*
X3089345Y3741387D01*
X3090895Y3741804D01*
X3092135Y3743053D01*
X3092755Y3744929D01*
Y3753887D01*
G01X3098180Y3741387D02*
Y3753887D01*
X3105310Y3741387D01*
Y3753887D01*
G01X3112285D02*
X3116005D01*
G01X3114145D02*
Y3741387D01*
G01X3112285D02*
X3116005D01*
G01X3126545Y3753887D02*
Y3741387D01*
G01X3122980Y3753887D02*
X3130110D01*
G01X3135690Y3743053D02*
X3136930Y3742012D01*
X3138325Y3741387D01*
X3139565D01*
X3140805Y3742012D01*
X3141735Y3743053D01*
X3142200Y3744512D01*
X3141890Y3745970D01*
X3141115Y3747220D01*
X3139720Y3748054D01*
X3137860Y3748470D01*
X3136775Y3749304D01*
X3136310Y3750762D01*
X3136620Y3752220D01*
X3137395Y3753262D01*
X3138480Y3753887D01*
X3139565D01*
X3140650Y3753470D01*
X3141580Y3752429D01*
G01X3159870Y3741387D02*
X3163745Y3753887D01*
X3167620Y3741387D01*
G01X3166225Y3745762D02*
X3161265D01*
G01X3173045Y3741387D02*
Y3753887D01*
X3176920D01*
X3178160Y3753262D01*
X3178935Y3752429D01*
X3179245Y3750762D01*
X3178935Y3749095D01*
X3178005Y3748054D01*
X3176920Y3747429D01*
X3173045D01*
G01X3176920D02*
X3179245Y3741387D01*
G01X3191645D02*
X3185445D01*
Y3753887D01*
X3191645D01*
G01X3189165Y3747845D02*
X3185445D01*
G01X3211485Y3753887D02*
X3215205D01*
G01X3213345D02*
Y3741387D01*
G01X3211485D02*
X3215205D01*
G01X3222180D02*
Y3753887D01*
X3229310Y3741387D01*
Y3753887D01*
G01X3246515Y3741387D02*
Y3753887D01*
X3250545Y3743470D01*
X3254575Y3753887D01*
Y3741387D01*
G01X3261085Y3753887D02*
X3264805D01*
G01X3262945D02*
Y3741387D01*
G01X3261085D02*
X3264805D01*
G01X3272245Y3753887D02*
Y3741387D01*
X3278445D01*
G01X3284490Y3743053D02*
X3285730Y3742012D01*
X3287125Y3741387D01*
X3288365D01*
X3289605Y3742012D01*
X3290535Y3743053D01*
X3291000Y3744512D01*
X3290690Y3745970D01*
X3289915Y3747220D01*
X3288520Y3748054D01*
X3286660Y3748470D01*
X3285575Y3749304D01*
X3285110Y3750762D01*
X3285420Y3752220D01*
X3286195Y3753262D01*
X3287280Y3753887D01*
X3288365D01*
X3289450Y3753470D01*
X3290380Y3752429D01*
G01X3051000Y2635432D02*
Y2647932D01*
X3055030Y2637515D01*
X3059060Y2647932D01*
Y2635432D01*
G01X3063865D02*
Y2647932D01*
X3070995Y2635432D01*
Y2647932D01*
G01X3083240Y2646890D02*
X3082310Y2647515D01*
X3081225Y2647932D01*
X3079985D01*
X3078590Y2647307D01*
X3077505Y2646265D01*
X3076730Y2645015D01*
X3076110Y2642932D01*
X3075955Y2641057D01*
X3076265Y2639182D01*
X3076730Y2637932D01*
X3077660Y2636682D01*
X3078745Y2635849D01*
X3079830Y2635432D01*
X3080915D01*
X3082000Y2635849D01*
X3082930Y2636473D01*
X3083705Y2637307D01*
G01X3087580Y2631265D02*
X3096880D01*
G01X3101530Y2647932D02*
Y2635432D01*
X3107730D01*
G01X3113155D02*
X3117030Y2647932D01*
X3120905Y2635432D01*
G01X3119510Y2639807D02*
X3114550D01*
G01X3129430Y2635432D02*
Y2641057D01*
X3126330Y2647932D01*
G01X3132530D02*
X3129430Y2641057D01*
G01X3144930Y2635432D02*
X3138730D01*
Y2647932D01*
X3144930D01*
G01X3142450Y2641890D02*
X3138730D01*
G01X3151130Y2635432D02*
Y2647932D01*
X3155005D01*
X3156245Y2647307D01*
X3157020Y2646474D01*
X3157330Y2644807D01*
X3157020Y2643140D01*
X3156090Y2642099D01*
X3155005Y2641474D01*
X3151130D01*
G01X3155005D02*
X3157330Y2635432D01*
G01X3051996Y2924349D02*
Y2936849D01*
X3056026Y2926432D01*
X3060056Y2936849D01*
Y2924349D01*
G01X3064861D02*
Y2936849D01*
X3071991Y2924349D01*
Y2936849D01*
G01X3084236Y2935807D02*
X3083306Y2936432D01*
X3082221Y2936849D01*
X3080981D01*
X3079586Y2936224D01*
X3078501Y2935182D01*
X3077726Y2933932D01*
X3077106Y2931849D01*
X3076951Y2929974D01*
X3077261Y2928099D01*
X3077726Y2926849D01*
X3078656Y2925599D01*
X3079741Y2924766D01*
X3080826Y2924349D01*
X3081911D01*
X3082996Y2924766D01*
X3083926Y2925390D01*
X3084701Y2926224D01*
G01X3088576Y2920182D02*
X3097876D01*
G01X3102526Y2936849D02*
Y2924349D01*
X3108726D01*
G01X3114151D02*
X3118026Y2936849D01*
X3121901Y2924349D01*
G01X3120506Y2928724D02*
X3115546D01*
G01X3130426Y2924349D02*
Y2929974D01*
X3127326Y2936849D01*
G01X3133526D02*
X3130426Y2929974D01*
G01X3145926Y2924349D02*
X3139726D01*
Y2936849D01*
X3145926D01*
G01X3143446Y2930807D02*
X3139726D01*
G01X3152126Y2924349D02*
Y2936849D01*
X3156001D01*
X3157241Y2936224D01*
X3158016Y2935391D01*
X3158326Y2933724D01*
X3158016Y2932057D01*
X3157086Y2931016D01*
X3156001Y2930391D01*
X3152126D01*
G01X3156001D02*
X3158326Y2924349D01*
G01X3052006Y3174919D02*
Y3187419D01*
X3056036Y3177002D01*
X3060066Y3187419D01*
Y3174919D01*
G01X3064871D02*
Y3187419D01*
X3072001Y3174919D01*
Y3187419D01*
G01X3084246Y3186377D02*
X3083316Y3187002D01*
X3082231Y3187419D01*
X3080991D01*
X3079596Y3186794D01*
X3078511Y3185752D01*
X3077736Y3184502D01*
X3077116Y3182419D01*
X3076961Y3180544D01*
X3077271Y3178669D01*
X3077736Y3177419D01*
X3078666Y3176169D01*
X3079751Y3175336D01*
X3080836Y3174919D01*
X3081921D01*
X3083006Y3175336D01*
X3083936Y3175960D01*
X3084711Y3176794D01*
G01X3088586Y3170752D02*
X3097886D01*
G01X3102536Y3187419D02*
Y3174919D01*
X3108736D01*
G01X3114161D02*
X3118036Y3187419D01*
X3121911Y3174919D01*
G01X3120516Y3179294D02*
X3115556D01*
G01X3130436Y3174919D02*
Y3180544D01*
X3127336Y3187419D01*
G01X3133536D02*
X3130436Y3180544D01*
G01X3145936Y3174919D02*
X3139736D01*
Y3187419D01*
X3145936D01*
G01X3143456Y3181377D02*
X3139736D01*
G01X3152136Y3174919D02*
Y3187419D01*
X3156011D01*
X3157251Y3186794D01*
X3158026Y3185961D01*
X3158336Y3184294D01*
X3158026Y3182627D01*
X3157096Y3181586D01*
X3156011Y3180961D01*
X3152136D01*
G01X3156011D02*
X3158336Y3174919D01*
G01X3047660Y3430925D02*
Y3443425D01*
X3051690Y3433008D01*
X3055720Y3443425D01*
Y3430925D01*
G01X3060525D02*
Y3443425D01*
X3067655Y3430925D01*
Y3443425D01*
G01X3079900Y3442383D02*
X3078970Y3443008D01*
X3077885Y3443425D01*
X3076645D01*
X3075250Y3442800D01*
X3074165Y3441758D01*
X3073390Y3440508D01*
X3072770Y3438425D01*
X3072615Y3436550D01*
X3072925Y3434675D01*
X3073390Y3433425D01*
X3074320Y3432175D01*
X3075405Y3431342D01*
X3076490Y3430925D01*
X3077575D01*
X3078660Y3431342D01*
X3079590Y3431966D01*
X3080365Y3432800D01*
G01X3084240Y3426758D02*
X3093540D01*
G01X3098190Y3443425D02*
Y3430925D01*
X3104390D01*
G01X3109815D02*
X3113690Y3443425D01*
X3117565Y3430925D01*
G01X3116170Y3435300D02*
X3111210D01*
G01X3126090Y3430925D02*
Y3436550D01*
X3122990Y3443425D01*
G01X3129190D02*
X3126090Y3436550D01*
G01X3141590Y3430925D02*
X3135390D01*
Y3443425D01*
X3141590D01*
G01X3139110Y3437383D02*
X3135390D01*
G01X3147790Y3430925D02*
Y3443425D01*
X3151665D01*
X3152905Y3442800D01*
X3153680Y3441967D01*
X3153990Y3440300D01*
X3153680Y3438633D01*
X3152750Y3437592D01*
X3151665Y3436967D01*
X3147790D01*
G01X3151665D02*
X3153990Y3430925D01*
G01X3052765Y3716387D02*
Y3728887D01*
X3056795Y3718470D01*
X3060825Y3728887D01*
Y3716387D01*
G01X3065630D02*
Y3728887D01*
X3072760Y3716387D01*
Y3728887D01*
G01X3085005Y3727845D02*
X3084075Y3728470D01*
X3082990Y3728887D01*
X3081750D01*
X3080355Y3728262D01*
X3079270Y3727220D01*
X3078495Y3725970D01*
X3077875Y3723887D01*
X3077720Y3722012D01*
X3078030Y3720137D01*
X3078495Y3718887D01*
X3079425Y3717637D01*
X3080510Y3716804D01*
X3081595Y3716387D01*
X3082680D01*
X3083765Y3716804D01*
X3084695Y3717428D01*
X3085470Y3718262D01*
G01X3089345Y3712220D02*
X3098645D01*
G01X3103295Y3728887D02*
Y3716387D01*
X3109495D01*
G01X3114920D02*
X3118795Y3728887D01*
X3122670Y3716387D01*
G01X3121275Y3720762D02*
X3116315D01*
G01X3131195Y3716387D02*
Y3722012D01*
X3128095Y3728887D01*
G01X3134295D02*
X3131195Y3722012D01*
G01X3146695Y3716387D02*
X3140495D01*
Y3728887D01*
X3146695D01*
G01X3144215Y3722845D02*
X3140495D01*
G01X3152895Y3716387D02*
Y3728887D01*
X3156770D01*
X3158010Y3728262D01*
X3158785Y3727429D01*
X3159095Y3725762D01*
X3158785Y3724095D01*
X3157855Y3723054D01*
X3156770Y3722429D01*
X3152895D01*
G01X3156770D02*
X3159095Y3716387D01*
G01X3068461Y2081229D02*
Y2093729D01*
X3071561D01*
X3072801Y2093104D01*
X3073731Y2092271D01*
X3074506Y2091021D01*
X3075126Y2089562D01*
X3075281Y2087479D01*
X3075126Y2085396D01*
X3074506Y2083937D01*
X3073731Y2082687D01*
X3072801Y2081854D01*
X3071561Y2081229D01*
X3068461D01*
G01X3081171D02*
Y2093729D01*
X3085046D01*
X3086286Y2093104D01*
X3087061Y2092271D01*
X3087371Y2090604D01*
X3087061Y2088937D01*
X3086131Y2087896D01*
X3085046Y2087271D01*
X3081171D01*
G01X3085046D02*
X3087371Y2081229D01*
G01X3094811Y2093729D02*
X3098531D01*
G01X3096671D02*
Y2081229D01*
G01X3094811D02*
X3098531D01*
G01X3105971Y2093729D02*
Y2081229D01*
X3112171D01*
G01X3118371Y2093729D02*
Y2081229D01*
X3124571D01*
G01X3149681Y2092687D02*
X3148751Y2093312D01*
X3147666Y2093729D01*
X3146426D01*
X3145031Y2093104D01*
X3143946Y2092062D01*
X3143171Y2090812D01*
X3142551Y2088729D01*
X3142396Y2086854D01*
X3142706Y2084979D01*
X3143171Y2083729D01*
X3144101Y2082479D01*
X3145186Y2081646D01*
X3146271Y2081229D01*
X3147356D01*
X3148441Y2081646D01*
X3149371Y2082270D01*
X3150146Y2083104D01*
G01X3155416Y2081229D02*
Y2093729D01*
G01X3161926D02*
Y2081229D01*
G01Y2087479D02*
X3155416D01*
G01X3167196Y2081229D02*
X3171071Y2093729D01*
X3174946Y2081229D01*
G01X3173551Y2085604D02*
X3168591D01*
G01X3180371Y2081229D02*
Y2093729D01*
X3184246D01*
X3185486Y2093104D01*
X3186261Y2092271D01*
X3186571Y2090604D01*
X3186261Y2088937D01*
X3185331Y2087896D01*
X3184246Y2087271D01*
X3180371D01*
G01X3184246D02*
X3186571Y2081229D01*
G01X3195871Y2093729D02*
Y2081229D01*
G01X3192306Y2093729D02*
X3199436D01*
G01X3208271Y2080812D02*
X3207961Y2081021D01*
Y2081437D01*
X3208271Y2081646D01*
X3208581Y2081437D01*
Y2081021D01*
X3208271Y2080812D01*
G01Y2086437D02*
X3207961Y2086646D01*
Y2087062D01*
X3208271Y2087271D01*
X3208581Y2087062D01*
Y2086646D01*
X3208271Y2086437D01*
G01X3233071Y2093729D02*
Y2081229D01*
G01X3229506Y2093729D02*
X3236636D01*
G01X3245471Y2081229D02*
X3244231Y2081437D01*
X3243146Y2082270D01*
X3242216Y2083521D01*
X3241596Y2084979D01*
X3241286Y2086646D01*
Y2088312D01*
X3241596Y2089979D01*
X3242216Y2091437D01*
X3243146Y2092687D01*
X3244231Y2093521D01*
X3245471Y2093729D01*
X3246711Y2093521D01*
X3247796Y2092687D01*
X3248726Y2091437D01*
X3249346Y2089979D01*
X3249656Y2088312D01*
Y2086646D01*
X3249346Y2084979D01*
X3248726Y2083521D01*
X3247796Y2082270D01*
X3246711Y2081437D01*
X3245471Y2081229D01*
G01X3254771D02*
Y2093729D01*
X3258491D01*
X3259731Y2093104D01*
X3260661Y2091646D01*
X3260971Y2089979D01*
X3260661Y2088312D01*
X3259886Y2087062D01*
X3258491Y2086437D01*
X3254771D01*
G01X3282671Y2093729D02*
Y2081229D01*
G01X3280501Y2089562D02*
X3284841D01*
G01X3295071Y2081229D02*
X3294141Y2081437D01*
X3293211Y2082270D01*
X3292591Y2083729D01*
X3292281Y2085396D01*
X3292591Y2087062D01*
X3293211Y2088521D01*
X3294141Y2089354D01*
X3295071Y2089562D01*
X3296001Y2089354D01*
X3296931Y2088521D01*
X3297551Y2087062D01*
X3297706Y2085396D01*
X3297551Y2083729D01*
X3296931Y2082270D01*
X3296001Y2081437D01*
X3295071Y2081229D01*
G01X3321111Y2087896D02*
X3321731Y2088521D01*
X3322196Y2089562D01*
X3322506Y2091021D01*
X3322196Y2092271D01*
X3321576Y2093104D01*
X3320491Y2093729D01*
X3316306D01*
Y2081229D01*
X3321421D01*
X3322506Y2082062D01*
X3323126Y2083312D01*
X3323436Y2084771D01*
X3323126Y2086229D01*
X3322196Y2087479D01*
X3321111Y2087896D01*
X3316306D01*
G01X3332271Y2081229D02*
X3331031Y2081437D01*
X3329946Y2082270D01*
X3329016Y2083521D01*
X3328396Y2084979D01*
X3328086Y2086646D01*
Y2088312D01*
X3328396Y2089979D01*
X3329016Y2091437D01*
X3329946Y2092687D01*
X3331031Y2093521D01*
X3332271Y2093729D01*
X3333511Y2093521D01*
X3334596Y2092687D01*
X3335526Y2091437D01*
X3336146Y2089979D01*
X3336456Y2088312D01*
Y2086646D01*
X3336146Y2084979D01*
X3335526Y2083521D01*
X3334596Y2082270D01*
X3333511Y2081437D01*
X3332271Y2081229D01*
G01X3344671Y2093729D02*
Y2081229D01*
G01X3341106Y2093729D02*
X3348236D01*
G01X3357071D02*
Y2081229D01*
G01X3353506Y2093729D02*
X3360636D01*
G01X3369471Y2081229D02*
X3368231Y2081437D01*
X3367146Y2082270D01*
X3366216Y2083521D01*
X3365596Y2084979D01*
X3365286Y2086646D01*
Y2088312D01*
X3365596Y2089979D01*
X3366216Y2091437D01*
X3367146Y2092687D01*
X3368231Y2093521D01*
X3369471Y2093729D01*
X3370711Y2093521D01*
X3371796Y2092687D01*
X3372726Y2091437D01*
X3373346Y2089979D01*
X3373656Y2088312D01*
Y2086646D01*
X3373346Y2084979D01*
X3372726Y2083521D01*
X3371796Y2082270D01*
X3370711Y2081437D01*
X3369471Y2081229D01*
G01X3377841D02*
Y2093729D01*
X3381871Y2083312D01*
X3385901Y2093729D01*
Y2081229D01*
G01X3082721Y2043729D02*
Y2031229D01*
G01X3079156Y2043729D02*
X3086286D01*
G01X3095121Y2031229D02*
X3093881Y2031437D01*
X3092796Y2032270D01*
X3091866Y2033521D01*
X3091246Y2034979D01*
X3090936Y2036646D01*
Y2038312D01*
X3091246Y2039979D01*
X3091866Y2041437D01*
X3092796Y2042687D01*
X3093881Y2043521D01*
X3095121Y2043729D01*
X3096361Y2043521D01*
X3097446Y2042687D01*
X3098376Y2041437D01*
X3098996Y2039979D01*
X3099306Y2038312D01*
Y2036646D01*
X3098996Y2034979D01*
X3098376Y2033521D01*
X3097446Y2032270D01*
X3096361Y2031437D01*
X3095121Y2031229D01*
G01X3104421Y2043729D02*
Y2031229D01*
X3110621D01*
G01X3123021D02*
X3116821D01*
Y2043729D01*
X3123021D01*
G01X3120541Y2037687D02*
X3116821D01*
G01X3129221Y2031229D02*
Y2043729D01*
X3133096D01*
X3134336Y2043104D01*
X3135111Y2042271D01*
X3135421Y2040604D01*
X3135111Y2038937D01*
X3134181Y2037896D01*
X3133096Y2037271D01*
X3129221D01*
G01X3133096D02*
X3135421Y2031229D01*
G01X3140846D02*
X3144721Y2043729D01*
X3148596Y2031229D01*
G01X3147201Y2035604D02*
X3142241D01*
G01X3153556Y2031229D02*
Y2043729D01*
X3160686Y2031229D01*
Y2043729D01*
G01X3172931Y2042687D02*
X3172001Y2043312D01*
X3170916Y2043729D01*
X3169676D01*
X3168281Y2043104D01*
X3167196Y2042062D01*
X3166421Y2040812D01*
X3165801Y2038729D01*
X3165646Y2036854D01*
X3165956Y2034979D01*
X3166421Y2033729D01*
X3167351Y2032479D01*
X3168436Y2031646D01*
X3169521Y2031229D01*
X3170606D01*
X3171691Y2031646D01*
X3172621Y2032270D01*
X3173396Y2033104D01*
G01X3185021Y2031229D02*
X3178821D01*
Y2043729D01*
X3185021D01*
G01X3182541Y2037687D02*
X3178821D01*
G01X3189671Y2027062D02*
X3198971D01*
G01X3203311Y2031229D02*
Y2043729D01*
X3206411D01*
X3207651Y2043104D01*
X3208581Y2042271D01*
X3209356Y2041021D01*
X3209976Y2039562D01*
X3210131Y2037479D01*
X3209976Y2035396D01*
X3209356Y2033937D01*
X3208581Y2032687D01*
X3207651Y2031854D01*
X3206411Y2031229D01*
X3203311D01*
G01X3216021D02*
Y2043729D01*
X3219896D01*
X3221136Y2043104D01*
X3221911Y2042271D01*
X3222221Y2040604D01*
X3221911Y2038937D01*
X3220981Y2037896D01*
X3219896Y2037271D01*
X3216021D01*
G01X3219896D02*
X3222221Y2031229D01*
G01X3229661Y2043729D02*
X3233381D01*
G01X3231521D02*
Y2031229D01*
G01X3229661D02*
X3233381D01*
G01X3240821Y2043729D02*
Y2031229D01*
X3247021D01*
G01X3253221Y2043729D02*
Y2031229D01*
X3259421D01*
G01X3087030Y3393425D02*
X3090750D01*
G01X3088890D02*
Y3380925D01*
G01X3087030D02*
X3090750D01*
G01X3097725D02*
Y3393425D01*
X3104855Y3380925D01*
Y3393425D01*
G01X3113690Y3380925D02*
Y3393425D01*
X3111830Y3390925D01*
G01Y3380925D02*
X3115550D01*
G01X3087030Y3418425D02*
X3090750D01*
G01X3088890D02*
Y3405925D01*
G01X3087030D02*
X3090750D01*
G01X3097725D02*
Y3418425D01*
X3104855Y3405925D01*
Y3418425D01*
G01X3113690Y3405925D02*
Y3418425D01*
X3111830Y3415925D01*
G01Y3405925D02*
X3115550D01*
G01X3105816Y-75154D02*
X3109536D01*
G01X3107521Y-72446D02*
Y-77863D01*
G01X3119921Y-79321D02*
Y-66821D01*
X3118061Y-69321D01*
G01Y-79321D02*
X3121781D01*
G01X3132321Y-79738D02*
X3132011Y-79529D01*
Y-79113D01*
X3132321Y-78904D01*
X3132631Y-79113D01*
Y-79529D01*
X3132321Y-79738D01*
G01X3142086Y-77863D02*
X3143171Y-78904D01*
X3144411Y-79321D01*
X3145651Y-78904D01*
X3146736Y-77655D01*
X3147511Y-75779D01*
X3147821Y-73904D01*
Y-71613D01*
X3147511Y-69738D01*
X3146736Y-68071D01*
X3145806Y-67238D01*
X3144721Y-66821D01*
X3143481Y-67238D01*
X3142551Y-68071D01*
X3141931Y-69321D01*
X3141621Y-70988D01*
X3141931Y-72446D01*
X3142706Y-73904D01*
X3143636Y-74738D01*
X3144721Y-74946D01*
X3145961Y-74530D01*
X3146891Y-73488D01*
X3147821Y-71613D01*
G01X3154176Y-74113D02*
X3155261Y-72654D01*
X3156191Y-71821D01*
X3157431Y-71404D01*
X3158516Y-71821D01*
X3159291Y-72654D01*
X3159911Y-73904D01*
X3160066Y-75363D01*
X3159911Y-76613D01*
X3159291Y-77863D01*
X3158361Y-78904D01*
X3157276Y-79321D01*
X3156036Y-78904D01*
X3154951Y-77655D01*
X3154331Y-75779D01*
X3154176Y-73696D01*
X3154486Y-70988D01*
X3154951Y-69529D01*
X3155726Y-68071D01*
X3156811Y-67029D01*
X3157896Y-66821D01*
X3158981Y-67238D01*
X3159756Y-68279D01*
G01X3166731Y-79738D02*
X3172311Y-66821D01*
G01X3179906Y-75154D02*
X3183936D01*
G01X3194321Y-79321D02*
Y-66821D01*
X3192461Y-69321D01*
G01Y-79321D02*
X3196181D01*
G01X3206721Y-79738D02*
X3206411Y-79529D01*
Y-79113D01*
X3206721Y-78904D01*
X3207031Y-79113D01*
Y-79529D01*
X3206721Y-79738D01*
G01X3216486Y-77863D02*
X3217571Y-78904D01*
X3218811Y-79321D01*
X3220051Y-78904D01*
X3221136Y-77655D01*
X3221911Y-75779D01*
X3222221Y-73904D01*
Y-71613D01*
X3221911Y-69738D01*
X3221136Y-68071D01*
X3220206Y-67238D01*
X3219121Y-66821D01*
X3217881Y-67238D01*
X3216951Y-68071D01*
X3216331Y-69321D01*
X3216021Y-70988D01*
X3216331Y-72446D01*
X3217106Y-73904D01*
X3218036Y-74738D01*
X3219121Y-74946D01*
X3220361Y-74530D01*
X3221291Y-73488D01*
X3222221Y-71613D01*
G01X3228576Y-74113D02*
X3229661Y-72654D01*
X3230591Y-71821D01*
X3231831Y-71404D01*
X3232916Y-71821D01*
X3233691Y-72654D01*
X3234311Y-73904D01*
X3234466Y-75363D01*
X3234311Y-76613D01*
X3233691Y-77863D01*
X3232761Y-78904D01*
X3231676Y-79321D01*
X3230436Y-78904D01*
X3229351Y-77655D01*
X3228731Y-75779D01*
X3228576Y-73696D01*
X3228886Y-70988D01*
X3229351Y-69529D01*
X3230126Y-68071D01*
X3231211Y-67029D01*
X3232296Y-66821D01*
X3233381Y-67238D01*
X3234156Y-68279D01*
G01X3105816Y-16054D02*
X3109536D01*
G01X3107521Y-13346D02*
Y-18763D01*
G01X3119921Y-20221D02*
Y-7721D01*
X3118061Y-10221D01*
G01Y-20221D02*
X3121781D01*
G01X3132321Y-20638D02*
X3132011Y-20429D01*
Y-20013D01*
X3132321Y-19804D01*
X3132631Y-20013D01*
Y-20429D01*
X3132321Y-20638D01*
G01X3142086Y-18763D02*
X3143171Y-19804D01*
X3144411Y-20221D01*
X3145651Y-19804D01*
X3146736Y-18555D01*
X3147511Y-16679D01*
X3147821Y-14804D01*
Y-12513D01*
X3147511Y-10638D01*
X3146736Y-8971D01*
X3145806Y-8138D01*
X3144721Y-7721D01*
X3143481Y-8138D01*
X3142551Y-8971D01*
X3141931Y-10221D01*
X3141621Y-11888D01*
X3141931Y-13346D01*
X3142706Y-14804D01*
X3143636Y-15638D01*
X3144721Y-15846D01*
X3145961Y-15430D01*
X3146891Y-14388D01*
X3147821Y-12513D01*
G01X3154176Y-15013D02*
X3155261Y-13554D01*
X3156191Y-12721D01*
X3157431Y-12304D01*
X3158516Y-12721D01*
X3159291Y-13554D01*
X3159911Y-14804D01*
X3160066Y-16263D01*
X3159911Y-17513D01*
X3159291Y-18763D01*
X3158361Y-19804D01*
X3157276Y-20221D01*
X3156036Y-19804D01*
X3154951Y-18555D01*
X3154331Y-16679D01*
X3154176Y-14596D01*
X3154486Y-11888D01*
X3154951Y-10429D01*
X3155726Y-8971D01*
X3156811Y-7929D01*
X3157896Y-7721D01*
X3158981Y-8138D01*
X3159756Y-9179D01*
G01X3166731Y-20638D02*
X3172311Y-7721D01*
G01X3179906Y-16054D02*
X3183936D01*
G01X3194321Y-20221D02*
Y-7721D01*
X3192461Y-10221D01*
G01Y-20221D02*
X3196181D01*
G01X3206721Y-20638D02*
X3206411Y-20429D01*
Y-20013D01*
X3206721Y-19804D01*
X3207031Y-20013D01*
Y-20429D01*
X3206721Y-20638D01*
G01X3216486Y-18763D02*
X3217571Y-19804D01*
X3218811Y-20221D01*
X3220051Y-19804D01*
X3221136Y-18555D01*
X3221911Y-16679D01*
X3222221Y-14804D01*
Y-12513D01*
X3221911Y-10638D01*
X3221136Y-8971D01*
X3220206Y-8138D01*
X3219121Y-7721D01*
X3217881Y-8138D01*
X3216951Y-8971D01*
X3216331Y-10221D01*
X3216021Y-11888D01*
X3216331Y-13346D01*
X3217106Y-14804D01*
X3218036Y-15638D01*
X3219121Y-15846D01*
X3220361Y-15430D01*
X3221291Y-14388D01*
X3222221Y-12513D01*
G01X3228576Y-15013D02*
X3229661Y-13554D01*
X3230591Y-12721D01*
X3231831Y-12304D01*
X3232916Y-12721D01*
X3233691Y-13554D01*
X3234311Y-14804D01*
X3234466Y-16263D01*
X3234311Y-17513D01*
X3233691Y-18763D01*
X3232761Y-19804D01*
X3231676Y-20221D01*
X3230436Y-19804D01*
X3229351Y-18555D01*
X3228731Y-16679D01*
X3228576Y-14596D01*
X3228886Y-11888D01*
X3229351Y-10429D01*
X3230126Y-8971D01*
X3231211Y-7929D01*
X3232296Y-7721D01*
X3233381Y-8138D01*
X3234156Y-9179D01*
G01X3105816Y634046D02*
X3109536D01*
G01X3107521Y636754D02*
Y631337D01*
G01X3119921Y629879D02*
Y642379D01*
X3118061Y639879D01*
G01Y629879D02*
X3121781D01*
G01X3132321Y629462D02*
X3132011Y629671D01*
Y630087D01*
X3132321Y630296D01*
X3132631Y630087D01*
Y629671D01*
X3132321Y629462D01*
G01X3142086Y631337D02*
X3143171Y630296D01*
X3144411Y629879D01*
X3145651Y630296D01*
X3146736Y631545D01*
X3147511Y633421D01*
X3147821Y635296D01*
Y637587D01*
X3147511Y639462D01*
X3146736Y641129D01*
X3145806Y641962D01*
X3144721Y642379D01*
X3143481Y641962D01*
X3142551Y641129D01*
X3141931Y639879D01*
X3141621Y638212D01*
X3141931Y636754D01*
X3142706Y635296D01*
X3143636Y634462D01*
X3144721Y634254D01*
X3145961Y634670D01*
X3146891Y635712D01*
X3147821Y637587D01*
G01X3154176Y635087D02*
X3155261Y636546D01*
X3156191Y637379D01*
X3157431Y637796D01*
X3158516Y637379D01*
X3159291Y636546D01*
X3159911Y635296D01*
X3160066Y633837D01*
X3159911Y632587D01*
X3159291Y631337D01*
X3158361Y630296D01*
X3157276Y629879D01*
X3156036Y630296D01*
X3154951Y631545D01*
X3154331Y633421D01*
X3154176Y635504D01*
X3154486Y638212D01*
X3154951Y639671D01*
X3155726Y641129D01*
X3156811Y642171D01*
X3157896Y642379D01*
X3158981Y641962D01*
X3159756Y640921D01*
G01X3166731Y629462D02*
X3172311Y642379D01*
G01X3179906Y634046D02*
X3183936D01*
G01X3194321Y629879D02*
Y642379D01*
X3192461Y639879D01*
G01Y629879D02*
X3196181D01*
G01X3206721Y629462D02*
X3206411Y629671D01*
Y630087D01*
X3206721Y630296D01*
X3207031Y630087D01*
Y629671D01*
X3206721Y629462D01*
G01X3216486Y631337D02*
X3217571Y630296D01*
X3218811Y629879D01*
X3220051Y630296D01*
X3221136Y631545D01*
X3221911Y633421D01*
X3222221Y635296D01*
Y637587D01*
X3221911Y639462D01*
X3221136Y641129D01*
X3220206Y641962D01*
X3219121Y642379D01*
X3217881Y641962D01*
X3216951Y641129D01*
X3216331Y639879D01*
X3216021Y638212D01*
X3216331Y636754D01*
X3217106Y635296D01*
X3218036Y634462D01*
X3219121Y634254D01*
X3220361Y634670D01*
X3221291Y635712D01*
X3222221Y637587D01*
G01X3228576Y635087D02*
X3229661Y636546D01*
X3230591Y637379D01*
X3231831Y637796D01*
X3232916Y637379D01*
X3233691Y636546D01*
X3234311Y635296D01*
X3234466Y633837D01*
X3234311Y632587D01*
X3233691Y631337D01*
X3232761Y630296D01*
X3231676Y629879D01*
X3230436Y630296D01*
X3229351Y631545D01*
X3228731Y633421D01*
X3228576Y635504D01*
X3228886Y638212D01*
X3229351Y639671D01*
X3230126Y641129D01*
X3231211Y642171D01*
X3232296Y642379D01*
X3233381Y641962D01*
X3234156Y640921D01*
G01X3105816Y752246D02*
X3109536D01*
G01X3107521Y754954D02*
Y749537D01*
G01X3119921Y748079D02*
Y760579D01*
X3118061Y758079D01*
G01Y748079D02*
X3121781D01*
G01X3132321Y747662D02*
X3132011Y747871D01*
Y748287D01*
X3132321Y748496D01*
X3132631Y748287D01*
Y747871D01*
X3132321Y747662D01*
G01X3142086Y749537D02*
X3143171Y748496D01*
X3144411Y748079D01*
X3145651Y748496D01*
X3146736Y749745D01*
X3147511Y751621D01*
X3147821Y753496D01*
Y755787D01*
X3147511Y757662D01*
X3146736Y759329D01*
X3145806Y760162D01*
X3144721Y760579D01*
X3143481Y760162D01*
X3142551Y759329D01*
X3141931Y758079D01*
X3141621Y756412D01*
X3141931Y754954D01*
X3142706Y753496D01*
X3143636Y752662D01*
X3144721Y752454D01*
X3145961Y752870D01*
X3146891Y753912D01*
X3147821Y755787D01*
G01X3154176Y753287D02*
X3155261Y754746D01*
X3156191Y755579D01*
X3157431Y755996D01*
X3158516Y755579D01*
X3159291Y754746D01*
X3159911Y753496D01*
X3160066Y752037D01*
X3159911Y750787D01*
X3159291Y749537D01*
X3158361Y748496D01*
X3157276Y748079D01*
X3156036Y748496D01*
X3154951Y749745D01*
X3154331Y751621D01*
X3154176Y753704D01*
X3154486Y756412D01*
X3154951Y757871D01*
X3155726Y759329D01*
X3156811Y760371D01*
X3157896Y760579D01*
X3158981Y760162D01*
X3159756Y759121D01*
G01X3166731Y747662D02*
X3172311Y760579D01*
G01X3179906Y752246D02*
X3183936D01*
G01X3194321Y748079D02*
Y760579D01*
X3192461Y758079D01*
G01Y748079D02*
X3196181D01*
G01X3206721Y747662D02*
X3206411Y747871D01*
Y748287D01*
X3206721Y748496D01*
X3207031Y748287D01*
Y747871D01*
X3206721Y747662D01*
G01X3216486Y749537D02*
X3217571Y748496D01*
X3218811Y748079D01*
X3220051Y748496D01*
X3221136Y749745D01*
X3221911Y751621D01*
X3222221Y753496D01*
Y755787D01*
X3221911Y757662D01*
X3221136Y759329D01*
X3220206Y760162D01*
X3219121Y760579D01*
X3217881Y760162D01*
X3216951Y759329D01*
X3216331Y758079D01*
X3216021Y756412D01*
X3216331Y754954D01*
X3217106Y753496D01*
X3218036Y752662D01*
X3219121Y752454D01*
X3220361Y752870D01*
X3221291Y753912D01*
X3222221Y755787D01*
G01X3228576Y753287D02*
X3229661Y754746D01*
X3230591Y755579D01*
X3231831Y755996D01*
X3232916Y755579D01*
X3233691Y754746D01*
X3234311Y753496D01*
X3234466Y752037D01*
X3234311Y750787D01*
X3233691Y749537D01*
X3232761Y748496D01*
X3231676Y748079D01*
X3230436Y748496D01*
X3229351Y749745D01*
X3228731Y751621D01*
X3228576Y753704D01*
X3228886Y756412D01*
X3229351Y757871D01*
X3230126Y759329D01*
X3231211Y760371D01*
X3232296Y760579D01*
X3233381Y760162D01*
X3234156Y759121D01*
G01X3105816Y1225046D02*
X3109536D01*
G01X3107521Y1227754D02*
Y1222337D01*
G01X3119921Y1220879D02*
Y1233379D01*
X3118061Y1230879D01*
G01Y1220879D02*
X3121781D01*
G01X3132321Y1220462D02*
X3132011Y1220671D01*
Y1221087D01*
X3132321Y1221296D01*
X3132631Y1221087D01*
Y1220671D01*
X3132321Y1220462D01*
G01X3142086Y1222337D02*
X3143171Y1221296D01*
X3144411Y1220879D01*
X3145651Y1221296D01*
X3146736Y1222545D01*
X3147511Y1224421D01*
X3147821Y1226296D01*
Y1228587D01*
X3147511Y1230462D01*
X3146736Y1232129D01*
X3145806Y1232962D01*
X3144721Y1233379D01*
X3143481Y1232962D01*
X3142551Y1232129D01*
X3141931Y1230879D01*
X3141621Y1229212D01*
X3141931Y1227754D01*
X3142706Y1226296D01*
X3143636Y1225462D01*
X3144721Y1225254D01*
X3145961Y1225670D01*
X3146891Y1226712D01*
X3147821Y1228587D01*
G01X3154176Y1226087D02*
X3155261Y1227546D01*
X3156191Y1228379D01*
X3157431Y1228796D01*
X3158516Y1228379D01*
X3159291Y1227546D01*
X3159911Y1226296D01*
X3160066Y1224837D01*
X3159911Y1223587D01*
X3159291Y1222337D01*
X3158361Y1221296D01*
X3157276Y1220879D01*
X3156036Y1221296D01*
X3154951Y1222545D01*
X3154331Y1224421D01*
X3154176Y1226504D01*
X3154486Y1229212D01*
X3154951Y1230671D01*
X3155726Y1232129D01*
X3156811Y1233171D01*
X3157896Y1233379D01*
X3158981Y1232962D01*
X3159756Y1231921D01*
G01X3166731Y1220462D02*
X3172311Y1233379D01*
G01X3179906Y1225046D02*
X3183936D01*
G01X3194321Y1220879D02*
Y1233379D01*
X3192461Y1230879D01*
G01Y1220879D02*
X3196181D01*
G01X3206721Y1220462D02*
X3206411Y1220671D01*
Y1221087D01*
X3206721Y1221296D01*
X3207031Y1221087D01*
Y1220671D01*
X3206721Y1220462D01*
G01X3216486Y1222337D02*
X3217571Y1221296D01*
X3218811Y1220879D01*
X3220051Y1221296D01*
X3221136Y1222545D01*
X3221911Y1224421D01*
X3222221Y1226296D01*
Y1228587D01*
X3221911Y1230462D01*
X3221136Y1232129D01*
X3220206Y1232962D01*
X3219121Y1233379D01*
X3217881Y1232962D01*
X3216951Y1232129D01*
X3216331Y1230879D01*
X3216021Y1229212D01*
X3216331Y1227754D01*
X3217106Y1226296D01*
X3218036Y1225462D01*
X3219121Y1225254D01*
X3220361Y1225670D01*
X3221291Y1226712D01*
X3222221Y1228587D01*
G01X3228576Y1226087D02*
X3229661Y1227546D01*
X3230591Y1228379D01*
X3231831Y1228796D01*
X3232916Y1228379D01*
X3233691Y1227546D01*
X3234311Y1226296D01*
X3234466Y1224837D01*
X3234311Y1223587D01*
X3233691Y1222337D01*
X3232761Y1221296D01*
X3231676Y1220879D01*
X3230436Y1221296D01*
X3229351Y1222545D01*
X3228731Y1224421D01*
X3228576Y1226504D01*
X3228886Y1229212D01*
X3229351Y1230671D01*
X3230126Y1232129D01*
X3231211Y1233171D01*
X3232296Y1233379D01*
X3233381Y1232962D01*
X3234156Y1231921D01*
G01X3105816Y1520546D02*
X3109536D01*
G01X3107521Y1523254D02*
Y1517837D01*
G01X3119921Y1516379D02*
Y1528879D01*
X3118061Y1526379D01*
G01Y1516379D02*
X3121781D01*
G01X3132321Y1515962D02*
X3132011Y1516171D01*
Y1516587D01*
X3132321Y1516796D01*
X3132631Y1516587D01*
Y1516171D01*
X3132321Y1515962D01*
G01X3142086Y1517837D02*
X3143171Y1516796D01*
X3144411Y1516379D01*
X3145651Y1516796D01*
X3146736Y1518045D01*
X3147511Y1519921D01*
X3147821Y1521796D01*
Y1524087D01*
X3147511Y1525962D01*
X3146736Y1527629D01*
X3145806Y1528462D01*
X3144721Y1528879D01*
X3143481Y1528462D01*
X3142551Y1527629D01*
X3141931Y1526379D01*
X3141621Y1524712D01*
X3141931Y1523254D01*
X3142706Y1521796D01*
X3143636Y1520962D01*
X3144721Y1520754D01*
X3145961Y1521170D01*
X3146891Y1522212D01*
X3147821Y1524087D01*
G01X3154176Y1521587D02*
X3155261Y1523046D01*
X3156191Y1523879D01*
X3157431Y1524296D01*
X3158516Y1523879D01*
X3159291Y1523046D01*
X3159911Y1521796D01*
X3160066Y1520337D01*
X3159911Y1519087D01*
X3159291Y1517837D01*
X3158361Y1516796D01*
X3157276Y1516379D01*
X3156036Y1516796D01*
X3154951Y1518045D01*
X3154331Y1519921D01*
X3154176Y1522004D01*
X3154486Y1524712D01*
X3154951Y1526171D01*
X3155726Y1527629D01*
X3156811Y1528671D01*
X3157896Y1528879D01*
X3158981Y1528462D01*
X3159756Y1527421D01*
G01X3166731Y1515962D02*
X3172311Y1528879D01*
G01X3179906Y1520546D02*
X3183936D01*
G01X3194321Y1516379D02*
Y1528879D01*
X3192461Y1526379D01*
G01Y1516379D02*
X3196181D01*
G01X3206721Y1515962D02*
X3206411Y1516171D01*
Y1516587D01*
X3206721Y1516796D01*
X3207031Y1516587D01*
Y1516171D01*
X3206721Y1515962D01*
G01X3216486Y1517837D02*
X3217571Y1516796D01*
X3218811Y1516379D01*
X3220051Y1516796D01*
X3221136Y1518045D01*
X3221911Y1519921D01*
X3222221Y1521796D01*
Y1524087D01*
X3221911Y1525962D01*
X3221136Y1527629D01*
X3220206Y1528462D01*
X3219121Y1528879D01*
X3217881Y1528462D01*
X3216951Y1527629D01*
X3216331Y1526379D01*
X3216021Y1524712D01*
X3216331Y1523254D01*
X3217106Y1521796D01*
X3218036Y1520962D01*
X3219121Y1520754D01*
X3220361Y1521170D01*
X3221291Y1522212D01*
X3222221Y1524087D01*
G01X3228576Y1521587D02*
X3229661Y1523046D01*
X3230591Y1523879D01*
X3231831Y1524296D01*
X3232916Y1523879D01*
X3233691Y1523046D01*
X3234311Y1521796D01*
X3234466Y1520337D01*
X3234311Y1519087D01*
X3233691Y1517837D01*
X3232761Y1516796D01*
X3231676Y1516379D01*
X3230436Y1516796D01*
X3229351Y1518045D01*
X3228731Y1519921D01*
X3228576Y1522004D01*
X3228886Y1524712D01*
X3229351Y1526171D01*
X3230126Y1527629D01*
X3231211Y1528671D01*
X3232296Y1528879D01*
X3233381Y1528462D01*
X3234156Y1527421D01*
G01X3105816Y1638746D02*
X3109536D01*
G01X3107521Y1641454D02*
Y1636037D01*
G01X3119921Y1634579D02*
Y1647079D01*
X3118061Y1644579D01*
G01Y1634579D02*
X3121781D01*
G01X3132321Y1634162D02*
X3132011Y1634371D01*
Y1634787D01*
X3132321Y1634996D01*
X3132631Y1634787D01*
Y1634371D01*
X3132321Y1634162D01*
G01X3142086Y1636037D02*
X3143171Y1634996D01*
X3144411Y1634579D01*
X3145651Y1634996D01*
X3146736Y1636245D01*
X3147511Y1638121D01*
X3147821Y1639996D01*
Y1642287D01*
X3147511Y1644162D01*
X3146736Y1645829D01*
X3145806Y1646662D01*
X3144721Y1647079D01*
X3143481Y1646662D01*
X3142551Y1645829D01*
X3141931Y1644579D01*
X3141621Y1642912D01*
X3141931Y1641454D01*
X3142706Y1639996D01*
X3143636Y1639162D01*
X3144721Y1638954D01*
X3145961Y1639370D01*
X3146891Y1640412D01*
X3147821Y1642287D01*
G01X3154176Y1639787D02*
X3155261Y1641246D01*
X3156191Y1642079D01*
X3157431Y1642496D01*
X3158516Y1642079D01*
X3159291Y1641246D01*
X3159911Y1639996D01*
X3160066Y1638537D01*
X3159911Y1637287D01*
X3159291Y1636037D01*
X3158361Y1634996D01*
X3157276Y1634579D01*
X3156036Y1634996D01*
X3154951Y1636245D01*
X3154331Y1638121D01*
X3154176Y1640204D01*
X3154486Y1642912D01*
X3154951Y1644371D01*
X3155726Y1645829D01*
X3156811Y1646871D01*
X3157896Y1647079D01*
X3158981Y1646662D01*
X3159756Y1645621D01*
G01X3166731Y1634162D02*
X3172311Y1647079D01*
G01X3179906Y1638746D02*
X3183936D01*
G01X3194321Y1634579D02*
Y1647079D01*
X3192461Y1644579D01*
G01Y1634579D02*
X3196181D01*
G01X3206721Y1634162D02*
X3206411Y1634371D01*
Y1634787D01*
X3206721Y1634996D01*
X3207031Y1634787D01*
Y1634371D01*
X3206721Y1634162D01*
G01X3216486Y1636037D02*
X3217571Y1634996D01*
X3218811Y1634579D01*
X3220051Y1634996D01*
X3221136Y1636245D01*
X3221911Y1638121D01*
X3222221Y1639996D01*
Y1642287D01*
X3221911Y1644162D01*
X3221136Y1645829D01*
X3220206Y1646662D01*
X3219121Y1647079D01*
X3217881Y1646662D01*
X3216951Y1645829D01*
X3216331Y1644579D01*
X3216021Y1642912D01*
X3216331Y1641454D01*
X3217106Y1639996D01*
X3218036Y1639162D01*
X3219121Y1638954D01*
X3220361Y1639370D01*
X3221291Y1640412D01*
X3222221Y1642287D01*
G01X3228576Y1639787D02*
X3229661Y1641246D01*
X3230591Y1642079D01*
X3231831Y1642496D01*
X3232916Y1642079D01*
X3233691Y1641246D01*
X3234311Y1639996D01*
X3234466Y1638537D01*
X3234311Y1637287D01*
X3233691Y1636037D01*
X3232761Y1634996D01*
X3231676Y1634579D01*
X3230436Y1634996D01*
X3229351Y1636245D01*
X3228731Y1638121D01*
X3228576Y1640204D01*
X3228886Y1642912D01*
X3229351Y1644371D01*
X3230126Y1645829D01*
X3231211Y1646871D01*
X3232296Y1647079D01*
X3233381Y1646662D01*
X3234156Y1645621D01*
G01X3105816Y1697846D02*
X3109536D01*
G01X3107521Y1700554D02*
Y1695137D01*
G01X3119921Y1693679D02*
Y1706179D01*
X3118061Y1703679D01*
G01Y1693679D02*
X3121781D01*
G01X3132321Y1693262D02*
X3132011Y1693471D01*
Y1693887D01*
X3132321Y1694096D01*
X3132631Y1693887D01*
Y1693471D01*
X3132321Y1693262D01*
G01X3142086Y1695137D02*
X3143171Y1694096D01*
X3144411Y1693679D01*
X3145651Y1694096D01*
X3146736Y1695345D01*
X3147511Y1697221D01*
X3147821Y1699096D01*
Y1701387D01*
X3147511Y1703262D01*
X3146736Y1704929D01*
X3145806Y1705762D01*
X3144721Y1706179D01*
X3143481Y1705762D01*
X3142551Y1704929D01*
X3141931Y1703679D01*
X3141621Y1702012D01*
X3141931Y1700554D01*
X3142706Y1699096D01*
X3143636Y1698262D01*
X3144721Y1698054D01*
X3145961Y1698470D01*
X3146891Y1699512D01*
X3147821Y1701387D01*
G01X3154176Y1698887D02*
X3155261Y1700346D01*
X3156191Y1701179D01*
X3157431Y1701596D01*
X3158516Y1701179D01*
X3159291Y1700346D01*
X3159911Y1699096D01*
X3160066Y1697637D01*
X3159911Y1696387D01*
X3159291Y1695137D01*
X3158361Y1694096D01*
X3157276Y1693679D01*
X3156036Y1694096D01*
X3154951Y1695345D01*
X3154331Y1697221D01*
X3154176Y1699304D01*
X3154486Y1702012D01*
X3154951Y1703471D01*
X3155726Y1704929D01*
X3156811Y1705971D01*
X3157896Y1706179D01*
X3158981Y1705762D01*
X3159756Y1704721D01*
G01X3166731Y1693262D02*
X3172311Y1706179D01*
G01X3179906Y1697846D02*
X3183936D01*
G01X3194321Y1693679D02*
Y1706179D01*
X3192461Y1703679D01*
G01Y1693679D02*
X3196181D01*
G01X3206721Y1693262D02*
X3206411Y1693471D01*
Y1693887D01*
X3206721Y1694096D01*
X3207031Y1693887D01*
Y1693471D01*
X3206721Y1693262D01*
G01X3216486Y1695137D02*
X3217571Y1694096D01*
X3218811Y1693679D01*
X3220051Y1694096D01*
X3221136Y1695345D01*
X3221911Y1697221D01*
X3222221Y1699096D01*
Y1701387D01*
X3221911Y1703262D01*
X3221136Y1704929D01*
X3220206Y1705762D01*
X3219121Y1706179D01*
X3217881Y1705762D01*
X3216951Y1704929D01*
X3216331Y1703679D01*
X3216021Y1702012D01*
X3216331Y1700554D01*
X3217106Y1699096D01*
X3218036Y1698262D01*
X3219121Y1698054D01*
X3220361Y1698470D01*
X3221291Y1699512D01*
X3222221Y1701387D01*
G01X3228576Y1698887D02*
X3229661Y1700346D01*
X3230591Y1701179D01*
X3231831Y1701596D01*
X3232916Y1701179D01*
X3233691Y1700346D01*
X3234311Y1699096D01*
X3234466Y1697637D01*
X3234311Y1696387D01*
X3233691Y1695137D01*
X3232761Y1694096D01*
X3231676Y1693679D01*
X3230436Y1694096D01*
X3229351Y1695345D01*
X3228731Y1697221D01*
X3228576Y1699304D01*
X3228886Y1702012D01*
X3229351Y1703471D01*
X3230126Y1704929D01*
X3231211Y1705971D01*
X3232296Y1706179D01*
X3233381Y1705762D01*
X3234156Y1704721D01*
G01X3098996Y2056229D02*
X3102871Y2068729D01*
X3106746Y2056229D01*
G01X3105351Y2060604D02*
X3100391D01*
G01X3112171Y2068729D02*
Y2056229D01*
X3118371D01*
G01X3124571Y2068729D02*
Y2056229D01*
X3130771D01*
G01X3149061Y2068729D02*
Y2059771D01*
X3149681Y2057895D01*
X3150921Y2056646D01*
X3152471Y2056229D01*
X3154021Y2056646D01*
X3155261Y2057895D01*
X3155881Y2059771D01*
Y2068729D01*
G01X3161306Y2056229D02*
Y2068729D01*
X3168436Y2056229D01*
Y2068729D01*
G01X3175411D02*
X3179131D01*
G01X3177271D02*
Y2056229D01*
G01X3175411D02*
X3179131D01*
G01X3189671Y2068729D02*
Y2056229D01*
G01X3186106Y2068729D02*
X3193236D01*
G01X3198816Y2057895D02*
X3200056Y2056854D01*
X3201451Y2056229D01*
X3202691D01*
X3203931Y2056854D01*
X3204861Y2057895D01*
X3205326Y2059354D01*
X3205016Y2060812D01*
X3204241Y2062062D01*
X3202846Y2062896D01*
X3200986Y2063312D01*
X3199901Y2064146D01*
X3199436Y2065604D01*
X3199746Y2067062D01*
X3200521Y2068104D01*
X3201606Y2068729D01*
X3202691D01*
X3203776Y2068312D01*
X3204706Y2067271D01*
G01X3222996Y2056229D02*
X3226871Y2068729D01*
X3230746Y2056229D01*
G01X3229351Y2060604D02*
X3224391D01*
G01X3236171Y2056229D02*
Y2068729D01*
X3240046D01*
X3241286Y2068104D01*
X3242061Y2067271D01*
X3242371Y2065604D01*
X3242061Y2063937D01*
X3241131Y2062896D01*
X3240046Y2062271D01*
X3236171D01*
G01X3240046D02*
X3242371Y2056229D01*
G01X3254771D02*
X3248571D01*
Y2068729D01*
X3254771D01*
G01X3252291Y2062687D02*
X3248571D01*
G01X3274611Y2068729D02*
X3278331D01*
G01X3276471D02*
Y2056229D01*
G01X3274611D02*
X3278331D01*
G01X3285306D02*
Y2068729D01*
X3292436Y2056229D01*
Y2068729D01*
G01X3309641Y2056229D02*
Y2068729D01*
X3313671Y2058312D01*
X3317701Y2068729D01*
Y2056229D01*
G01X3324211Y2068729D02*
X3327931D01*
G01X3326071D02*
Y2056229D01*
G01X3324211D02*
X3327931D01*
G01X3335371Y2068729D02*
Y2056229D01*
X3341571D01*
G01X3347616Y2057895D02*
X3348856Y2056854D01*
X3350251Y2056229D01*
X3351491D01*
X3352731Y2056854D01*
X3353661Y2057895D01*
X3354126Y2059354D01*
X3353816Y2060812D01*
X3353041Y2062062D01*
X3351646Y2062896D01*
X3349786Y2063312D01*
X3348701Y2064146D01*
X3348236Y2065604D01*
X3348546Y2067062D01*
X3349321Y2068104D01*
X3350406Y2068729D01*
X3351491D01*
X3352576Y2068312D01*
X3353506Y2067271D01*
G01X3090370Y2622932D02*
X3094090D01*
G01X3092230D02*
Y2610432D01*
G01X3090370D02*
X3094090D01*
G01X3101065D02*
Y2622932D01*
X3108195Y2610432D01*
Y2622932D01*
G01X3113620Y2612307D02*
X3114550Y2611265D01*
X3115635Y2610640D01*
X3117030Y2610432D01*
X3118425Y2610849D01*
X3119510Y2611682D01*
X3120285Y2613140D01*
X3120440Y2614807D01*
X3120130Y2616474D01*
X3119355Y2617515D01*
X3118270Y2618349D01*
X3117185Y2618557D01*
X3116100Y2618349D01*
X3114705Y2617515D01*
X3115170Y2622932D01*
X3119355D01*
G01X3091366Y2886849D02*
X3095086D01*
G01X3093226D02*
Y2874349D01*
G01X3091366D02*
X3095086D01*
G01X3102061D02*
Y2886849D01*
X3109191Y2874349D01*
Y2886849D01*
G01X3114616Y2876849D02*
X3115546Y2875390D01*
X3116786Y2874557D01*
X3118181Y2874349D01*
X3119421Y2874557D01*
X3120661Y2875599D01*
X3121436Y2876849D01*
X3121591Y2878099D01*
X3121281Y2879557D01*
X3120196Y2880599D01*
X3119111Y2881016D01*
X3117716D01*
G01X3119111D02*
X3120041Y2881641D01*
X3120816Y2882682D01*
X3121126Y2883932D01*
X3120816Y2885182D01*
X3120041Y2886224D01*
X3118646Y2886849D01*
X3117251Y2886641D01*
X3115856Y2885807D01*
G01X3091366Y2911849D02*
X3095086D01*
G01X3093226D02*
Y2899349D01*
G01X3091366D02*
X3095086D01*
G01X3102061D02*
Y2911849D01*
X3109191Y2899349D01*
Y2911849D01*
G01X3114616Y2901849D02*
X3115546Y2900390D01*
X3116786Y2899557D01*
X3118181Y2899349D01*
X3119421Y2899557D01*
X3120661Y2900599D01*
X3121436Y2901849D01*
X3121591Y2903099D01*
X3121281Y2904557D01*
X3120196Y2905599D01*
X3119111Y2906016D01*
X3117716D01*
G01X3119111D02*
X3120041Y2906641D01*
X3120816Y2907682D01*
X3121126Y2908932D01*
X3120816Y2910182D01*
X3120041Y2911224D01*
X3118646Y2911849D01*
X3117251Y2911641D01*
X3115856Y2910807D01*
G01X3091376Y3137419D02*
X3095096D01*
G01X3093236D02*
Y3124919D01*
G01X3091376D02*
X3095096D01*
G01X3102071D02*
Y3137419D01*
X3109201Y3124919D01*
Y3137419D01*
G01X3115091Y3135336D02*
X3116021Y3136585D01*
X3117106Y3137211D01*
X3118346Y3137419D01*
X3119896Y3137002D01*
X3120981Y3135961D01*
X3121291Y3134711D01*
X3121136Y3133460D01*
X3120516Y3132419D01*
X3117416Y3130336D01*
X3116021Y3128877D01*
X3115091Y3126794D01*
X3114781Y3124919D01*
X3121291D01*
G01X3091376Y3162419D02*
X3095096D01*
G01X3093236D02*
Y3149919D01*
G01X3091376D02*
X3095096D01*
G01X3102071D02*
Y3162419D01*
X3109201Y3149919D01*
Y3162419D01*
G01X3115091Y3160336D02*
X3116021Y3161585D01*
X3117106Y3162211D01*
X3118346Y3162419D01*
X3119896Y3162002D01*
X3120981Y3160961D01*
X3121291Y3159711D01*
X3121136Y3158460D01*
X3120516Y3157419D01*
X3117416Y3155336D01*
X3116021Y3153877D01*
X3115091Y3151794D01*
X3114781Y3149919D01*
X3121291D01*
G01X3092135Y3653887D02*
X3095855D01*
G01X3093995D02*
Y3641387D01*
G01X3092135D02*
X3095855D01*
G01X3102830D02*
Y3653887D01*
X3109960Y3641387D01*
Y3653887D01*
G01X3120655Y3641387D02*
Y3653887D01*
X3114920Y3644929D01*
X3122670D01*
G01X3092135Y3678887D02*
X3095855D01*
G01X3093995D02*
Y3666387D01*
G01X3092135D02*
X3095855D01*
G01X3102830D02*
Y3678887D01*
X3109960Y3666387D01*
Y3678887D01*
G01X3120655Y3666387D02*
Y3678887D01*
X3114920Y3669929D01*
X3122670D01*
G01X3092135Y3703887D02*
X3095855D01*
G01X3093995D02*
Y3691387D01*
G01X3092135D02*
X3095855D01*
G01X3102830D02*
Y3703887D01*
X3109960Y3691387D01*
Y3703887D01*
G01X3120655Y3691387D02*
Y3703887D01*
X3114920Y3694929D01*
X3122670D01*
G01X3118216Y-193354D02*
X3121936D01*
G01X3119921Y-190646D02*
Y-196063D01*
G01X3134181Y-197521D02*
Y-185021D01*
X3128446Y-193979D01*
X3136196D01*
G01X3144721Y-197938D02*
X3144411Y-197729D01*
Y-197313D01*
X3144721Y-197104D01*
X3145031Y-197313D01*
Y-197729D01*
X3144721Y-197938D01*
G01X3157121Y-185021D02*
X3155881Y-185438D01*
X3154951Y-186479D01*
X3154331Y-187729D01*
X3153866Y-189396D01*
X3153711Y-191271D01*
X3153866Y-193146D01*
X3154331Y-194813D01*
X3154951Y-196063D01*
X3155881Y-197104D01*
X3157121Y-197521D01*
X3158361Y-197104D01*
X3159291Y-196063D01*
X3159911Y-194813D01*
X3160376Y-193146D01*
X3160531Y-191271D01*
X3160376Y-189396D01*
X3159911Y-187729D01*
X3159291Y-186479D01*
X3158361Y-185438D01*
X3157121Y-185021D01*
G01X3166731Y-197938D02*
X3172311Y-185021D01*
G01X3179906Y-193354D02*
X3183936D01*
G01X3196181Y-197521D02*
Y-185021D01*
X3190446Y-193979D01*
X3198196D01*
G01X3206721Y-197938D02*
X3206411Y-197729D01*
Y-197313D01*
X3206721Y-197104D01*
X3207031Y-197313D01*
Y-197729D01*
X3206721Y-197938D01*
G01X3219121Y-185021D02*
X3217881Y-185438D01*
X3216951Y-186479D01*
X3216331Y-187729D01*
X3215866Y-189396D01*
X3215711Y-191271D01*
X3215866Y-193146D01*
X3216331Y-194813D01*
X3216951Y-196063D01*
X3217881Y-197104D01*
X3219121Y-197521D01*
X3220361Y-197104D01*
X3221291Y-196063D01*
X3221911Y-194813D01*
X3222376Y-193146D01*
X3222531Y-191271D01*
X3222376Y-189396D01*
X3221911Y-187729D01*
X3221291Y-186479D01*
X3220361Y-185438D01*
X3219121Y-185021D01*
G01X3118216Y-134254D02*
X3121936D01*
G01X3119921Y-131546D02*
Y-136963D01*
G01X3134181Y-138421D02*
Y-125921D01*
X3128446Y-134879D01*
X3136196D01*
G01X3144721Y-138838D02*
X3144411Y-138629D01*
Y-138213D01*
X3144721Y-138004D01*
X3145031Y-138213D01*
Y-138629D01*
X3144721Y-138838D01*
G01X3157121Y-125921D02*
X3155881Y-126338D01*
X3154951Y-127379D01*
X3154331Y-128629D01*
X3153866Y-130296D01*
X3153711Y-132171D01*
X3153866Y-134046D01*
X3154331Y-135713D01*
X3154951Y-136963D01*
X3155881Y-138004D01*
X3157121Y-138421D01*
X3158361Y-138004D01*
X3159291Y-136963D01*
X3159911Y-135713D01*
X3160376Y-134046D01*
X3160531Y-132171D01*
X3160376Y-130296D01*
X3159911Y-128629D01*
X3159291Y-127379D01*
X3158361Y-126338D01*
X3157121Y-125921D01*
G01X3166731Y-138838D02*
X3172311Y-125921D01*
G01X3179906Y-134254D02*
X3183936D01*
G01X3196181Y-138421D02*
Y-125921D01*
X3190446Y-134879D01*
X3198196D01*
G01X3206721Y-138838D02*
X3206411Y-138629D01*
Y-138213D01*
X3206721Y-138004D01*
X3207031Y-138213D01*
Y-138629D01*
X3206721Y-138838D01*
G01X3219121Y-125921D02*
X3217881Y-126338D01*
X3216951Y-127379D01*
X3216331Y-128629D01*
X3215866Y-130296D01*
X3215711Y-132171D01*
X3215866Y-134046D01*
X3216331Y-135713D01*
X3216951Y-136963D01*
X3217881Y-138004D01*
X3219121Y-138421D01*
X3220361Y-138004D01*
X3221291Y-136963D01*
X3221911Y-135713D01*
X3222376Y-134046D01*
X3222531Y-132171D01*
X3222376Y-130296D01*
X3221911Y-128629D01*
X3221291Y-127379D01*
X3220361Y-126338D01*
X3219121Y-125921D01*
G01X3118216Y43046D02*
X3121936D01*
G01X3119921Y45754D02*
Y40337D01*
G01X3134181Y38879D02*
Y51379D01*
X3128446Y42421D01*
X3136196D01*
G01X3144721Y38462D02*
X3144411Y38671D01*
Y39087D01*
X3144721Y39296D01*
X3145031Y39087D01*
Y38671D01*
X3144721Y38462D01*
G01X3157121Y51379D02*
X3155881Y50962D01*
X3154951Y49921D01*
X3154331Y48671D01*
X3153866Y47004D01*
X3153711Y45129D01*
X3153866Y43254D01*
X3154331Y41587D01*
X3154951Y40337D01*
X3155881Y39296D01*
X3157121Y38879D01*
X3158361Y39296D01*
X3159291Y40337D01*
X3159911Y41587D01*
X3160376Y43254D01*
X3160531Y45129D01*
X3160376Y47004D01*
X3159911Y48671D01*
X3159291Y49921D01*
X3158361Y50962D01*
X3157121Y51379D01*
G01X3166731Y38462D02*
X3172311Y51379D01*
G01X3179906Y43046D02*
X3183936D01*
G01X3196181Y38879D02*
Y51379D01*
X3190446Y42421D01*
X3198196D01*
G01X3206721Y38462D02*
X3206411Y38671D01*
Y39087D01*
X3206721Y39296D01*
X3207031Y39087D01*
Y38671D01*
X3206721Y38462D01*
G01X3219121Y51379D02*
X3217881Y50962D01*
X3216951Y49921D01*
X3216331Y48671D01*
X3215866Y47004D01*
X3215711Y45129D01*
X3215866Y43254D01*
X3216331Y41587D01*
X3216951Y40337D01*
X3217881Y39296D01*
X3219121Y38879D01*
X3220361Y39296D01*
X3221291Y40337D01*
X3221911Y41587D01*
X3222376Y43254D01*
X3222531Y45129D01*
X3222376Y47004D01*
X3221911Y48671D01*
X3221291Y49921D01*
X3220361Y50962D01*
X3219121Y51379D01*
G01X3118216Y102146D02*
X3121936D01*
G01X3119921Y104854D02*
Y99437D01*
G01X3129376Y108396D02*
X3130306Y109645D01*
X3131391Y110271D01*
X3132631Y110479D01*
X3134181Y110062D01*
X3135266Y109021D01*
X3135576Y107771D01*
X3135421Y106520D01*
X3134801Y105479D01*
X3131701Y103396D01*
X3130306Y101937D01*
X3129376Y99854D01*
X3129066Y97979D01*
X3135576D01*
G01X3144721Y97562D02*
X3144411Y97771D01*
Y98187D01*
X3144721Y98396D01*
X3145031Y98187D01*
Y97771D01*
X3144721Y97562D01*
G01X3157121Y110479D02*
X3155881Y110062D01*
X3154951Y109021D01*
X3154331Y107771D01*
X3153866Y106104D01*
X3153711Y104229D01*
X3153866Y102354D01*
X3154331Y100687D01*
X3154951Y99437D01*
X3155881Y98396D01*
X3157121Y97979D01*
X3158361Y98396D01*
X3159291Y99437D01*
X3159911Y100687D01*
X3160376Y102354D01*
X3160531Y104229D01*
X3160376Y106104D01*
X3159911Y107771D01*
X3159291Y109021D01*
X3158361Y110062D01*
X3157121Y110479D01*
G01X3166731Y97562D02*
X3172311Y110479D01*
G01X3179906Y102146D02*
X3183936D01*
G01X3191376Y108396D02*
X3192306Y109645D01*
X3193391Y110271D01*
X3194631Y110479D01*
X3196181Y110062D01*
X3197266Y109021D01*
X3197576Y107771D01*
X3197421Y106520D01*
X3196801Y105479D01*
X3193701Y103396D01*
X3192306Y101937D01*
X3191376Y99854D01*
X3191066Y97979D01*
X3197576D01*
G01X3206721Y97562D02*
X3206411Y97771D01*
Y98187D01*
X3206721Y98396D01*
X3207031Y98187D01*
Y97771D01*
X3206721Y97562D01*
G01X3219121Y110479D02*
X3217881Y110062D01*
X3216951Y109021D01*
X3216331Y107771D01*
X3215866Y106104D01*
X3215711Y104229D01*
X3215866Y102354D01*
X3216331Y100687D01*
X3216951Y99437D01*
X3217881Y98396D01*
X3219121Y97979D01*
X3220361Y98396D01*
X3221291Y99437D01*
X3221911Y100687D01*
X3222376Y102354D01*
X3222531Y104229D01*
X3222376Y106104D01*
X3221911Y107771D01*
X3221291Y109021D01*
X3220361Y110062D01*
X3219121Y110479D01*
G01X3118216Y161246D02*
X3121936D01*
G01X3119921Y163954D02*
Y158537D01*
G01X3129376Y167496D02*
X3130306Y168745D01*
X3131391Y169371D01*
X3132631Y169579D01*
X3134181Y169162D01*
X3135266Y168121D01*
X3135576Y166871D01*
X3135421Y165620D01*
X3134801Y164579D01*
X3131701Y162496D01*
X3130306Y161037D01*
X3129376Y158954D01*
X3129066Y157079D01*
X3135576D01*
G01X3144721Y156662D02*
X3144411Y156871D01*
Y157287D01*
X3144721Y157496D01*
X3145031Y157287D01*
Y156871D01*
X3144721Y156662D01*
G01X3157121Y169579D02*
X3155881Y169162D01*
X3154951Y168121D01*
X3154331Y166871D01*
X3153866Y165204D01*
X3153711Y163329D01*
X3153866Y161454D01*
X3154331Y159787D01*
X3154951Y158537D01*
X3155881Y157496D01*
X3157121Y157079D01*
X3158361Y157496D01*
X3159291Y158537D01*
X3159911Y159787D01*
X3160376Y161454D01*
X3160531Y163329D01*
X3160376Y165204D01*
X3159911Y166871D01*
X3159291Y168121D01*
X3158361Y169162D01*
X3157121Y169579D01*
G01X3166731Y156662D02*
X3172311Y169579D01*
G01X3179906Y161246D02*
X3183936D01*
G01X3191376Y167496D02*
X3192306Y168745D01*
X3193391Y169371D01*
X3194631Y169579D01*
X3196181Y169162D01*
X3197266Y168121D01*
X3197576Y166871D01*
X3197421Y165620D01*
X3196801Y164579D01*
X3193701Y162496D01*
X3192306Y161037D01*
X3191376Y158954D01*
X3191066Y157079D01*
X3197576D01*
G01X3206721Y156662D02*
X3206411Y156871D01*
Y157287D01*
X3206721Y157496D01*
X3207031Y157287D01*
Y156871D01*
X3206721Y156662D01*
G01X3219121Y169579D02*
X3217881Y169162D01*
X3216951Y168121D01*
X3216331Y166871D01*
X3215866Y165204D01*
X3215711Y163329D01*
X3215866Y161454D01*
X3216331Y159787D01*
X3216951Y158537D01*
X3217881Y157496D01*
X3219121Y157079D01*
X3220361Y157496D01*
X3221291Y158537D01*
X3221911Y159787D01*
X3222376Y161454D01*
X3222531Y163329D01*
X3222376Y165204D01*
X3221911Y166871D01*
X3221291Y168121D01*
X3220361Y169162D01*
X3219121Y169579D01*
G01X3118216Y220346D02*
X3121936D01*
G01X3119921Y223054D02*
Y217637D01*
G01X3129376Y226596D02*
X3130306Y227845D01*
X3131391Y228471D01*
X3132631Y228679D01*
X3134181Y228262D01*
X3135266Y227221D01*
X3135576Y225971D01*
X3135421Y224720D01*
X3134801Y223679D01*
X3131701Y221596D01*
X3130306Y220137D01*
X3129376Y218054D01*
X3129066Y216179D01*
X3135576D01*
G01X3144721Y215762D02*
X3144411Y215971D01*
Y216387D01*
X3144721Y216596D01*
X3145031Y216387D01*
Y215971D01*
X3144721Y215762D01*
G01X3157121Y228679D02*
X3155881Y228262D01*
X3154951Y227221D01*
X3154331Y225971D01*
X3153866Y224304D01*
X3153711Y222429D01*
X3153866Y220554D01*
X3154331Y218887D01*
X3154951Y217637D01*
X3155881Y216596D01*
X3157121Y216179D01*
X3158361Y216596D01*
X3159291Y217637D01*
X3159911Y218887D01*
X3160376Y220554D01*
X3160531Y222429D01*
X3160376Y224304D01*
X3159911Y225971D01*
X3159291Y227221D01*
X3158361Y228262D01*
X3157121Y228679D01*
G01X3166731Y215762D02*
X3172311Y228679D01*
G01X3179906Y220346D02*
X3183936D01*
G01X3191376Y226596D02*
X3192306Y227845D01*
X3193391Y228471D01*
X3194631Y228679D01*
X3196181Y228262D01*
X3197266Y227221D01*
X3197576Y225971D01*
X3197421Y224720D01*
X3196801Y223679D01*
X3193701Y221596D01*
X3192306Y220137D01*
X3191376Y218054D01*
X3191066Y216179D01*
X3197576D01*
G01X3206721Y215762D02*
X3206411Y215971D01*
Y216387D01*
X3206721Y216596D01*
X3207031Y216387D01*
Y215971D01*
X3206721Y215762D01*
G01X3219121Y228679D02*
X3217881Y228262D01*
X3216951Y227221D01*
X3216331Y225971D01*
X3215866Y224304D01*
X3215711Y222429D01*
X3215866Y220554D01*
X3216331Y218887D01*
X3216951Y217637D01*
X3217881Y216596D01*
X3219121Y216179D01*
X3220361Y216596D01*
X3221291Y217637D01*
X3221911Y218887D01*
X3222376Y220554D01*
X3222531Y222429D01*
X3222376Y224304D01*
X3221911Y225971D01*
X3221291Y227221D01*
X3220361Y228262D01*
X3219121Y228679D01*
G01X3118216Y279446D02*
X3121936D01*
G01X3119921Y282154D02*
Y276737D01*
G01X3129376Y285696D02*
X3130306Y286945D01*
X3131391Y287571D01*
X3132631Y287779D01*
X3134181Y287362D01*
X3135266Y286321D01*
X3135576Y285071D01*
X3135421Y283820D01*
X3134801Y282779D01*
X3131701Y280696D01*
X3130306Y279237D01*
X3129376Y277154D01*
X3129066Y275279D01*
X3135576D01*
G01X3144721Y274862D02*
X3144411Y275071D01*
Y275487D01*
X3144721Y275696D01*
X3145031Y275487D01*
Y275071D01*
X3144721Y274862D01*
G01X3157121Y287779D02*
X3155881Y287362D01*
X3154951Y286321D01*
X3154331Y285071D01*
X3153866Y283404D01*
X3153711Y281529D01*
X3153866Y279654D01*
X3154331Y277987D01*
X3154951Y276737D01*
X3155881Y275696D01*
X3157121Y275279D01*
X3158361Y275696D01*
X3159291Y276737D01*
X3159911Y277987D01*
X3160376Y279654D01*
X3160531Y281529D01*
X3160376Y283404D01*
X3159911Y285071D01*
X3159291Y286321D01*
X3158361Y287362D01*
X3157121Y287779D01*
G01X3166731Y274862D02*
X3172311Y287779D01*
G01X3179906Y279446D02*
X3183936D01*
G01X3191376Y285696D02*
X3192306Y286945D01*
X3193391Y287571D01*
X3194631Y287779D01*
X3196181Y287362D01*
X3197266Y286321D01*
X3197576Y285071D01*
X3197421Y283820D01*
X3196801Y282779D01*
X3193701Y280696D01*
X3192306Y279237D01*
X3191376Y277154D01*
X3191066Y275279D01*
X3197576D01*
G01X3206721Y274862D02*
X3206411Y275071D01*
Y275487D01*
X3206721Y275696D01*
X3207031Y275487D01*
Y275071D01*
X3206721Y274862D01*
G01X3219121Y287779D02*
X3217881Y287362D01*
X3216951Y286321D01*
X3216331Y285071D01*
X3215866Y283404D01*
X3215711Y281529D01*
X3215866Y279654D01*
X3216331Y277987D01*
X3216951Y276737D01*
X3217881Y275696D01*
X3219121Y275279D01*
X3220361Y275696D01*
X3221291Y276737D01*
X3221911Y277987D01*
X3222376Y279654D01*
X3222531Y281529D01*
X3222376Y283404D01*
X3221911Y285071D01*
X3221291Y286321D01*
X3220361Y287362D01*
X3219121Y287779D01*
G01X3118216Y338546D02*
X3121936D01*
G01X3119921Y341254D02*
Y335837D01*
G01X3129376Y344796D02*
X3130306Y346045D01*
X3131391Y346671D01*
X3132631Y346879D01*
X3134181Y346462D01*
X3135266Y345421D01*
X3135576Y344171D01*
X3135421Y342920D01*
X3134801Y341879D01*
X3131701Y339796D01*
X3130306Y338337D01*
X3129376Y336254D01*
X3129066Y334379D01*
X3135576D01*
G01X3144721Y333962D02*
X3144411Y334171D01*
Y334587D01*
X3144721Y334796D01*
X3145031Y334587D01*
Y334171D01*
X3144721Y333962D01*
G01X3157121Y346879D02*
X3155881Y346462D01*
X3154951Y345421D01*
X3154331Y344171D01*
X3153866Y342504D01*
X3153711Y340629D01*
X3153866Y338754D01*
X3154331Y337087D01*
X3154951Y335837D01*
X3155881Y334796D01*
X3157121Y334379D01*
X3158361Y334796D01*
X3159291Y335837D01*
X3159911Y337087D01*
X3160376Y338754D01*
X3160531Y340629D01*
X3160376Y342504D01*
X3159911Y344171D01*
X3159291Y345421D01*
X3158361Y346462D01*
X3157121Y346879D01*
G01X3166731Y333962D02*
X3172311Y346879D01*
G01X3179906Y338546D02*
X3183936D01*
G01X3194321Y346879D02*
X3193081Y346462D01*
X3192151Y345421D01*
X3191531Y344171D01*
X3191066Y342504D01*
X3190911Y340629D01*
X3191066Y338754D01*
X3191531Y337087D01*
X3192151Y335837D01*
X3193081Y334796D01*
X3194321Y334379D01*
X3195561Y334796D01*
X3196491Y335837D01*
X3197111Y337087D01*
X3197576Y338754D01*
X3197731Y340629D01*
X3197576Y342504D01*
X3197111Y344171D01*
X3196491Y345421D01*
X3195561Y346462D01*
X3194321Y346879D01*
G01X3206721Y333962D02*
X3206411Y334171D01*
Y334587D01*
X3206721Y334796D01*
X3207031Y334587D01*
Y334171D01*
X3206721Y333962D01*
G01X3219121Y346879D02*
X3217881Y346462D01*
X3216951Y345421D01*
X3216331Y344171D01*
X3215866Y342504D01*
X3215711Y340629D01*
X3215866Y338754D01*
X3216331Y337087D01*
X3216951Y335837D01*
X3217881Y334796D01*
X3219121Y334379D01*
X3220361Y334796D01*
X3221291Y335837D01*
X3221911Y337087D01*
X3222376Y338754D01*
X3222531Y340629D01*
X3222376Y342504D01*
X3221911Y344171D01*
X3221291Y345421D01*
X3220361Y346462D01*
X3219121Y346879D01*
G01X3118216Y397646D02*
X3121936D01*
G01X3119921Y400354D02*
Y394937D01*
G01X3129376Y403896D02*
X3130306Y405145D01*
X3131391Y405771D01*
X3132631Y405979D01*
X3134181Y405562D01*
X3135266Y404521D01*
X3135576Y403271D01*
X3135421Y402020D01*
X3134801Y400979D01*
X3131701Y398896D01*
X3130306Y397437D01*
X3129376Y395354D01*
X3129066Y393479D01*
X3135576D01*
G01X3144721Y393062D02*
X3144411Y393271D01*
Y393687D01*
X3144721Y393896D01*
X3145031Y393687D01*
Y393271D01*
X3144721Y393062D01*
G01X3157121Y405979D02*
X3155881Y405562D01*
X3154951Y404521D01*
X3154331Y403271D01*
X3153866Y401604D01*
X3153711Y399729D01*
X3153866Y397854D01*
X3154331Y396187D01*
X3154951Y394937D01*
X3155881Y393896D01*
X3157121Y393479D01*
X3158361Y393896D01*
X3159291Y394937D01*
X3159911Y396187D01*
X3160376Y397854D01*
X3160531Y399729D01*
X3160376Y401604D01*
X3159911Y403271D01*
X3159291Y404521D01*
X3158361Y405562D01*
X3157121Y405979D01*
G01X3166731Y393062D02*
X3172311Y405979D01*
G01X3179906Y397646D02*
X3183936D01*
G01X3191376Y403896D02*
X3192306Y405145D01*
X3193391Y405771D01*
X3194631Y405979D01*
X3196181Y405562D01*
X3197266Y404521D01*
X3197576Y403271D01*
X3197421Y402020D01*
X3196801Y400979D01*
X3193701Y398896D01*
X3192306Y397437D01*
X3191376Y395354D01*
X3191066Y393479D01*
X3197576D01*
G01X3206721Y393062D02*
X3206411Y393271D01*
Y393687D01*
X3206721Y393896D01*
X3207031Y393687D01*
Y393271D01*
X3206721Y393062D01*
G01X3219121Y405979D02*
X3217881Y405562D01*
X3216951Y404521D01*
X3216331Y403271D01*
X3215866Y401604D01*
X3215711Y399729D01*
X3215866Y397854D01*
X3216331Y396187D01*
X3216951Y394937D01*
X3217881Y393896D01*
X3219121Y393479D01*
X3220361Y393896D01*
X3221291Y394937D01*
X3221911Y396187D01*
X3222376Y397854D01*
X3222531Y399729D01*
X3222376Y401604D01*
X3221911Y403271D01*
X3221291Y404521D01*
X3220361Y405562D01*
X3219121Y405979D01*
G01X3118216Y456746D02*
X3121936D01*
G01X3119921Y459454D02*
Y454037D01*
G01X3129376Y462996D02*
X3130306Y464245D01*
X3131391Y464871D01*
X3132631Y465079D01*
X3134181Y464662D01*
X3135266Y463621D01*
X3135576Y462371D01*
X3135421Y461120D01*
X3134801Y460079D01*
X3131701Y457996D01*
X3130306Y456537D01*
X3129376Y454454D01*
X3129066Y452579D01*
X3135576D01*
G01X3144721Y452162D02*
X3144411Y452371D01*
Y452787D01*
X3144721Y452996D01*
X3145031Y452787D01*
Y452371D01*
X3144721Y452162D01*
G01X3157121Y465079D02*
X3155881Y464662D01*
X3154951Y463621D01*
X3154331Y462371D01*
X3153866Y460704D01*
X3153711Y458829D01*
X3153866Y456954D01*
X3154331Y455287D01*
X3154951Y454037D01*
X3155881Y452996D01*
X3157121Y452579D01*
X3158361Y452996D01*
X3159291Y454037D01*
X3159911Y455287D01*
X3160376Y456954D01*
X3160531Y458829D01*
X3160376Y460704D01*
X3159911Y462371D01*
X3159291Y463621D01*
X3158361Y464662D01*
X3157121Y465079D01*
G01X3166731Y452162D02*
X3172311Y465079D01*
G01X3179906Y456746D02*
X3183936D01*
G01X3191376Y462996D02*
X3192306Y464245D01*
X3193391Y464871D01*
X3194631Y465079D01*
X3196181Y464662D01*
X3197266Y463621D01*
X3197576Y462371D01*
X3197421Y461120D01*
X3196801Y460079D01*
X3193701Y457996D01*
X3192306Y456537D01*
X3191376Y454454D01*
X3191066Y452579D01*
X3197576D01*
G01X3206721Y452162D02*
X3206411Y452371D01*
Y452787D01*
X3206721Y452996D01*
X3207031Y452787D01*
Y452371D01*
X3206721Y452162D01*
G01X3219121Y465079D02*
X3217881Y464662D01*
X3216951Y463621D01*
X3216331Y462371D01*
X3215866Y460704D01*
X3215711Y458829D01*
X3215866Y456954D01*
X3216331Y455287D01*
X3216951Y454037D01*
X3217881Y452996D01*
X3219121Y452579D01*
X3220361Y452996D01*
X3221291Y454037D01*
X3221911Y455287D01*
X3222376Y456954D01*
X3222531Y458829D01*
X3222376Y460704D01*
X3221911Y462371D01*
X3221291Y463621D01*
X3220361Y464662D01*
X3219121Y465079D01*
G01X3118216Y515846D02*
X3121936D01*
G01X3119921Y518554D02*
Y513137D01*
G01X3129376Y522096D02*
X3130306Y523345D01*
X3131391Y523971D01*
X3132631Y524179D01*
X3134181Y523762D01*
X3135266Y522721D01*
X3135576Y521471D01*
X3135421Y520220D01*
X3134801Y519179D01*
X3131701Y517096D01*
X3130306Y515637D01*
X3129376Y513554D01*
X3129066Y511679D01*
X3135576D01*
G01X3144721Y511262D02*
X3144411Y511471D01*
Y511887D01*
X3144721Y512096D01*
X3145031Y511887D01*
Y511471D01*
X3144721Y511262D01*
G01X3157121Y524179D02*
X3155881Y523762D01*
X3154951Y522721D01*
X3154331Y521471D01*
X3153866Y519804D01*
X3153711Y517929D01*
X3153866Y516054D01*
X3154331Y514387D01*
X3154951Y513137D01*
X3155881Y512096D01*
X3157121Y511679D01*
X3158361Y512096D01*
X3159291Y513137D01*
X3159911Y514387D01*
X3160376Y516054D01*
X3160531Y517929D01*
X3160376Y519804D01*
X3159911Y521471D01*
X3159291Y522721D01*
X3158361Y523762D01*
X3157121Y524179D01*
G01X3166731Y511262D02*
X3172311Y524179D01*
G01X3179906Y515846D02*
X3183936D01*
G01X3191376Y522096D02*
X3192306Y523345D01*
X3193391Y523971D01*
X3194631Y524179D01*
X3196181Y523762D01*
X3197266Y522721D01*
X3197576Y521471D01*
X3197421Y520220D01*
X3196801Y519179D01*
X3193701Y517096D01*
X3192306Y515637D01*
X3191376Y513554D01*
X3191066Y511679D01*
X3197576D01*
G01X3206721Y511262D02*
X3206411Y511471D01*
Y511887D01*
X3206721Y512096D01*
X3207031Y511887D01*
Y511471D01*
X3206721Y511262D01*
G01X3219121Y524179D02*
X3217881Y523762D01*
X3216951Y522721D01*
X3216331Y521471D01*
X3215866Y519804D01*
X3215711Y517929D01*
X3215866Y516054D01*
X3216331Y514387D01*
X3216951Y513137D01*
X3217881Y512096D01*
X3219121Y511679D01*
X3220361Y512096D01*
X3221291Y513137D01*
X3221911Y514387D01*
X3222376Y516054D01*
X3222531Y517929D01*
X3222376Y519804D01*
X3221911Y521471D01*
X3221291Y522721D01*
X3220361Y523762D01*
X3219121Y524179D01*
G01X3118216Y574946D02*
X3121936D01*
G01X3119921Y577654D02*
Y572237D01*
G01X3129376Y581196D02*
X3130306Y582445D01*
X3131391Y583071D01*
X3132631Y583279D01*
X3134181Y582862D01*
X3135266Y581821D01*
X3135576Y580571D01*
X3135421Y579320D01*
X3134801Y578279D01*
X3131701Y576196D01*
X3130306Y574737D01*
X3129376Y572654D01*
X3129066Y570779D01*
X3135576D01*
G01X3144721Y570362D02*
X3144411Y570571D01*
Y570987D01*
X3144721Y571196D01*
X3145031Y570987D01*
Y570571D01*
X3144721Y570362D01*
G01X3157121Y583279D02*
X3155881Y582862D01*
X3154951Y581821D01*
X3154331Y580571D01*
X3153866Y578904D01*
X3153711Y577029D01*
X3153866Y575154D01*
X3154331Y573487D01*
X3154951Y572237D01*
X3155881Y571196D01*
X3157121Y570779D01*
X3158361Y571196D01*
X3159291Y572237D01*
X3159911Y573487D01*
X3160376Y575154D01*
X3160531Y577029D01*
X3160376Y578904D01*
X3159911Y580571D01*
X3159291Y581821D01*
X3158361Y582862D01*
X3157121Y583279D01*
G01X3166731Y570362D02*
X3172311Y583279D01*
G01X3179906Y574946D02*
X3183936D01*
G01X3191376Y581196D02*
X3192306Y582445D01*
X3193391Y583071D01*
X3194631Y583279D01*
X3196181Y582862D01*
X3197266Y581821D01*
X3197576Y580571D01*
X3197421Y579320D01*
X3196801Y578279D01*
X3193701Y576196D01*
X3192306Y574737D01*
X3191376Y572654D01*
X3191066Y570779D01*
X3197576D01*
G01X3206721Y570362D02*
X3206411Y570571D01*
Y570987D01*
X3206721Y571196D01*
X3207031Y570987D01*
Y570571D01*
X3206721Y570362D01*
G01X3219121Y583279D02*
X3217881Y582862D01*
X3216951Y581821D01*
X3216331Y580571D01*
X3215866Y578904D01*
X3215711Y577029D01*
X3215866Y575154D01*
X3216331Y573487D01*
X3216951Y572237D01*
X3217881Y571196D01*
X3219121Y570779D01*
X3220361Y571196D01*
X3221291Y572237D01*
X3221911Y573487D01*
X3222376Y575154D01*
X3222531Y577029D01*
X3222376Y578904D01*
X3221911Y580571D01*
X3221291Y581821D01*
X3220361Y582862D01*
X3219121Y583279D01*
G01X3118216Y693146D02*
X3121936D01*
G01X3119921Y695854D02*
Y690437D01*
G01X3129376Y699396D02*
X3130306Y700645D01*
X3131391Y701271D01*
X3132631Y701479D01*
X3134181Y701062D01*
X3135266Y700021D01*
X3135576Y698771D01*
X3135421Y697520D01*
X3134801Y696479D01*
X3131701Y694396D01*
X3130306Y692937D01*
X3129376Y690854D01*
X3129066Y688979D01*
X3135576D01*
G01X3144721Y688562D02*
X3144411Y688771D01*
Y689187D01*
X3144721Y689396D01*
X3145031Y689187D01*
Y688771D01*
X3144721Y688562D01*
G01X3157121Y701479D02*
X3155881Y701062D01*
X3154951Y700021D01*
X3154331Y698771D01*
X3153866Y697104D01*
X3153711Y695229D01*
X3153866Y693354D01*
X3154331Y691687D01*
X3154951Y690437D01*
X3155881Y689396D01*
X3157121Y688979D01*
X3158361Y689396D01*
X3159291Y690437D01*
X3159911Y691687D01*
X3160376Y693354D01*
X3160531Y695229D01*
X3160376Y697104D01*
X3159911Y698771D01*
X3159291Y700021D01*
X3158361Y701062D01*
X3157121Y701479D01*
G01X3166731Y688562D02*
X3172311Y701479D01*
G01X3179906Y693146D02*
X3183936D01*
G01X3191376Y699396D02*
X3192306Y700645D01*
X3193391Y701271D01*
X3194631Y701479D01*
X3196181Y701062D01*
X3197266Y700021D01*
X3197576Y698771D01*
X3197421Y697520D01*
X3196801Y696479D01*
X3193701Y694396D01*
X3192306Y692937D01*
X3191376Y690854D01*
X3191066Y688979D01*
X3197576D01*
G01X3206721Y688562D02*
X3206411Y688771D01*
Y689187D01*
X3206721Y689396D01*
X3207031Y689187D01*
Y688771D01*
X3206721Y688562D01*
G01X3219121Y701479D02*
X3217881Y701062D01*
X3216951Y700021D01*
X3216331Y698771D01*
X3215866Y697104D01*
X3215711Y695229D01*
X3215866Y693354D01*
X3216331Y691687D01*
X3216951Y690437D01*
X3217881Y689396D01*
X3219121Y688979D01*
X3220361Y689396D01*
X3221291Y690437D01*
X3221911Y691687D01*
X3222376Y693354D01*
X3222531Y695229D01*
X3222376Y697104D01*
X3221911Y698771D01*
X3221291Y700021D01*
X3220361Y701062D01*
X3219121Y701479D01*
G01X3112016Y811346D02*
X3115736D01*
G01X3113721Y814054D02*
Y808637D01*
G01X3122711Y809679D02*
X3123641Y808220D01*
X3124881Y807387D01*
X3126276Y807179D01*
X3127516Y807387D01*
X3128756Y808429D01*
X3129531Y809679D01*
X3129686Y810929D01*
X3129376Y812387D01*
X3128291Y813429D01*
X3127206Y813846D01*
X3125811D01*
G01X3127206D02*
X3128136Y814471D01*
X3128911Y815512D01*
X3129221Y816762D01*
X3128911Y818012D01*
X3128136Y819054D01*
X3126741Y819679D01*
X3125346Y819471D01*
X3123951Y818637D01*
G01X3138521Y806762D02*
X3138211Y806971D01*
Y807387D01*
X3138521Y807596D01*
X3138831Y807387D01*
Y806971D01*
X3138521Y806762D01*
G01X3150921Y807179D02*
Y819679D01*
X3149061Y817179D01*
G01Y807179D02*
X3152781D01*
G01X3165181D02*
Y819679D01*
X3159446Y810721D01*
X3167196D01*
G01X3172931Y806762D02*
X3178511Y819679D01*
G01X3186106Y811346D02*
X3190136D01*
G01X3200521Y819679D02*
X3199281Y819262D01*
X3198351Y818221D01*
X3197731Y816971D01*
X3197266Y815304D01*
X3197111Y813429D01*
X3197266Y811554D01*
X3197731Y809887D01*
X3198351Y808637D01*
X3199281Y807596D01*
X3200521Y807179D01*
X3201761Y807596D01*
X3202691Y808637D01*
X3203311Y809887D01*
X3203776Y811554D01*
X3203931Y813429D01*
X3203776Y815304D01*
X3203311Y816971D01*
X3202691Y818221D01*
X3201761Y819262D01*
X3200521Y819679D01*
G01X3212921Y806762D02*
X3212611Y806971D01*
Y807387D01*
X3212921Y807596D01*
X3213231Y807387D01*
Y806971D01*
X3212921Y806762D01*
G01X3225321Y819679D02*
X3224081Y819262D01*
X3223151Y818221D01*
X3222531Y816971D01*
X3222066Y815304D01*
X3221911Y813429D01*
X3222066Y811554D01*
X3222531Y809887D01*
X3223151Y808637D01*
X3224081Y807596D01*
X3225321Y807179D01*
X3226561Y807596D01*
X3227491Y808637D01*
X3228111Y809887D01*
X3228576Y811554D01*
X3228731Y813429D01*
X3228576Y815304D01*
X3228111Y816971D01*
X3227491Y818221D01*
X3226561Y819262D01*
X3225321Y819679D01*
G01X3118216Y870446D02*
X3121936D01*
G01X3119921Y873154D02*
Y867737D01*
G01X3128911Y868779D02*
X3129841Y867320D01*
X3131081Y866487D01*
X3132476Y866279D01*
X3133716Y866487D01*
X3134956Y867529D01*
X3135731Y868779D01*
X3135886Y870029D01*
X3135576Y871487D01*
X3134491Y872529D01*
X3133406Y872946D01*
X3132011D01*
G01X3133406D02*
X3134336Y873571D01*
X3135111Y874612D01*
X3135421Y875862D01*
X3135111Y877112D01*
X3134336Y878154D01*
X3132941Y878779D01*
X3131546Y878571D01*
X3130151Y877737D01*
G01X3144721Y865862D02*
X3144411Y866071D01*
Y866487D01*
X3144721Y866696D01*
X3145031Y866487D01*
Y866071D01*
X3144721Y865862D01*
G01X3157121Y878779D02*
X3155881Y878362D01*
X3154951Y877321D01*
X3154331Y876071D01*
X3153866Y874404D01*
X3153711Y872529D01*
X3153866Y870654D01*
X3154331Y868987D01*
X3154951Y867737D01*
X3155881Y866696D01*
X3157121Y866279D01*
X3158361Y866696D01*
X3159291Y867737D01*
X3159911Y868987D01*
X3160376Y870654D01*
X3160531Y872529D01*
X3160376Y874404D01*
X3159911Y876071D01*
X3159291Y877321D01*
X3158361Y878362D01*
X3157121Y878779D01*
G01X3166731Y865862D02*
X3172311Y878779D01*
G01X3179906Y870446D02*
X3183936D01*
G01X3190911Y868779D02*
X3191841Y867320D01*
X3193081Y866487D01*
X3194476Y866279D01*
X3195716Y866487D01*
X3196956Y867529D01*
X3197731Y868779D01*
X3197886Y870029D01*
X3197576Y871487D01*
X3196491Y872529D01*
X3195406Y872946D01*
X3194011D01*
G01X3195406D02*
X3196336Y873571D01*
X3197111Y874612D01*
X3197421Y875862D01*
X3197111Y877112D01*
X3196336Y878154D01*
X3194941Y878779D01*
X3193546Y878571D01*
X3192151Y877737D01*
G01X3206721Y865862D02*
X3206411Y866071D01*
Y866487D01*
X3206721Y866696D01*
X3207031Y866487D01*
Y866071D01*
X3206721Y865862D01*
G01X3219121Y878779D02*
X3217881Y878362D01*
X3216951Y877321D01*
X3216331Y876071D01*
X3215866Y874404D01*
X3215711Y872529D01*
X3215866Y870654D01*
X3216331Y868987D01*
X3216951Y867737D01*
X3217881Y866696D01*
X3219121Y866279D01*
X3220361Y866696D01*
X3221291Y867737D01*
X3221911Y868987D01*
X3222376Y870654D01*
X3222531Y872529D01*
X3222376Y874404D01*
X3221911Y876071D01*
X3221291Y877321D01*
X3220361Y878362D01*
X3219121Y878779D01*
G01X3118216Y929546D02*
X3121936D01*
G01X3119921Y932254D02*
Y926837D01*
G01X3128911Y927879D02*
X3129841Y926420D01*
X3131081Y925587D01*
X3132476Y925379D01*
X3133716Y925587D01*
X3134956Y926629D01*
X3135731Y927879D01*
X3135886Y929129D01*
X3135576Y930587D01*
X3134491Y931629D01*
X3133406Y932046D01*
X3132011D01*
G01X3133406D02*
X3134336Y932671D01*
X3135111Y933712D01*
X3135421Y934962D01*
X3135111Y936212D01*
X3134336Y937254D01*
X3132941Y937879D01*
X3131546Y937671D01*
X3130151Y936837D01*
G01X3144721Y924962D02*
X3144411Y925171D01*
Y925587D01*
X3144721Y925796D01*
X3145031Y925587D01*
Y925171D01*
X3144721Y924962D01*
G01X3157121Y937879D02*
X3155881Y937462D01*
X3154951Y936421D01*
X3154331Y935171D01*
X3153866Y933504D01*
X3153711Y931629D01*
X3153866Y929754D01*
X3154331Y928087D01*
X3154951Y926837D01*
X3155881Y925796D01*
X3157121Y925379D01*
X3158361Y925796D01*
X3159291Y926837D01*
X3159911Y928087D01*
X3160376Y929754D01*
X3160531Y931629D01*
X3160376Y933504D01*
X3159911Y935171D01*
X3159291Y936421D01*
X3158361Y937462D01*
X3157121Y937879D01*
G01X3166731Y924962D02*
X3172311Y937879D01*
G01X3179906Y929546D02*
X3183936D01*
G01X3190911Y927879D02*
X3191841Y926420D01*
X3193081Y925587D01*
X3194476Y925379D01*
X3195716Y925587D01*
X3196956Y926629D01*
X3197731Y927879D01*
X3197886Y929129D01*
X3197576Y930587D01*
X3196491Y931629D01*
X3195406Y932046D01*
X3194011D01*
G01X3195406D02*
X3196336Y932671D01*
X3197111Y933712D01*
X3197421Y934962D01*
X3197111Y936212D01*
X3196336Y937254D01*
X3194941Y937879D01*
X3193546Y937671D01*
X3192151Y936837D01*
G01X3206721Y924962D02*
X3206411Y925171D01*
Y925587D01*
X3206721Y925796D01*
X3207031Y925587D01*
Y925171D01*
X3206721Y924962D01*
G01X3219121Y937879D02*
X3217881Y937462D01*
X3216951Y936421D01*
X3216331Y935171D01*
X3215866Y933504D01*
X3215711Y931629D01*
X3215866Y929754D01*
X3216331Y928087D01*
X3216951Y926837D01*
X3217881Y925796D01*
X3219121Y925379D01*
X3220361Y925796D01*
X3221291Y926837D01*
X3221911Y928087D01*
X3222376Y929754D01*
X3222531Y931629D01*
X3222376Y933504D01*
X3221911Y935171D01*
X3221291Y936421D01*
X3220361Y937462D01*
X3219121Y937879D01*
G01X3118216Y988646D02*
X3121936D01*
G01X3119921Y991354D02*
Y985937D01*
G01X3128911Y986979D02*
X3129841Y985520D01*
X3131081Y984687D01*
X3132476Y984479D01*
X3133716Y984687D01*
X3134956Y985729D01*
X3135731Y986979D01*
X3135886Y988229D01*
X3135576Y989687D01*
X3134491Y990729D01*
X3133406Y991146D01*
X3132011D01*
G01X3133406D02*
X3134336Y991771D01*
X3135111Y992812D01*
X3135421Y994062D01*
X3135111Y995312D01*
X3134336Y996354D01*
X3132941Y996979D01*
X3131546Y996771D01*
X3130151Y995937D01*
G01X3144721Y984062D02*
X3144411Y984271D01*
Y984687D01*
X3144721Y984896D01*
X3145031Y984687D01*
Y984271D01*
X3144721Y984062D01*
G01X3157121Y996979D02*
X3155881Y996562D01*
X3154951Y995521D01*
X3154331Y994271D01*
X3153866Y992604D01*
X3153711Y990729D01*
X3153866Y988854D01*
X3154331Y987187D01*
X3154951Y985937D01*
X3155881Y984896D01*
X3157121Y984479D01*
X3158361Y984896D01*
X3159291Y985937D01*
X3159911Y987187D01*
X3160376Y988854D01*
X3160531Y990729D01*
X3160376Y992604D01*
X3159911Y994271D01*
X3159291Y995521D01*
X3158361Y996562D01*
X3157121Y996979D01*
G01X3166731Y984062D02*
X3172311Y996979D01*
G01X3179906Y988646D02*
X3183936D01*
G01X3190911Y986979D02*
X3191841Y985520D01*
X3193081Y984687D01*
X3194476Y984479D01*
X3195716Y984687D01*
X3196956Y985729D01*
X3197731Y986979D01*
X3197886Y988229D01*
X3197576Y989687D01*
X3196491Y990729D01*
X3195406Y991146D01*
X3194011D01*
G01X3195406D02*
X3196336Y991771D01*
X3197111Y992812D01*
X3197421Y994062D01*
X3197111Y995312D01*
X3196336Y996354D01*
X3194941Y996979D01*
X3193546Y996771D01*
X3192151Y995937D01*
G01X3206721Y984062D02*
X3206411Y984271D01*
Y984687D01*
X3206721Y984896D01*
X3207031Y984687D01*
Y984271D01*
X3206721Y984062D01*
G01X3219121Y996979D02*
X3217881Y996562D01*
X3216951Y995521D01*
X3216331Y994271D01*
X3215866Y992604D01*
X3215711Y990729D01*
X3215866Y988854D01*
X3216331Y987187D01*
X3216951Y985937D01*
X3217881Y984896D01*
X3219121Y984479D01*
X3220361Y984896D01*
X3221291Y985937D01*
X3221911Y987187D01*
X3222376Y988854D01*
X3222531Y990729D01*
X3222376Y992604D01*
X3221911Y994271D01*
X3221291Y995521D01*
X3220361Y996562D01*
X3219121Y996979D01*
G01X3118216Y1047746D02*
X3121936D01*
G01X3119921Y1050454D02*
Y1045037D01*
G01X3128911Y1046079D02*
X3129841Y1044620D01*
X3131081Y1043787D01*
X3132476Y1043579D01*
X3133716Y1043787D01*
X3134956Y1044829D01*
X3135731Y1046079D01*
X3135886Y1047329D01*
X3135576Y1048787D01*
X3134491Y1049829D01*
X3133406Y1050246D01*
X3132011D01*
G01X3133406D02*
X3134336Y1050871D01*
X3135111Y1051912D01*
X3135421Y1053162D01*
X3135111Y1054412D01*
X3134336Y1055454D01*
X3132941Y1056079D01*
X3131546Y1055871D01*
X3130151Y1055037D01*
G01X3144721Y1043162D02*
X3144411Y1043371D01*
Y1043787D01*
X3144721Y1043996D01*
X3145031Y1043787D01*
Y1043371D01*
X3144721Y1043162D01*
G01X3157121Y1056079D02*
X3155881Y1055662D01*
X3154951Y1054621D01*
X3154331Y1053371D01*
X3153866Y1051704D01*
X3153711Y1049829D01*
X3153866Y1047954D01*
X3154331Y1046287D01*
X3154951Y1045037D01*
X3155881Y1043996D01*
X3157121Y1043579D01*
X3158361Y1043996D01*
X3159291Y1045037D01*
X3159911Y1046287D01*
X3160376Y1047954D01*
X3160531Y1049829D01*
X3160376Y1051704D01*
X3159911Y1053371D01*
X3159291Y1054621D01*
X3158361Y1055662D01*
X3157121Y1056079D01*
G01X3166731Y1043162D02*
X3172311Y1056079D01*
G01X3179906Y1047746D02*
X3183936D01*
G01X3190911Y1046079D02*
X3191841Y1044620D01*
X3193081Y1043787D01*
X3194476Y1043579D01*
X3195716Y1043787D01*
X3196956Y1044829D01*
X3197731Y1046079D01*
X3197886Y1047329D01*
X3197576Y1048787D01*
X3196491Y1049829D01*
X3195406Y1050246D01*
X3194011D01*
G01X3195406D02*
X3196336Y1050871D01*
X3197111Y1051912D01*
X3197421Y1053162D01*
X3197111Y1054412D01*
X3196336Y1055454D01*
X3194941Y1056079D01*
X3193546Y1055871D01*
X3192151Y1055037D01*
G01X3206721Y1043162D02*
X3206411Y1043371D01*
Y1043787D01*
X3206721Y1043996D01*
X3207031Y1043787D01*
Y1043371D01*
X3206721Y1043162D01*
G01X3219121Y1056079D02*
X3217881Y1055662D01*
X3216951Y1054621D01*
X3216331Y1053371D01*
X3215866Y1051704D01*
X3215711Y1049829D01*
X3215866Y1047954D01*
X3216331Y1046287D01*
X3216951Y1045037D01*
X3217881Y1043996D01*
X3219121Y1043579D01*
X3220361Y1043996D01*
X3221291Y1045037D01*
X3221911Y1046287D01*
X3222376Y1047954D01*
X3222531Y1049829D01*
X3222376Y1051704D01*
X3221911Y1053371D01*
X3221291Y1054621D01*
X3220361Y1055662D01*
X3219121Y1056079D01*
G01X3118216Y1106846D02*
X3121936D01*
G01X3119921Y1109554D02*
Y1104137D01*
G01X3128911Y1105179D02*
X3129841Y1103720D01*
X3131081Y1102887D01*
X3132476Y1102679D01*
X3133716Y1102887D01*
X3134956Y1103929D01*
X3135731Y1105179D01*
X3135886Y1106429D01*
X3135576Y1107887D01*
X3134491Y1108929D01*
X3133406Y1109346D01*
X3132011D01*
G01X3133406D02*
X3134336Y1109971D01*
X3135111Y1111012D01*
X3135421Y1112262D01*
X3135111Y1113512D01*
X3134336Y1114554D01*
X3132941Y1115179D01*
X3131546Y1114971D01*
X3130151Y1114137D01*
G01X3144721Y1102262D02*
X3144411Y1102471D01*
Y1102887D01*
X3144721Y1103096D01*
X3145031Y1102887D01*
Y1102471D01*
X3144721Y1102262D01*
G01X3157121Y1115179D02*
X3155881Y1114762D01*
X3154951Y1113721D01*
X3154331Y1112471D01*
X3153866Y1110804D01*
X3153711Y1108929D01*
X3153866Y1107054D01*
X3154331Y1105387D01*
X3154951Y1104137D01*
X3155881Y1103096D01*
X3157121Y1102679D01*
X3158361Y1103096D01*
X3159291Y1104137D01*
X3159911Y1105387D01*
X3160376Y1107054D01*
X3160531Y1108929D01*
X3160376Y1110804D01*
X3159911Y1112471D01*
X3159291Y1113721D01*
X3158361Y1114762D01*
X3157121Y1115179D01*
G01X3166731Y1102262D02*
X3172311Y1115179D01*
G01X3179906Y1106846D02*
X3183936D01*
G01X3190911Y1105179D02*
X3191841Y1103720D01*
X3193081Y1102887D01*
X3194476Y1102679D01*
X3195716Y1102887D01*
X3196956Y1103929D01*
X3197731Y1105179D01*
X3197886Y1106429D01*
X3197576Y1107887D01*
X3196491Y1108929D01*
X3195406Y1109346D01*
X3194011D01*
G01X3195406D02*
X3196336Y1109971D01*
X3197111Y1111012D01*
X3197421Y1112262D01*
X3197111Y1113512D01*
X3196336Y1114554D01*
X3194941Y1115179D01*
X3193546Y1114971D01*
X3192151Y1114137D01*
G01X3206721Y1102262D02*
X3206411Y1102471D01*
Y1102887D01*
X3206721Y1103096D01*
X3207031Y1102887D01*
Y1102471D01*
X3206721Y1102262D01*
G01X3219121Y1115179D02*
X3217881Y1114762D01*
X3216951Y1113721D01*
X3216331Y1112471D01*
X3215866Y1110804D01*
X3215711Y1108929D01*
X3215866Y1107054D01*
X3216331Y1105387D01*
X3216951Y1104137D01*
X3217881Y1103096D01*
X3219121Y1102679D01*
X3220361Y1103096D01*
X3221291Y1104137D01*
X3221911Y1105387D01*
X3222376Y1107054D01*
X3222531Y1108929D01*
X3222376Y1110804D01*
X3221911Y1112471D01*
X3221291Y1113721D01*
X3220361Y1114762D01*
X3219121Y1115179D01*
G01X3118216Y1165946D02*
X3121936D01*
G01X3119921Y1168654D02*
Y1163237D01*
G01X3128911Y1164279D02*
X3129841Y1162820D01*
X3131081Y1161987D01*
X3132476Y1161779D01*
X3133716Y1161987D01*
X3134956Y1163029D01*
X3135731Y1164279D01*
X3135886Y1165529D01*
X3135576Y1166987D01*
X3134491Y1168029D01*
X3133406Y1168446D01*
X3132011D01*
G01X3133406D02*
X3134336Y1169071D01*
X3135111Y1170112D01*
X3135421Y1171362D01*
X3135111Y1172612D01*
X3134336Y1173654D01*
X3132941Y1174279D01*
X3131546Y1174071D01*
X3130151Y1173237D01*
G01X3144721Y1161362D02*
X3144411Y1161571D01*
Y1161987D01*
X3144721Y1162196D01*
X3145031Y1161987D01*
Y1161571D01*
X3144721Y1161362D01*
G01X3157121Y1174279D02*
X3155881Y1173862D01*
X3154951Y1172821D01*
X3154331Y1171571D01*
X3153866Y1169904D01*
X3153711Y1168029D01*
X3153866Y1166154D01*
X3154331Y1164487D01*
X3154951Y1163237D01*
X3155881Y1162196D01*
X3157121Y1161779D01*
X3158361Y1162196D01*
X3159291Y1163237D01*
X3159911Y1164487D01*
X3160376Y1166154D01*
X3160531Y1168029D01*
X3160376Y1169904D01*
X3159911Y1171571D01*
X3159291Y1172821D01*
X3158361Y1173862D01*
X3157121Y1174279D01*
G01X3166731Y1161362D02*
X3172311Y1174279D01*
G01X3179906Y1165946D02*
X3183936D01*
G01X3190911Y1164279D02*
X3191841Y1162820D01*
X3193081Y1161987D01*
X3194476Y1161779D01*
X3195716Y1161987D01*
X3196956Y1163029D01*
X3197731Y1164279D01*
X3197886Y1165529D01*
X3197576Y1166987D01*
X3196491Y1168029D01*
X3195406Y1168446D01*
X3194011D01*
G01X3195406D02*
X3196336Y1169071D01*
X3197111Y1170112D01*
X3197421Y1171362D01*
X3197111Y1172612D01*
X3196336Y1173654D01*
X3194941Y1174279D01*
X3193546Y1174071D01*
X3192151Y1173237D01*
G01X3206721Y1161362D02*
X3206411Y1161571D01*
Y1161987D01*
X3206721Y1162196D01*
X3207031Y1161987D01*
Y1161571D01*
X3206721Y1161362D01*
G01X3219121Y1174279D02*
X3217881Y1173862D01*
X3216951Y1172821D01*
X3216331Y1171571D01*
X3215866Y1169904D01*
X3215711Y1168029D01*
X3215866Y1166154D01*
X3216331Y1164487D01*
X3216951Y1163237D01*
X3217881Y1162196D01*
X3219121Y1161779D01*
X3220361Y1162196D01*
X3221291Y1163237D01*
X3221911Y1164487D01*
X3222376Y1166154D01*
X3222531Y1168029D01*
X3222376Y1169904D01*
X3221911Y1171571D01*
X3221291Y1172821D01*
X3220361Y1173862D01*
X3219121Y1174279D01*
G01X3118216Y1284146D02*
X3121936D01*
G01X3119921Y1286854D02*
Y1281437D01*
G01X3128911Y1282479D02*
X3129841Y1281020D01*
X3131081Y1280187D01*
X3132476Y1279979D01*
X3133716Y1280187D01*
X3134956Y1281229D01*
X3135731Y1282479D01*
X3135886Y1283729D01*
X3135576Y1285187D01*
X3134491Y1286229D01*
X3133406Y1286646D01*
X3132011D01*
G01X3133406D02*
X3134336Y1287271D01*
X3135111Y1288312D01*
X3135421Y1289562D01*
X3135111Y1290812D01*
X3134336Y1291854D01*
X3132941Y1292479D01*
X3131546Y1292271D01*
X3130151Y1291437D01*
G01X3144721Y1279562D02*
X3144411Y1279771D01*
Y1280187D01*
X3144721Y1280396D01*
X3145031Y1280187D01*
Y1279771D01*
X3144721Y1279562D01*
G01X3157121Y1292479D02*
X3155881Y1292062D01*
X3154951Y1291021D01*
X3154331Y1289771D01*
X3153866Y1288104D01*
X3153711Y1286229D01*
X3153866Y1284354D01*
X3154331Y1282687D01*
X3154951Y1281437D01*
X3155881Y1280396D01*
X3157121Y1279979D01*
X3158361Y1280396D01*
X3159291Y1281437D01*
X3159911Y1282687D01*
X3160376Y1284354D01*
X3160531Y1286229D01*
X3160376Y1288104D01*
X3159911Y1289771D01*
X3159291Y1291021D01*
X3158361Y1292062D01*
X3157121Y1292479D01*
G01X3166731Y1279562D02*
X3172311Y1292479D01*
G01X3179906Y1284146D02*
X3183936D01*
G01X3190911Y1282479D02*
X3191841Y1281020D01*
X3193081Y1280187D01*
X3194476Y1279979D01*
X3195716Y1280187D01*
X3196956Y1281229D01*
X3197731Y1282479D01*
X3197886Y1283729D01*
X3197576Y1285187D01*
X3196491Y1286229D01*
X3195406Y1286646D01*
X3194011D01*
G01X3195406D02*
X3196336Y1287271D01*
X3197111Y1288312D01*
X3197421Y1289562D01*
X3197111Y1290812D01*
X3196336Y1291854D01*
X3194941Y1292479D01*
X3193546Y1292271D01*
X3192151Y1291437D01*
G01X3206721Y1279562D02*
X3206411Y1279771D01*
Y1280187D01*
X3206721Y1280396D01*
X3207031Y1280187D01*
Y1279771D01*
X3206721Y1279562D01*
G01X3219121Y1292479D02*
X3217881Y1292062D01*
X3216951Y1291021D01*
X3216331Y1289771D01*
X3215866Y1288104D01*
X3215711Y1286229D01*
X3215866Y1284354D01*
X3216331Y1282687D01*
X3216951Y1281437D01*
X3217881Y1280396D01*
X3219121Y1279979D01*
X3220361Y1280396D01*
X3221291Y1281437D01*
X3221911Y1282687D01*
X3222376Y1284354D01*
X3222531Y1286229D01*
X3222376Y1288104D01*
X3221911Y1289771D01*
X3221291Y1291021D01*
X3220361Y1292062D01*
X3219121Y1292479D01*
G01X3118216Y1343246D02*
X3121936D01*
G01X3119921Y1345954D02*
Y1340537D01*
G01X3128911Y1341579D02*
X3129841Y1340120D01*
X3131081Y1339287D01*
X3132476Y1339079D01*
X3133716Y1339287D01*
X3134956Y1340329D01*
X3135731Y1341579D01*
X3135886Y1342829D01*
X3135576Y1344287D01*
X3134491Y1345329D01*
X3133406Y1345746D01*
X3132011D01*
G01X3133406D02*
X3134336Y1346371D01*
X3135111Y1347412D01*
X3135421Y1348662D01*
X3135111Y1349912D01*
X3134336Y1350954D01*
X3132941Y1351579D01*
X3131546Y1351371D01*
X3130151Y1350537D01*
G01X3144721Y1338662D02*
X3144411Y1338871D01*
Y1339287D01*
X3144721Y1339496D01*
X3145031Y1339287D01*
Y1338871D01*
X3144721Y1338662D01*
G01X3157121Y1351579D02*
X3155881Y1351162D01*
X3154951Y1350121D01*
X3154331Y1348871D01*
X3153866Y1347204D01*
X3153711Y1345329D01*
X3153866Y1343454D01*
X3154331Y1341787D01*
X3154951Y1340537D01*
X3155881Y1339496D01*
X3157121Y1339079D01*
X3158361Y1339496D01*
X3159291Y1340537D01*
X3159911Y1341787D01*
X3160376Y1343454D01*
X3160531Y1345329D01*
X3160376Y1347204D01*
X3159911Y1348871D01*
X3159291Y1350121D01*
X3158361Y1351162D01*
X3157121Y1351579D01*
G01X3166731Y1338662D02*
X3172311Y1351579D01*
G01X3179906Y1343246D02*
X3183936D01*
G01X3190911Y1341579D02*
X3191841Y1340120D01*
X3193081Y1339287D01*
X3194476Y1339079D01*
X3195716Y1339287D01*
X3196956Y1340329D01*
X3197731Y1341579D01*
X3197886Y1342829D01*
X3197576Y1344287D01*
X3196491Y1345329D01*
X3195406Y1345746D01*
X3194011D01*
G01X3195406D02*
X3196336Y1346371D01*
X3197111Y1347412D01*
X3197421Y1348662D01*
X3197111Y1349912D01*
X3196336Y1350954D01*
X3194941Y1351579D01*
X3193546Y1351371D01*
X3192151Y1350537D01*
G01X3206721Y1338662D02*
X3206411Y1338871D01*
Y1339287D01*
X3206721Y1339496D01*
X3207031Y1339287D01*
Y1338871D01*
X3206721Y1338662D01*
G01X3219121Y1351579D02*
X3217881Y1351162D01*
X3216951Y1350121D01*
X3216331Y1348871D01*
X3215866Y1347204D01*
X3215711Y1345329D01*
X3215866Y1343454D01*
X3216331Y1341787D01*
X3216951Y1340537D01*
X3217881Y1339496D01*
X3219121Y1339079D01*
X3220361Y1339496D01*
X3221291Y1340537D01*
X3221911Y1341787D01*
X3222376Y1343454D01*
X3222531Y1345329D01*
X3222376Y1347204D01*
X3221911Y1348871D01*
X3221291Y1350121D01*
X3220361Y1351162D01*
X3219121Y1351579D01*
G01X3118216Y1402346D02*
X3121936D01*
G01X3119921Y1405054D02*
Y1399637D01*
G01X3129376Y1408596D02*
X3130306Y1409845D01*
X3131391Y1410471D01*
X3132631Y1410679D01*
X3134181Y1410262D01*
X3135266Y1409221D01*
X3135576Y1407971D01*
X3135421Y1406720D01*
X3134801Y1405679D01*
X3131701Y1403596D01*
X3130306Y1402137D01*
X3129376Y1400054D01*
X3129066Y1398179D01*
X3135576D01*
G01X3144721Y1397762D02*
X3144411Y1397971D01*
Y1398387D01*
X3144721Y1398596D01*
X3145031Y1398387D01*
Y1397971D01*
X3144721Y1397762D01*
G01X3157121Y1410679D02*
X3155881Y1410262D01*
X3154951Y1409221D01*
X3154331Y1407971D01*
X3153866Y1406304D01*
X3153711Y1404429D01*
X3153866Y1402554D01*
X3154331Y1400887D01*
X3154951Y1399637D01*
X3155881Y1398596D01*
X3157121Y1398179D01*
X3158361Y1398596D01*
X3159291Y1399637D01*
X3159911Y1400887D01*
X3160376Y1402554D01*
X3160531Y1404429D01*
X3160376Y1406304D01*
X3159911Y1407971D01*
X3159291Y1409221D01*
X3158361Y1410262D01*
X3157121Y1410679D01*
G01X3166731Y1397762D02*
X3172311Y1410679D01*
G01X3179906Y1402346D02*
X3183936D01*
G01X3191376Y1408596D02*
X3192306Y1409845D01*
X3193391Y1410471D01*
X3194631Y1410679D01*
X3196181Y1410262D01*
X3197266Y1409221D01*
X3197576Y1407971D01*
X3197421Y1406720D01*
X3196801Y1405679D01*
X3193701Y1403596D01*
X3192306Y1402137D01*
X3191376Y1400054D01*
X3191066Y1398179D01*
X3197576D01*
G01X3206721Y1397762D02*
X3206411Y1397971D01*
Y1398387D01*
X3206721Y1398596D01*
X3207031Y1398387D01*
Y1397971D01*
X3206721Y1397762D01*
G01X3219121Y1410679D02*
X3217881Y1410262D01*
X3216951Y1409221D01*
X3216331Y1407971D01*
X3215866Y1406304D01*
X3215711Y1404429D01*
X3215866Y1402554D01*
X3216331Y1400887D01*
X3216951Y1399637D01*
X3217881Y1398596D01*
X3219121Y1398179D01*
X3220361Y1398596D01*
X3221291Y1399637D01*
X3221911Y1400887D01*
X3222376Y1402554D01*
X3222531Y1404429D01*
X3222376Y1406304D01*
X3221911Y1407971D01*
X3221291Y1409221D01*
X3220361Y1410262D01*
X3219121Y1410679D01*
G01X3118216Y1461446D02*
X3121936D01*
G01X3119921Y1464154D02*
Y1458737D01*
G01X3128911Y1459779D02*
X3129841Y1458320D01*
X3131081Y1457487D01*
X3132476Y1457279D01*
X3133716Y1457487D01*
X3134956Y1458529D01*
X3135731Y1459779D01*
X3135886Y1461029D01*
X3135576Y1462487D01*
X3134491Y1463529D01*
X3133406Y1463946D01*
X3132011D01*
G01X3133406D02*
X3134336Y1464571D01*
X3135111Y1465612D01*
X3135421Y1466862D01*
X3135111Y1468112D01*
X3134336Y1469154D01*
X3132941Y1469779D01*
X3131546Y1469571D01*
X3130151Y1468737D01*
G01X3144721Y1456862D02*
X3144411Y1457071D01*
Y1457487D01*
X3144721Y1457696D01*
X3145031Y1457487D01*
Y1457071D01*
X3144721Y1456862D01*
G01X3157121Y1469779D02*
X3155881Y1469362D01*
X3154951Y1468321D01*
X3154331Y1467071D01*
X3153866Y1465404D01*
X3153711Y1463529D01*
X3153866Y1461654D01*
X3154331Y1459987D01*
X3154951Y1458737D01*
X3155881Y1457696D01*
X3157121Y1457279D01*
X3158361Y1457696D01*
X3159291Y1458737D01*
X3159911Y1459987D01*
X3160376Y1461654D01*
X3160531Y1463529D01*
X3160376Y1465404D01*
X3159911Y1467071D01*
X3159291Y1468321D01*
X3158361Y1469362D01*
X3157121Y1469779D01*
G01X3166731Y1456862D02*
X3172311Y1469779D01*
G01X3179906Y1461446D02*
X3183936D01*
G01X3190911Y1459779D02*
X3191841Y1458320D01*
X3193081Y1457487D01*
X3194476Y1457279D01*
X3195716Y1457487D01*
X3196956Y1458529D01*
X3197731Y1459779D01*
X3197886Y1461029D01*
X3197576Y1462487D01*
X3196491Y1463529D01*
X3195406Y1463946D01*
X3194011D01*
G01X3195406D02*
X3196336Y1464571D01*
X3197111Y1465612D01*
X3197421Y1466862D01*
X3197111Y1468112D01*
X3196336Y1469154D01*
X3194941Y1469779D01*
X3193546Y1469571D01*
X3192151Y1468737D01*
G01X3206721Y1456862D02*
X3206411Y1457071D01*
Y1457487D01*
X3206721Y1457696D01*
X3207031Y1457487D01*
Y1457071D01*
X3206721Y1456862D01*
G01X3219121Y1469779D02*
X3217881Y1469362D01*
X3216951Y1468321D01*
X3216331Y1467071D01*
X3215866Y1465404D01*
X3215711Y1463529D01*
X3215866Y1461654D01*
X3216331Y1459987D01*
X3216951Y1458737D01*
X3217881Y1457696D01*
X3219121Y1457279D01*
X3220361Y1457696D01*
X3221291Y1458737D01*
X3221911Y1459987D01*
X3222376Y1461654D01*
X3222531Y1463529D01*
X3222376Y1465404D01*
X3221911Y1467071D01*
X3221291Y1468321D01*
X3220361Y1469362D01*
X3219121Y1469779D01*
G01X3118216Y1579646D02*
X3121936D01*
G01X3119921Y1582354D02*
Y1576937D01*
G01X3128911Y1577979D02*
X3129841Y1576520D01*
X3131081Y1575687D01*
X3132476Y1575479D01*
X3133716Y1575687D01*
X3134956Y1576729D01*
X3135731Y1577979D01*
X3135886Y1579229D01*
X3135576Y1580687D01*
X3134491Y1581729D01*
X3133406Y1582146D01*
X3132011D01*
G01X3133406D02*
X3134336Y1582771D01*
X3135111Y1583812D01*
X3135421Y1585062D01*
X3135111Y1586312D01*
X3134336Y1587354D01*
X3132941Y1587979D01*
X3131546Y1587771D01*
X3130151Y1586937D01*
G01X3144721Y1575062D02*
X3144411Y1575271D01*
Y1575687D01*
X3144721Y1575896D01*
X3145031Y1575687D01*
Y1575271D01*
X3144721Y1575062D01*
G01X3157121Y1587979D02*
X3155881Y1587562D01*
X3154951Y1586521D01*
X3154331Y1585271D01*
X3153866Y1583604D01*
X3153711Y1581729D01*
X3153866Y1579854D01*
X3154331Y1578187D01*
X3154951Y1576937D01*
X3155881Y1575896D01*
X3157121Y1575479D01*
X3158361Y1575896D01*
X3159291Y1576937D01*
X3159911Y1578187D01*
X3160376Y1579854D01*
X3160531Y1581729D01*
X3160376Y1583604D01*
X3159911Y1585271D01*
X3159291Y1586521D01*
X3158361Y1587562D01*
X3157121Y1587979D01*
G01X3166731Y1575062D02*
X3172311Y1587979D01*
G01X3179906Y1579646D02*
X3183936D01*
G01X3190911Y1577979D02*
X3191841Y1576520D01*
X3193081Y1575687D01*
X3194476Y1575479D01*
X3195716Y1575687D01*
X3196956Y1576729D01*
X3197731Y1577979D01*
X3197886Y1579229D01*
X3197576Y1580687D01*
X3196491Y1581729D01*
X3195406Y1582146D01*
X3194011D01*
G01X3195406D02*
X3196336Y1582771D01*
X3197111Y1583812D01*
X3197421Y1585062D01*
X3197111Y1586312D01*
X3196336Y1587354D01*
X3194941Y1587979D01*
X3193546Y1587771D01*
X3192151Y1586937D01*
G01X3206721Y1575062D02*
X3206411Y1575271D01*
Y1575687D01*
X3206721Y1575896D01*
X3207031Y1575687D01*
Y1575271D01*
X3206721Y1575062D01*
G01X3219121Y1587979D02*
X3217881Y1587562D01*
X3216951Y1586521D01*
X3216331Y1585271D01*
X3215866Y1583604D01*
X3215711Y1581729D01*
X3215866Y1579854D01*
X3216331Y1578187D01*
X3216951Y1576937D01*
X3217881Y1575896D01*
X3219121Y1575479D01*
X3220361Y1575896D01*
X3221291Y1576937D01*
X3221911Y1578187D01*
X3222376Y1579854D01*
X3222531Y1581729D01*
X3222376Y1583604D01*
X3221911Y1585271D01*
X3221291Y1586521D01*
X3220361Y1587562D01*
X3219121Y1587979D01*
G01X3112016Y1756946D02*
X3115736D01*
G01X3113721Y1759654D02*
Y1754237D01*
G01X3126121Y1765279D02*
X3124881Y1764862D01*
X3123951Y1763821D01*
X3123331Y1762571D01*
X3122866Y1760904D01*
X3122711Y1759029D01*
X3122866Y1757154D01*
X3123331Y1755487D01*
X3123951Y1754237D01*
X3124881Y1753196D01*
X3126121Y1752779D01*
X3127361Y1753196D01*
X3128291Y1754237D01*
X3128911Y1755487D01*
X3129376Y1757154D01*
X3129531Y1759029D01*
X3129376Y1760904D01*
X3128911Y1762571D01*
X3128291Y1763821D01*
X3127361Y1764862D01*
X3126121Y1765279D01*
G01X3138521Y1752362D02*
X3138211Y1752571D01*
Y1752987D01*
X3138521Y1753196D01*
X3138831Y1752987D01*
Y1752571D01*
X3138521Y1752362D01*
G01X3150921Y1765279D02*
X3149681Y1764862D01*
X3148751Y1763821D01*
X3148131Y1762571D01*
X3147666Y1760904D01*
X3147511Y1759029D01*
X3147666Y1757154D01*
X3148131Y1755487D01*
X3148751Y1754237D01*
X3149681Y1753196D01*
X3150921Y1752779D01*
X3152161Y1753196D01*
X3153091Y1754237D01*
X3153711Y1755487D01*
X3154176Y1757154D01*
X3154331Y1759029D01*
X3154176Y1760904D01*
X3153711Y1762571D01*
X3153091Y1763821D01*
X3152161Y1764862D01*
X3150921Y1765279D01*
G01X3160531Y1752362D02*
X3166111Y1765279D01*
G01X3173706Y1756946D02*
X3177736D01*
G01X3188121Y1752779D02*
Y1765279D01*
X3186261Y1762779D01*
G01Y1752779D02*
X3189981D01*
G01X3200521Y1765279D02*
X3199281Y1764862D01*
X3198351Y1763821D01*
X3197731Y1762571D01*
X3197266Y1760904D01*
X3197111Y1759029D01*
X3197266Y1757154D01*
X3197731Y1755487D01*
X3198351Y1754237D01*
X3199281Y1753196D01*
X3200521Y1752779D01*
X3201761Y1753196D01*
X3202691Y1754237D01*
X3203311Y1755487D01*
X3203776Y1757154D01*
X3203931Y1759029D01*
X3203776Y1760904D01*
X3203311Y1762571D01*
X3202691Y1763821D01*
X3201761Y1764862D01*
X3200521Y1765279D01*
G01X3212921Y1752362D02*
X3212611Y1752571D01*
Y1752987D01*
X3212921Y1753196D01*
X3213231Y1752987D01*
Y1752571D01*
X3212921Y1752362D01*
G01X3225321Y1765279D02*
X3224081Y1764862D01*
X3223151Y1763821D01*
X3222531Y1762571D01*
X3222066Y1760904D01*
X3221911Y1759029D01*
X3222066Y1757154D01*
X3222531Y1755487D01*
X3223151Y1754237D01*
X3224081Y1753196D01*
X3225321Y1752779D01*
X3226561Y1753196D01*
X3227491Y1754237D01*
X3228111Y1755487D01*
X3228576Y1757154D01*
X3228731Y1759029D01*
X3228576Y1760904D01*
X3228111Y1762571D01*
X3227491Y1763821D01*
X3226561Y1764862D01*
X3225321Y1765279D01*
G01X3112016Y1816046D02*
X3115736D01*
G01X3113721Y1818754D02*
Y1813337D01*
G01X3126121Y1824379D02*
X3124881Y1823962D01*
X3123951Y1822921D01*
X3123331Y1821671D01*
X3122866Y1820004D01*
X3122711Y1818129D01*
X3122866Y1816254D01*
X3123331Y1814587D01*
X3123951Y1813337D01*
X3124881Y1812296D01*
X3126121Y1811879D01*
X3127361Y1812296D01*
X3128291Y1813337D01*
X3128911Y1814587D01*
X3129376Y1816254D01*
X3129531Y1818129D01*
X3129376Y1820004D01*
X3128911Y1821671D01*
X3128291Y1822921D01*
X3127361Y1823962D01*
X3126121Y1824379D01*
G01X3138521Y1811462D02*
X3138211Y1811671D01*
Y1812087D01*
X3138521Y1812296D01*
X3138831Y1812087D01*
Y1811671D01*
X3138521Y1811462D01*
G01X3150921Y1824379D02*
X3149681Y1823962D01*
X3148751Y1822921D01*
X3148131Y1821671D01*
X3147666Y1820004D01*
X3147511Y1818129D01*
X3147666Y1816254D01*
X3148131Y1814587D01*
X3148751Y1813337D01*
X3149681Y1812296D01*
X3150921Y1811879D01*
X3152161Y1812296D01*
X3153091Y1813337D01*
X3153711Y1814587D01*
X3154176Y1816254D01*
X3154331Y1818129D01*
X3154176Y1820004D01*
X3153711Y1821671D01*
X3153091Y1822921D01*
X3152161Y1823962D01*
X3150921Y1824379D01*
G01X3160531Y1811462D02*
X3166111Y1824379D01*
G01X3173706Y1816046D02*
X3177736D01*
G01X3188121Y1811879D02*
Y1824379D01*
X3186261Y1821879D01*
G01Y1811879D02*
X3189981D01*
G01X3200521Y1824379D02*
X3199281Y1823962D01*
X3198351Y1822921D01*
X3197731Y1821671D01*
X3197266Y1820004D01*
X3197111Y1818129D01*
X3197266Y1816254D01*
X3197731Y1814587D01*
X3198351Y1813337D01*
X3199281Y1812296D01*
X3200521Y1811879D01*
X3201761Y1812296D01*
X3202691Y1813337D01*
X3203311Y1814587D01*
X3203776Y1816254D01*
X3203931Y1818129D01*
X3203776Y1820004D01*
X3203311Y1821671D01*
X3202691Y1822921D01*
X3201761Y1823962D01*
X3200521Y1824379D01*
G01X3212921Y1811462D02*
X3212611Y1811671D01*
Y1812087D01*
X3212921Y1812296D01*
X3213231Y1812087D01*
Y1811671D01*
X3212921Y1811462D01*
G01X3225321Y1824379D02*
X3224081Y1823962D01*
X3223151Y1822921D01*
X3222531Y1821671D01*
X3222066Y1820004D01*
X3221911Y1818129D01*
X3222066Y1816254D01*
X3222531Y1814587D01*
X3223151Y1813337D01*
X3224081Y1812296D01*
X3225321Y1811879D01*
X3226561Y1812296D01*
X3227491Y1813337D01*
X3228111Y1814587D01*
X3228576Y1816254D01*
X3228731Y1818129D01*
X3228576Y1820004D01*
X3228111Y1821671D01*
X3227491Y1822921D01*
X3226561Y1823962D01*
X3225321Y1824379D01*
G01X3118216Y1875146D02*
X3121936D01*
G01X3119921Y1877854D02*
Y1872437D01*
G01X3129376Y1881396D02*
X3130306Y1882645D01*
X3131391Y1883271D01*
X3132631Y1883479D01*
X3134181Y1883062D01*
X3135266Y1882021D01*
X3135576Y1880771D01*
X3135421Y1879520D01*
X3134801Y1878479D01*
X3131701Y1876396D01*
X3130306Y1874937D01*
X3129376Y1872854D01*
X3129066Y1870979D01*
X3135576D01*
G01X3144721Y1870562D02*
X3144411Y1870771D01*
Y1871187D01*
X3144721Y1871396D01*
X3145031Y1871187D01*
Y1870771D01*
X3144721Y1870562D01*
G01X3157121Y1883479D02*
X3155881Y1883062D01*
X3154951Y1882021D01*
X3154331Y1880771D01*
X3153866Y1879104D01*
X3153711Y1877229D01*
X3153866Y1875354D01*
X3154331Y1873687D01*
X3154951Y1872437D01*
X3155881Y1871396D01*
X3157121Y1870979D01*
X3158361Y1871396D01*
X3159291Y1872437D01*
X3159911Y1873687D01*
X3160376Y1875354D01*
X3160531Y1877229D01*
X3160376Y1879104D01*
X3159911Y1880771D01*
X3159291Y1882021D01*
X3158361Y1883062D01*
X3157121Y1883479D01*
G01X3166731Y1870562D02*
X3172311Y1883479D01*
G01X3179906Y1875146D02*
X3183936D01*
G01X3191376Y1881396D02*
X3192306Y1882645D01*
X3193391Y1883271D01*
X3194631Y1883479D01*
X3196181Y1883062D01*
X3197266Y1882021D01*
X3197576Y1880771D01*
X3197421Y1879520D01*
X3196801Y1878479D01*
X3193701Y1876396D01*
X3192306Y1874937D01*
X3191376Y1872854D01*
X3191066Y1870979D01*
X3197576D01*
G01X3206721Y1870562D02*
X3206411Y1870771D01*
Y1871187D01*
X3206721Y1871396D01*
X3207031Y1871187D01*
Y1870771D01*
X3206721Y1870562D01*
G01X3219121Y1883479D02*
X3217881Y1883062D01*
X3216951Y1882021D01*
X3216331Y1880771D01*
X3215866Y1879104D01*
X3215711Y1877229D01*
X3215866Y1875354D01*
X3216331Y1873687D01*
X3216951Y1872437D01*
X3217881Y1871396D01*
X3219121Y1870979D01*
X3220361Y1871396D01*
X3221291Y1872437D01*
X3221911Y1873687D01*
X3222376Y1875354D01*
X3222531Y1877229D01*
X3222376Y1879104D01*
X3221911Y1880771D01*
X3221291Y1882021D01*
X3220361Y1883062D01*
X3219121Y1883479D01*
G01X3118216Y1934246D02*
X3121936D01*
G01X3119921Y1936954D02*
Y1931537D01*
G01X3132321Y1942579D02*
X3131081Y1942162D01*
X3130151Y1941121D01*
X3129531Y1939871D01*
X3129066Y1938204D01*
X3128911Y1936329D01*
X3129066Y1934454D01*
X3129531Y1932787D01*
X3130151Y1931537D01*
X3131081Y1930496D01*
X3132321Y1930079D01*
X3133561Y1930496D01*
X3134491Y1931537D01*
X3135111Y1932787D01*
X3135576Y1934454D01*
X3135731Y1936329D01*
X3135576Y1938204D01*
X3135111Y1939871D01*
X3134491Y1941121D01*
X3133561Y1942162D01*
X3132321Y1942579D01*
G01X3144721Y1929662D02*
X3144411Y1929871D01*
Y1930287D01*
X3144721Y1930496D01*
X3145031Y1930287D01*
Y1929871D01*
X3144721Y1929662D01*
G01X3157121Y1942579D02*
X3155881Y1942162D01*
X3154951Y1941121D01*
X3154331Y1939871D01*
X3153866Y1938204D01*
X3153711Y1936329D01*
X3153866Y1934454D01*
X3154331Y1932787D01*
X3154951Y1931537D01*
X3155881Y1930496D01*
X3157121Y1930079D01*
X3158361Y1930496D01*
X3159291Y1931537D01*
X3159911Y1932787D01*
X3160376Y1934454D01*
X3160531Y1936329D01*
X3160376Y1938204D01*
X3159911Y1939871D01*
X3159291Y1941121D01*
X3158361Y1942162D01*
X3157121Y1942579D01*
G01X3166731Y1929662D02*
X3172311Y1942579D01*
G01X3179906Y1934246D02*
X3183936D01*
G01X3194321Y1930079D02*
X3195406Y1930287D01*
X3196646Y1930912D01*
X3197421Y1931954D01*
X3197731Y1933412D01*
X3197421Y1934870D01*
X3196491Y1936121D01*
X3195096Y1936746D01*
X3193546D01*
X3192616Y1937162D01*
X3191841Y1938204D01*
X3191531Y1939662D01*
X3191996Y1941121D01*
X3193081Y1942162D01*
X3194321Y1942579D01*
X3195561Y1942162D01*
X3196646Y1941121D01*
X3197111Y1939662D01*
X3196801Y1938204D01*
X3196026Y1937162D01*
X3195096Y1936746D01*
X3193546D01*
X3192151Y1936121D01*
X3191221Y1934870D01*
X3190911Y1933412D01*
X3191221Y1931954D01*
X3191996Y1930912D01*
X3193236Y1930287D01*
X3194321Y1930079D01*
G01X3206721Y1929662D02*
X3206411Y1929871D01*
Y1930287D01*
X3206721Y1930496D01*
X3207031Y1930287D01*
Y1929871D01*
X3206721Y1929662D01*
G01X3219121Y1942579D02*
X3217881Y1942162D01*
X3216951Y1941121D01*
X3216331Y1939871D01*
X3215866Y1938204D01*
X3215711Y1936329D01*
X3215866Y1934454D01*
X3216331Y1932787D01*
X3216951Y1931537D01*
X3217881Y1930496D01*
X3219121Y1930079D01*
X3220361Y1930496D01*
X3221291Y1931537D01*
X3221911Y1932787D01*
X3222376Y1934454D01*
X3222531Y1936329D01*
X3222376Y1938204D01*
X3221911Y1939871D01*
X3221291Y1941121D01*
X3220361Y1942162D01*
X3219121Y1942579D01*
G01X3118216Y1993346D02*
X3121936D01*
G01X3119921Y1996054D02*
Y1990637D01*
G01X3132321Y2001679D02*
X3131081Y2001262D01*
X3130151Y2000221D01*
X3129531Y1998971D01*
X3129066Y1997304D01*
X3128911Y1995429D01*
X3129066Y1993554D01*
X3129531Y1991887D01*
X3130151Y1990637D01*
X3131081Y1989596D01*
X3132321Y1989179D01*
X3133561Y1989596D01*
X3134491Y1990637D01*
X3135111Y1991887D01*
X3135576Y1993554D01*
X3135731Y1995429D01*
X3135576Y1997304D01*
X3135111Y1998971D01*
X3134491Y2000221D01*
X3133561Y2001262D01*
X3132321Y2001679D01*
G01X3144721Y1988762D02*
X3144411Y1988971D01*
Y1989387D01*
X3144721Y1989596D01*
X3145031Y1989387D01*
Y1988971D01*
X3144721Y1988762D01*
G01X3157121Y2001679D02*
X3155881Y2001262D01*
X3154951Y2000221D01*
X3154331Y1998971D01*
X3153866Y1997304D01*
X3153711Y1995429D01*
X3153866Y1993554D01*
X3154331Y1991887D01*
X3154951Y1990637D01*
X3155881Y1989596D01*
X3157121Y1989179D01*
X3158361Y1989596D01*
X3159291Y1990637D01*
X3159911Y1991887D01*
X3160376Y1993554D01*
X3160531Y1995429D01*
X3160376Y1997304D01*
X3159911Y1998971D01*
X3159291Y2000221D01*
X3158361Y2001262D01*
X3157121Y2001679D01*
G01X3166731Y1988762D02*
X3172311Y2001679D01*
G01X3179906Y1993346D02*
X3183936D01*
G01X3194321Y1989179D02*
X3195406Y1989387D01*
X3196646Y1990012D01*
X3197421Y1991054D01*
X3197731Y1992512D01*
X3197421Y1993970D01*
X3196491Y1995221D01*
X3195096Y1995846D01*
X3193546D01*
X3192616Y1996262D01*
X3191841Y1997304D01*
X3191531Y1998762D01*
X3191996Y2000221D01*
X3193081Y2001262D01*
X3194321Y2001679D01*
X3195561Y2001262D01*
X3196646Y2000221D01*
X3197111Y1998762D01*
X3196801Y1997304D01*
X3196026Y1996262D01*
X3195096Y1995846D01*
X3193546D01*
X3192151Y1995221D01*
X3191221Y1993970D01*
X3190911Y1992512D01*
X3191221Y1991054D01*
X3191996Y1990012D01*
X3193236Y1989387D01*
X3194321Y1989179D01*
G01X3206721Y1988762D02*
X3206411Y1988971D01*
Y1989387D01*
X3206721Y1989596D01*
X3207031Y1989387D01*
Y1988971D01*
X3206721Y1988762D01*
G01X3219121Y2001679D02*
X3217881Y2001262D01*
X3216951Y2000221D01*
X3216331Y1998971D01*
X3215866Y1997304D01*
X3215711Y1995429D01*
X3215866Y1993554D01*
X3216331Y1991887D01*
X3216951Y1990637D01*
X3217881Y1989596D01*
X3219121Y1989179D01*
X3220361Y1989596D01*
X3221291Y1990637D01*
X3221911Y1991887D01*
X3222376Y1993554D01*
X3222531Y1995429D01*
X3222376Y1997304D01*
X3221911Y1998971D01*
X3221291Y2000221D01*
X3220361Y2001262D01*
X3219121Y2001679D01*
G01X3215300Y2635432D02*
Y2647932D01*
X3219330Y2637515D01*
X3223360Y2647932D01*
Y2635432D01*
G01X3227855D02*
X3231730Y2647932D01*
X3235605Y2635432D01*
G01X3234210Y2639807D02*
X3229250D01*
G01X3240875Y2635432D02*
X3247385Y2647932D01*
G01X3240875D02*
X3247385Y2635432D01*
G01X3251880Y2631265D02*
X3261180D01*
G01X3265520Y2635432D02*
Y2647932D01*
X3268620D01*
X3269860Y2647307D01*
X3270790Y2646474D01*
X3271565Y2645224D01*
X3272185Y2643765D01*
X3272340Y2641682D01*
X3272185Y2639599D01*
X3271565Y2638140D01*
X3270790Y2636890D01*
X3269860Y2636057D01*
X3268620Y2635432D01*
X3265520D01*
G01X3284430D02*
X3278230D01*
Y2647932D01*
X3284430D01*
G01X3281950Y2641890D02*
X3278230D01*
G01X3290630Y2635432D02*
Y2647932D01*
X3294350D01*
X3295590Y2647307D01*
X3296520Y2645849D01*
X3296830Y2644182D01*
X3296520Y2642515D01*
X3295745Y2641265D01*
X3294350Y2640640D01*
X3290630D01*
G01X3306130Y2647932D02*
Y2635432D01*
G01X3302565Y2647932D02*
X3309695D01*
G01X3315275Y2635432D02*
Y2647932D01*
G01X3321785D02*
Y2635432D01*
G01Y2641682D02*
X3315275D01*
G01X3216296Y2924349D02*
Y2936849D01*
X3220326Y2926432D01*
X3224356Y2936849D01*
Y2924349D01*
G01X3228851D02*
X3232726Y2936849D01*
X3236601Y2924349D01*
G01X3235206Y2928724D02*
X3230246D01*
G01X3241871Y2924349D02*
X3248381Y2936849D01*
G01X3241871D02*
X3248381Y2924349D01*
G01X3252876Y2920182D02*
X3262176D01*
G01X3266516Y2924349D02*
Y2936849D01*
X3269616D01*
X3270856Y2936224D01*
X3271786Y2935391D01*
X3272561Y2934141D01*
X3273181Y2932682D01*
X3273336Y2930599D01*
X3273181Y2928516D01*
X3272561Y2927057D01*
X3271786Y2925807D01*
X3270856Y2924974D01*
X3269616Y2924349D01*
X3266516D01*
G01X3285426D02*
X3279226D01*
Y2936849D01*
X3285426D01*
G01X3282946Y2930807D02*
X3279226D01*
G01X3291626Y2924349D02*
Y2936849D01*
X3295346D01*
X3296586Y2936224D01*
X3297516Y2934766D01*
X3297826Y2933099D01*
X3297516Y2931432D01*
X3296741Y2930182D01*
X3295346Y2929557D01*
X3291626D01*
G01X3307126Y2936849D02*
Y2924349D01*
G01X3303561Y2936849D02*
X3310691D01*
G01X3316271Y2924349D02*
Y2936849D01*
G01X3322781D02*
Y2924349D01*
G01Y2930599D02*
X3316271D01*
G01X3216306Y3174919D02*
Y3187419D01*
X3220336Y3177002D01*
X3224366Y3187419D01*
Y3174919D01*
G01X3228861D02*
X3232736Y3187419D01*
X3236611Y3174919D01*
G01X3235216Y3179294D02*
X3230256D01*
G01X3241881Y3174919D02*
X3248391Y3187419D01*
G01X3241881D02*
X3248391Y3174919D01*
G01X3252886Y3170752D02*
X3262186D01*
G01X3266526Y3174919D02*
Y3187419D01*
X3269626D01*
X3270866Y3186794D01*
X3271796Y3185961D01*
X3272571Y3184711D01*
X3273191Y3183252D01*
X3273346Y3181169D01*
X3273191Y3179086D01*
X3272571Y3177627D01*
X3271796Y3176377D01*
X3270866Y3175544D01*
X3269626Y3174919D01*
X3266526D01*
G01X3285436D02*
X3279236D01*
Y3187419D01*
X3285436D01*
G01X3282956Y3181377D02*
X3279236D01*
G01X3291636Y3174919D02*
Y3187419D01*
X3295356D01*
X3296596Y3186794D01*
X3297526Y3185336D01*
X3297836Y3183669D01*
X3297526Y3182002D01*
X3296751Y3180752D01*
X3295356Y3180127D01*
X3291636D01*
G01X3307136Y3187419D02*
Y3174919D01*
G01X3303571Y3187419D02*
X3310701D01*
G01X3316281Y3174919D02*
Y3187419D01*
G01X3322791D02*
Y3174919D01*
G01Y3181169D02*
X3316281D01*
G01X3211960Y3430925D02*
Y3443425D01*
X3215990Y3433008D01*
X3220020Y3443425D01*
Y3430925D01*
G01X3224515D02*
X3228390Y3443425D01*
X3232265Y3430925D01*
G01X3230870Y3435300D02*
X3225910D01*
G01X3237535Y3430925D02*
X3244045Y3443425D01*
G01X3237535D02*
X3244045Y3430925D01*
G01X3248540Y3426758D02*
X3257840D01*
G01X3262180Y3430925D02*
Y3443425D01*
X3265280D01*
X3266520Y3442800D01*
X3267450Y3441967D01*
X3268225Y3440717D01*
X3268845Y3439258D01*
X3269000Y3437175D01*
X3268845Y3435092D01*
X3268225Y3433633D01*
X3267450Y3432383D01*
X3266520Y3431550D01*
X3265280Y3430925D01*
X3262180D01*
G01X3281090D02*
X3274890D01*
Y3443425D01*
X3281090D01*
G01X3278610Y3437383D02*
X3274890D01*
G01X3287290Y3430925D02*
Y3443425D01*
X3291010D01*
X3292250Y3442800D01*
X3293180Y3441342D01*
X3293490Y3439675D01*
X3293180Y3438008D01*
X3292405Y3436758D01*
X3291010Y3436133D01*
X3287290D01*
G01X3302790Y3443425D02*
Y3430925D01*
G01X3299225Y3443425D02*
X3306355D01*
G01X3311935Y3430925D02*
Y3443425D01*
G01X3318445D02*
Y3430925D01*
G01Y3437175D02*
X3311935D01*
G01X3217065Y3716387D02*
Y3728887D01*
X3221095Y3718470D01*
X3225125Y3728887D01*
Y3716387D01*
G01X3229620D02*
X3233495Y3728887D01*
X3237370Y3716387D01*
G01X3235975Y3720762D02*
X3231015D01*
G01X3242640Y3716387D02*
X3249150Y3728887D01*
G01X3242640D02*
X3249150Y3716387D01*
G01X3253645Y3712220D02*
X3262945D01*
G01X3267285Y3716387D02*
Y3728887D01*
X3270385D01*
X3271625Y3728262D01*
X3272555Y3727429D01*
X3273330Y3726179D01*
X3273950Y3724720D01*
X3274105Y3722637D01*
X3273950Y3720554D01*
X3273330Y3719095D01*
X3272555Y3717845D01*
X3271625Y3717012D01*
X3270385Y3716387D01*
X3267285D01*
G01X3286195D02*
X3279995D01*
Y3728887D01*
X3286195D01*
G01X3283715Y3722845D02*
X3279995D01*
G01X3292395Y3716387D02*
Y3728887D01*
X3296115D01*
X3297355Y3728262D01*
X3298285Y3726804D01*
X3298595Y3725137D01*
X3298285Y3723470D01*
X3297510Y3722220D01*
X3296115Y3721595D01*
X3292395D01*
G01X3307895Y3728887D02*
Y3716387D01*
G01X3304330Y3728887D02*
X3311460D01*
G01X3317040Y3716387D02*
Y3728887D01*
G01X3323550D02*
Y3716387D01*
G01Y3722637D02*
X3317040D01*
G01X3243820Y2610432D02*
X3244130Y2613140D01*
X3244595Y2615432D01*
X3245215Y2617515D01*
X3245990Y2619807D01*
X3247230Y2622932D01*
X3241030D01*
G01X3253585Y2620849D02*
X3254515Y2622098D01*
X3255600Y2622724D01*
X3256840Y2622932D01*
X3258390Y2622515D01*
X3259475Y2621474D01*
X3259785Y2620224D01*
X3259630Y2618973D01*
X3259010Y2617932D01*
X3255910Y2615849D01*
X3254515Y2614390D01*
X3253585Y2612307D01*
X3253275Y2610432D01*
X3259785D01*
G01X3268930Y2610015D02*
X3268620Y2610224D01*
Y2610640D01*
X3268930Y2610849D01*
X3269240Y2610640D01*
Y2610224D01*
X3268930Y2610015D01*
G01X3278385Y2620849D02*
X3279315Y2622098D01*
X3280400Y2622724D01*
X3281640Y2622932D01*
X3283190Y2622515D01*
X3284275Y2621474D01*
X3284585Y2620224D01*
X3284430Y2618973D01*
X3283810Y2617932D01*
X3280710Y2615849D01*
X3279315Y2614390D01*
X3278385Y2612307D01*
X3278075Y2610432D01*
X3284585D01*
G01X3290320Y2612307D02*
X3291250Y2611265D01*
X3292335Y2610640D01*
X3293730Y2610432D01*
X3295125Y2610849D01*
X3296210Y2611682D01*
X3296985Y2613140D01*
X3297140Y2614807D01*
X3296830Y2616474D01*
X3296055Y2617515D01*
X3294970Y2618349D01*
X3293885Y2618557D01*
X3292800Y2618349D01*
X3291405Y2617515D01*
X3291870Y2622932D01*
X3296055D01*
G01X3248381Y2879557D02*
X3249466Y2881016D01*
X3250396Y2881849D01*
X3251636Y2882266D01*
X3252721Y2881849D01*
X3253496Y2881016D01*
X3254116Y2879766D01*
X3254271Y2878307D01*
X3254116Y2877057D01*
X3253496Y2875807D01*
X3252566Y2874766D01*
X3251481Y2874349D01*
X3250241Y2874766D01*
X3249156Y2876015D01*
X3248536Y2877891D01*
X3248381Y2879974D01*
X3248691Y2882682D01*
X3249156Y2884141D01*
X3249931Y2885599D01*
X3251016Y2886641D01*
X3252101Y2886849D01*
X3253186Y2886432D01*
X3253961Y2885391D01*
G01X3263726Y2874349D02*
Y2886849D01*
X3261866Y2884349D01*
G01Y2874349D02*
X3265586D01*
G01X3276126Y2873932D02*
X3275816Y2874141D01*
Y2874557D01*
X3276126Y2874766D01*
X3276436Y2874557D01*
Y2874141D01*
X3276126Y2873932D01*
G01X3285116Y2876849D02*
X3286046Y2875390D01*
X3287286Y2874557D01*
X3288681Y2874349D01*
X3289921Y2874557D01*
X3291161Y2875599D01*
X3291936Y2876849D01*
X3292091Y2878099D01*
X3291781Y2879557D01*
X3290696Y2880599D01*
X3289611Y2881016D01*
X3288216D01*
G01X3289611D02*
X3290541Y2881641D01*
X3291316Y2882682D01*
X3291626Y2883932D01*
X3291316Y2885182D01*
X3290541Y2886224D01*
X3289146Y2886849D01*
X3287751Y2886641D01*
X3286356Y2885807D01*
G01X3248381Y2904557D02*
X3249466Y2906016D01*
X3250396Y2906849D01*
X3251636Y2907266D01*
X3252721Y2906849D01*
X3253496Y2906016D01*
X3254116Y2904766D01*
X3254271Y2903307D01*
X3254116Y2902057D01*
X3253496Y2900807D01*
X3252566Y2899766D01*
X3251481Y2899349D01*
X3250241Y2899766D01*
X3249156Y2901015D01*
X3248536Y2902891D01*
X3248381Y2904974D01*
X3248691Y2907682D01*
X3249156Y2909141D01*
X3249931Y2910599D01*
X3251016Y2911641D01*
X3252101Y2911849D01*
X3253186Y2911432D01*
X3253961Y2910391D01*
G01X3263726Y2899349D02*
Y2911849D01*
X3261866Y2909349D01*
G01Y2899349D02*
X3265586D01*
G01X3276126Y2898932D02*
X3275816Y2899141D01*
Y2899557D01*
X3276126Y2899766D01*
X3276436Y2899557D01*
Y2899141D01*
X3276126Y2898932D01*
G01X3285116Y2901849D02*
X3286046Y2900390D01*
X3287286Y2899557D01*
X3288681Y2899349D01*
X3289921Y2899557D01*
X3291161Y2900599D01*
X3291936Y2901849D01*
X3292091Y2903099D01*
X3291781Y2904557D01*
X3290696Y2905599D01*
X3289611Y2906016D01*
X3288216D01*
G01X3289611D02*
X3290541Y2906641D01*
X3291316Y2907682D01*
X3291626Y2908932D01*
X3291316Y2910182D01*
X3290541Y2911224D01*
X3289146Y2911849D01*
X3287751Y2911641D01*
X3286356Y2910807D01*
G01X3244826Y3124919D02*
X3245136Y3127627D01*
X3245601Y3129919D01*
X3246221Y3132002D01*
X3246996Y3134294D01*
X3248236Y3137419D01*
X3242036D01*
G01X3254591Y3135336D02*
X3255521Y3136585D01*
X3256606Y3137211D01*
X3257846Y3137419D01*
X3259396Y3137002D01*
X3260481Y3135961D01*
X3260791Y3134711D01*
X3260636Y3133460D01*
X3260016Y3132419D01*
X3256916Y3130336D01*
X3255521Y3128877D01*
X3254591Y3126794D01*
X3254281Y3124919D01*
X3260791D01*
G01X3269936Y3124502D02*
X3269626Y3124711D01*
Y3125127D01*
X3269936Y3125336D01*
X3270246Y3125127D01*
Y3124711D01*
X3269936Y3124502D01*
G01X3279391Y3135336D02*
X3280321Y3136585D01*
X3281406Y3137211D01*
X3282646Y3137419D01*
X3284196Y3137002D01*
X3285281Y3135961D01*
X3285591Y3134711D01*
X3285436Y3133460D01*
X3284816Y3132419D01*
X3281716Y3130336D01*
X3280321Y3128877D01*
X3279391Y3126794D01*
X3279081Y3124919D01*
X3285591D01*
G01X3291326Y3126794D02*
X3292256Y3125752D01*
X3293341Y3125127D01*
X3294736Y3124919D01*
X3296131Y3125336D01*
X3297216Y3126169D01*
X3297991Y3127627D01*
X3298146Y3129294D01*
X3297836Y3130961D01*
X3297061Y3132002D01*
X3295976Y3132836D01*
X3294891Y3133044D01*
X3293806Y3132836D01*
X3292411Y3132002D01*
X3292876Y3137419D01*
X3297061D01*
G01X3244826Y3149919D02*
X3245136Y3152627D01*
X3245601Y3154919D01*
X3246221Y3157002D01*
X3246996Y3159294D01*
X3248236Y3162419D01*
X3242036D01*
G01X3254591Y3160336D02*
X3255521Y3161585D01*
X3256606Y3162211D01*
X3257846Y3162419D01*
X3259396Y3162002D01*
X3260481Y3160961D01*
X3260791Y3159711D01*
X3260636Y3158460D01*
X3260016Y3157419D01*
X3256916Y3155336D01*
X3255521Y3153877D01*
X3254591Y3151794D01*
X3254281Y3149919D01*
X3260791D01*
G01X3269936Y3149502D02*
X3269626Y3149711D01*
Y3150127D01*
X3269936Y3150336D01*
X3270246Y3150127D01*
Y3149711D01*
X3269936Y3149502D01*
G01X3279391Y3160336D02*
X3280321Y3161585D01*
X3281406Y3162211D01*
X3282646Y3162419D01*
X3284196Y3162002D01*
X3285281Y3160961D01*
X3285591Y3159711D01*
X3285436Y3158460D01*
X3284816Y3157419D01*
X3281716Y3155336D01*
X3280321Y3153877D01*
X3279391Y3151794D01*
X3279081Y3149919D01*
X3285591D01*
G01X3291326Y3151794D02*
X3292256Y3150752D01*
X3293341Y3150127D01*
X3294736Y3149919D01*
X3296131Y3150336D01*
X3297216Y3151169D01*
X3297991Y3152627D01*
X3298146Y3154294D01*
X3297836Y3155961D01*
X3297061Y3157002D01*
X3295976Y3157836D01*
X3294891Y3158044D01*
X3293806Y3157836D01*
X3292411Y3157002D01*
X3292876Y3162419D01*
X3297061D01*
G01X3246990Y3380925D02*
X3248075Y3381133D01*
X3249315Y3381758D01*
X3250090Y3382800D01*
X3250400Y3384258D01*
X3250090Y3385716D01*
X3249160Y3386967D01*
X3247765Y3387592D01*
X3246215D01*
X3245285Y3388008D01*
X3244510Y3389050D01*
X3244200Y3390508D01*
X3244665Y3391967D01*
X3245750Y3393008D01*
X3246990Y3393425D01*
X3248230Y3393008D01*
X3249315Y3391967D01*
X3249780Y3390508D01*
X3249470Y3389050D01*
X3248695Y3388008D01*
X3247765Y3387592D01*
X3246215D01*
X3244820Y3386967D01*
X3243890Y3385716D01*
X3243580Y3384258D01*
X3243890Y3382800D01*
X3244665Y3381758D01*
X3245905Y3381133D01*
X3246990Y3380925D01*
G01X3255980Y3383425D02*
X3256910Y3381966D01*
X3258150Y3381133D01*
X3259545Y3380925D01*
X3260785Y3381133D01*
X3262025Y3382175D01*
X3262800Y3383425D01*
X3262955Y3384675D01*
X3262645Y3386133D01*
X3261560Y3387175D01*
X3260475Y3387592D01*
X3259080D01*
G01X3260475D02*
X3261405Y3388217D01*
X3262180Y3389258D01*
X3262490Y3390508D01*
X3262180Y3391758D01*
X3261405Y3392800D01*
X3260010Y3393425D01*
X3258615Y3393217D01*
X3257220Y3392383D01*
G01X3271790Y3380508D02*
X3271480Y3380717D01*
Y3381133D01*
X3271790Y3381342D01*
X3272100Y3381133D01*
Y3380717D01*
X3271790Y3380508D01*
G01X3281245Y3391342D02*
X3282175Y3392591D01*
X3283260Y3393217D01*
X3284500Y3393425D01*
X3286050Y3393008D01*
X3287135Y3391967D01*
X3287445Y3390717D01*
X3287290Y3389466D01*
X3286670Y3388425D01*
X3283570Y3386342D01*
X3282175Y3384883D01*
X3281245Y3382800D01*
X3280935Y3380925D01*
X3287445D01*
G01X3246990Y3405925D02*
X3248075Y3406133D01*
X3249315Y3406758D01*
X3250090Y3407800D01*
X3250400Y3409258D01*
X3250090Y3410716D01*
X3249160Y3411967D01*
X3247765Y3412592D01*
X3246215D01*
X3245285Y3413008D01*
X3244510Y3414050D01*
X3244200Y3415508D01*
X3244665Y3416967D01*
X3245750Y3418008D01*
X3246990Y3418425D01*
X3248230Y3418008D01*
X3249315Y3416967D01*
X3249780Y3415508D01*
X3249470Y3414050D01*
X3248695Y3413008D01*
X3247765Y3412592D01*
X3246215D01*
X3244820Y3411967D01*
X3243890Y3410716D01*
X3243580Y3409258D01*
X3243890Y3407800D01*
X3244665Y3406758D01*
X3245905Y3406133D01*
X3246990Y3405925D01*
G01X3255980Y3408425D02*
X3256910Y3406966D01*
X3258150Y3406133D01*
X3259545Y3405925D01*
X3260785Y3406133D01*
X3262025Y3407175D01*
X3262800Y3408425D01*
X3262955Y3409675D01*
X3262645Y3411133D01*
X3261560Y3412175D01*
X3260475Y3412592D01*
X3259080D01*
G01X3260475D02*
X3261405Y3413217D01*
X3262180Y3414258D01*
X3262490Y3415508D01*
X3262180Y3416758D01*
X3261405Y3417800D01*
X3260010Y3418425D01*
X3258615Y3418217D01*
X3257220Y3417383D01*
G01X3271790Y3405508D02*
X3271480Y3405717D01*
Y3406133D01*
X3271790Y3406342D01*
X3272100Y3406133D01*
Y3405717D01*
X3271790Y3405508D01*
G01X3281245Y3416342D02*
X3282175Y3417591D01*
X3283260Y3418217D01*
X3284500Y3418425D01*
X3286050Y3418008D01*
X3287135Y3416967D01*
X3287445Y3415717D01*
X3287290Y3414466D01*
X3286670Y3413425D01*
X3283570Y3411342D01*
X3282175Y3409883D01*
X3281245Y3407800D01*
X3280935Y3405925D01*
X3287445D01*
G01X3248685Y3643887D02*
X3249615Y3642428D01*
X3250855Y3641595D01*
X3252250Y3641387D01*
X3253490Y3641595D01*
X3254730Y3642637D01*
X3255505Y3643887D01*
X3255660Y3645137D01*
X3255350Y3646595D01*
X3254265Y3647637D01*
X3253180Y3648054D01*
X3251785D01*
G01X3253180D02*
X3254110Y3648679D01*
X3254885Y3649720D01*
X3255195Y3650970D01*
X3254885Y3652220D01*
X3254110Y3653262D01*
X3252715Y3653887D01*
X3251320Y3653679D01*
X3249925Y3652845D01*
G01X3264495Y3641387D02*
Y3653887D01*
X3262635Y3651387D01*
G01Y3641387D02*
X3266355D01*
G01X3276895Y3640970D02*
X3276585Y3641179D01*
Y3641595D01*
X3276895Y3641804D01*
X3277205Y3641595D01*
Y3641179D01*
X3276895Y3640970D01*
G01X3286350Y3651804D02*
X3287280Y3653053D01*
X3288365Y3653679D01*
X3289605Y3653887D01*
X3291155Y3653470D01*
X3292240Y3652429D01*
X3292550Y3651179D01*
X3292395Y3649928D01*
X3291775Y3648887D01*
X3288675Y3646804D01*
X3287280Y3645345D01*
X3286350Y3643262D01*
X3286040Y3641387D01*
X3292550D01*
G01X3248685Y3668887D02*
X3249615Y3667428D01*
X3250855Y3666595D01*
X3252250Y3666387D01*
X3253490Y3666595D01*
X3254730Y3667637D01*
X3255505Y3668887D01*
X3255660Y3670137D01*
X3255350Y3671595D01*
X3254265Y3672637D01*
X3253180Y3673054D01*
X3251785D01*
G01X3253180D02*
X3254110Y3673679D01*
X3254885Y3674720D01*
X3255195Y3675970D01*
X3254885Y3677220D01*
X3254110Y3678262D01*
X3252715Y3678887D01*
X3251320Y3678679D01*
X3249925Y3677845D01*
G01X3264495Y3666387D02*
Y3678887D01*
X3262635Y3676387D01*
G01Y3666387D02*
X3266355D01*
G01X3276895Y3665970D02*
X3276585Y3666179D01*
Y3666595D01*
X3276895Y3666804D01*
X3277205Y3666595D01*
Y3666179D01*
X3276895Y3665970D01*
G01X3286350Y3676804D02*
X3287280Y3678053D01*
X3288365Y3678679D01*
X3289605Y3678887D01*
X3291155Y3678470D01*
X3292240Y3677429D01*
X3292550Y3676179D01*
X3292395Y3674928D01*
X3291775Y3673887D01*
X3288675Y3671804D01*
X3287280Y3670345D01*
X3286350Y3668262D01*
X3286040Y3666387D01*
X3292550D01*
G01X3248685Y3693887D02*
X3249615Y3692428D01*
X3250855Y3691595D01*
X3252250Y3691387D01*
X3253490Y3691595D01*
X3254730Y3692637D01*
X3255505Y3693887D01*
X3255660Y3695137D01*
X3255350Y3696595D01*
X3254265Y3697637D01*
X3253180Y3698054D01*
X3251785D01*
G01X3253180D02*
X3254110Y3698679D01*
X3254885Y3699720D01*
X3255195Y3700970D01*
X3254885Y3702220D01*
X3254110Y3703262D01*
X3252715Y3703887D01*
X3251320Y3703679D01*
X3249925Y3702845D01*
G01X3264495Y3691387D02*
Y3703887D01*
X3262635Y3701387D01*
G01Y3691387D02*
X3266355D01*
G01X3276895Y3690970D02*
X3276585Y3691179D01*
Y3691595D01*
X3276895Y3691804D01*
X3277205Y3691595D01*
Y3691179D01*
X3276895Y3690970D01*
G01X3286350Y3701804D02*
X3287280Y3703053D01*
X3288365Y3703679D01*
X3289605Y3703887D01*
X3291155Y3703470D01*
X3292240Y3702429D01*
X3292550Y3701179D01*
X3292395Y3699928D01*
X3291775Y3698887D01*
X3288675Y3696804D01*
X3287280Y3695345D01*
X3286350Y3693262D01*
X3286040Y3691387D01*
X3292550D01*
G01X3278021Y2043729D02*
Y2031229D01*
G01X3274456Y2043729D02*
X3281586D01*
G01X3290421Y2031229D02*
X3289181Y2031437D01*
X3288096Y2032270D01*
X3287166Y2033521D01*
X3286546Y2034979D01*
X3286236Y2036646D01*
Y2038312D01*
X3286546Y2039979D01*
X3287166Y2041437D01*
X3288096Y2042687D01*
X3289181Y2043521D01*
X3290421Y2043729D01*
X3291661Y2043521D01*
X3292746Y2042687D01*
X3293676Y2041437D01*
X3294296Y2039979D01*
X3294606Y2038312D01*
Y2036646D01*
X3294296Y2034979D01*
X3293676Y2033521D01*
X3292746Y2032270D01*
X3291661Y2031437D01*
X3290421Y2031229D01*
G01X3299721Y2043729D02*
Y2031229D01*
X3305921D01*
G01X3318321D02*
X3312121D01*
Y2043729D01*
X3318321D01*
G01X3315841Y2037687D02*
X3312121D01*
G01X3324521Y2031229D02*
Y2043729D01*
X3328396D01*
X3329636Y2043104D01*
X3330411Y2042271D01*
X3330721Y2040604D01*
X3330411Y2038937D01*
X3329481Y2037896D01*
X3328396Y2037271D01*
X3324521D01*
G01X3328396D02*
X3330721Y2031229D01*
G01X3336146D02*
X3340021Y2043729D01*
X3343896Y2031229D01*
G01X3342501Y2035604D02*
X3337541D01*
G01X3348856Y2031229D02*
Y2043729D01*
X3355986Y2031229D01*
Y2043729D01*
G01X3368231Y2042687D02*
X3367301Y2043312D01*
X3366216Y2043729D01*
X3364976D01*
X3363581Y2043104D01*
X3362496Y2042062D01*
X3361721Y2040812D01*
X3361101Y2038729D01*
X3360946Y2036854D01*
X3361256Y2034979D01*
X3361721Y2033729D01*
X3362651Y2032479D01*
X3363736Y2031646D01*
X3364821Y2031229D01*
X3365906D01*
X3366991Y2031646D01*
X3367921Y2032270D01*
X3368696Y2033104D01*
G01X3380321Y2031229D02*
X3374121D01*
Y2043729D01*
X3380321D01*
G01X3377841Y2037687D02*
X3374121D01*
G01X3384971Y2027062D02*
X3394271D01*
G01X3402021Y2043729D02*
Y2031229D01*
G01X3398456Y2043729D02*
X3405586D01*
G01X3411321Y2031229D02*
Y2043729D01*
X3415196D01*
X3416436Y2043104D01*
X3417211Y2042271D01*
X3417521Y2040604D01*
X3417211Y2038937D01*
X3416281Y2037896D01*
X3415196Y2037271D01*
X3411321D01*
G01X3415196D02*
X3417521Y2031229D01*
G01X3422946D02*
X3426821Y2043729D01*
X3430696Y2031229D01*
G01X3429301Y2035604D02*
X3424341D01*
G01X3435346Y2043729D02*
X3439221Y2031229D01*
X3443096Y2043729D01*
G01X3454721Y2031229D02*
X3448521D01*
Y2043729D01*
X3454721D01*
G01X3452241Y2037687D02*
X3448521D01*
G01X3460921Y2043729D02*
Y2031229D01*
X3467121D01*
G01X3307316Y-75154D02*
X3311036D01*
G01X3309021Y-72446D02*
Y-77863D01*
G01X3321421Y-79321D02*
Y-66821D01*
X3319561Y-69321D01*
G01Y-79321D02*
X3323281D01*
G01X3333821Y-79738D02*
X3333511Y-79529D01*
Y-79113D01*
X3333821Y-78904D01*
X3334131Y-79113D01*
Y-79529D01*
X3333821Y-79738D01*
G01X3343586Y-77863D02*
X3344671Y-78904D01*
X3345911Y-79321D01*
X3347151Y-78904D01*
X3348236Y-77655D01*
X3349011Y-75779D01*
X3349321Y-73904D01*
Y-71613D01*
X3349011Y-69738D01*
X3348236Y-68071D01*
X3347306Y-67238D01*
X3346221Y-66821D01*
X3344981Y-67238D01*
X3344051Y-68071D01*
X3343431Y-69321D01*
X3343121Y-70988D01*
X3343431Y-72446D01*
X3344206Y-73904D01*
X3345136Y-74738D01*
X3346221Y-74946D01*
X3347461Y-74530D01*
X3348391Y-73488D01*
X3349321Y-71613D01*
G01X3355676Y-74113D02*
X3356761Y-72654D01*
X3357691Y-71821D01*
X3358931Y-71404D01*
X3360016Y-71821D01*
X3360791Y-72654D01*
X3361411Y-73904D01*
X3361566Y-75363D01*
X3361411Y-76613D01*
X3360791Y-77863D01*
X3359861Y-78904D01*
X3358776Y-79321D01*
X3357536Y-78904D01*
X3356451Y-77655D01*
X3355831Y-75779D01*
X3355676Y-73696D01*
X3355986Y-70988D01*
X3356451Y-69529D01*
X3357226Y-68071D01*
X3358311Y-67029D01*
X3359396Y-66821D01*
X3360481Y-67238D01*
X3361256Y-68279D01*
G01X3368231Y-79738D02*
X3373811Y-66821D01*
G01X3381406Y-75154D02*
X3385436D01*
G01X3395821Y-79321D02*
Y-66821D01*
X3393961Y-69321D01*
G01Y-79321D02*
X3397681D01*
G01X3408221Y-79738D02*
X3407911Y-79529D01*
Y-79113D01*
X3408221Y-78904D01*
X3408531Y-79113D01*
Y-79529D01*
X3408221Y-79738D01*
G01X3417986Y-77863D02*
X3419071Y-78904D01*
X3420311Y-79321D01*
X3421551Y-78904D01*
X3422636Y-77655D01*
X3423411Y-75779D01*
X3423721Y-73904D01*
Y-71613D01*
X3423411Y-69738D01*
X3422636Y-68071D01*
X3421706Y-67238D01*
X3420621Y-66821D01*
X3419381Y-67238D01*
X3418451Y-68071D01*
X3417831Y-69321D01*
X3417521Y-70988D01*
X3417831Y-72446D01*
X3418606Y-73904D01*
X3419536Y-74738D01*
X3420621Y-74946D01*
X3421861Y-74530D01*
X3422791Y-73488D01*
X3423721Y-71613D01*
G01X3430076Y-74113D02*
X3431161Y-72654D01*
X3432091Y-71821D01*
X3433331Y-71404D01*
X3434416Y-71821D01*
X3435191Y-72654D01*
X3435811Y-73904D01*
X3435966Y-75363D01*
X3435811Y-76613D01*
X3435191Y-77863D01*
X3434261Y-78904D01*
X3433176Y-79321D01*
X3431936Y-78904D01*
X3430851Y-77655D01*
X3430231Y-75779D01*
X3430076Y-73696D01*
X3430386Y-70988D01*
X3430851Y-69529D01*
X3431626Y-68071D01*
X3432711Y-67029D01*
X3433796Y-66821D01*
X3434881Y-67238D01*
X3435656Y-68279D01*
G01X3307316Y-16054D02*
X3311036D01*
G01X3309021Y-13346D02*
Y-18763D01*
G01X3318011Y-17721D02*
X3318941Y-19180D01*
X3320181Y-20013D01*
X3321576Y-20221D01*
X3322816Y-20013D01*
X3324056Y-18971D01*
X3324831Y-17721D01*
X3324986Y-16471D01*
X3324676Y-15013D01*
X3323591Y-13971D01*
X3322506Y-13554D01*
X3321111D01*
G01X3322506D02*
X3323436Y-12929D01*
X3324211Y-11888D01*
X3324521Y-10638D01*
X3324211Y-9388D01*
X3323436Y-8346D01*
X3322041Y-7721D01*
X3320646Y-7929D01*
X3319251Y-8763D01*
G01X3333821Y-20638D02*
X3333511Y-20429D01*
Y-20013D01*
X3333821Y-19804D01*
X3334131Y-20013D01*
Y-20429D01*
X3333821Y-20638D01*
G01X3346221Y-20221D02*
Y-7721D01*
X3344361Y-10221D01*
G01Y-20221D02*
X3348081D01*
G01X3360481D02*
Y-7721D01*
X3354746Y-16679D01*
X3362496D01*
G01X3368231Y-20638D02*
X3373811Y-7721D01*
G01X3381406Y-16054D02*
X3385436D01*
G01X3392411Y-17721D02*
X3393341Y-19180D01*
X3394581Y-20013D01*
X3395976Y-20221D01*
X3397216Y-20013D01*
X3398456Y-18971D01*
X3399231Y-17721D01*
X3399386Y-16471D01*
X3399076Y-15013D01*
X3397991Y-13971D01*
X3396906Y-13554D01*
X3395511D01*
G01X3396906D02*
X3397836Y-12929D01*
X3398611Y-11888D01*
X3398921Y-10638D01*
X3398611Y-9388D01*
X3397836Y-8346D01*
X3396441Y-7721D01*
X3395046Y-7929D01*
X3393651Y-8763D01*
G01X3408221Y-20638D02*
X3407911Y-20429D01*
Y-20013D01*
X3408221Y-19804D01*
X3408531Y-20013D01*
Y-20429D01*
X3408221Y-20638D01*
G01X3420621Y-20221D02*
Y-7721D01*
X3418761Y-10221D01*
G01Y-20221D02*
X3422481D01*
G01X3434881D02*
Y-7721D01*
X3429146Y-16679D01*
X3436896D01*
G01X3319716Y-193354D02*
X3323436D01*
G01X3321421Y-190646D02*
Y-196063D01*
G01X3335681Y-197521D02*
Y-185021D01*
X3329946Y-193979D01*
X3337696D01*
G01X3346221Y-197938D02*
X3345911Y-197729D01*
Y-197313D01*
X3346221Y-197104D01*
X3346531Y-197313D01*
Y-197729D01*
X3346221Y-197938D01*
G01X3358621Y-185021D02*
X3357381Y-185438D01*
X3356451Y-186479D01*
X3355831Y-187729D01*
X3355366Y-189396D01*
X3355211Y-191271D01*
X3355366Y-193146D01*
X3355831Y-194813D01*
X3356451Y-196063D01*
X3357381Y-197104D01*
X3358621Y-197521D01*
X3359861Y-197104D01*
X3360791Y-196063D01*
X3361411Y-194813D01*
X3361876Y-193146D01*
X3362031Y-191271D01*
X3361876Y-189396D01*
X3361411Y-187729D01*
X3360791Y-186479D01*
X3359861Y-185438D01*
X3358621Y-185021D01*
G01X3368231Y-197938D02*
X3373811Y-185021D01*
G01X3381406Y-193354D02*
X3385436D01*
G01X3397681Y-197521D02*
Y-185021D01*
X3391946Y-193979D01*
X3399696D01*
G01X3408221Y-197938D02*
X3407911Y-197729D01*
Y-197313D01*
X3408221Y-197104D01*
X3408531Y-197313D01*
Y-197729D01*
X3408221Y-197938D01*
G01X3420621Y-185021D02*
X3419381Y-185438D01*
X3418451Y-186479D01*
X3417831Y-187729D01*
X3417366Y-189396D01*
X3417211Y-191271D01*
X3417366Y-193146D01*
X3417831Y-194813D01*
X3418451Y-196063D01*
X3419381Y-197104D01*
X3420621Y-197521D01*
X3421861Y-197104D01*
X3422791Y-196063D01*
X3423411Y-194813D01*
X3423876Y-193146D01*
X3424031Y-191271D01*
X3423876Y-189396D01*
X3423411Y-187729D01*
X3422791Y-186479D01*
X3421861Y-185438D01*
X3420621Y-185021D01*
G01X3319716Y-134254D02*
X3323436D01*
G01X3321421Y-131546D02*
Y-136963D01*
G01X3335681Y-138421D02*
Y-125921D01*
X3329946Y-134879D01*
X3337696D01*
G01X3346221Y-138838D02*
X3345911Y-138629D01*
Y-138213D01*
X3346221Y-138004D01*
X3346531Y-138213D01*
Y-138629D01*
X3346221Y-138838D01*
G01X3358621Y-125921D02*
X3357381Y-126338D01*
X3356451Y-127379D01*
X3355831Y-128629D01*
X3355366Y-130296D01*
X3355211Y-132171D01*
X3355366Y-134046D01*
X3355831Y-135713D01*
X3356451Y-136963D01*
X3357381Y-138004D01*
X3358621Y-138421D01*
X3359861Y-138004D01*
X3360791Y-136963D01*
X3361411Y-135713D01*
X3361876Y-134046D01*
X3362031Y-132171D01*
X3361876Y-130296D01*
X3361411Y-128629D01*
X3360791Y-127379D01*
X3359861Y-126338D01*
X3358621Y-125921D01*
G01X3368231Y-138838D02*
X3373811Y-125921D01*
G01X3381406Y-134254D02*
X3385436D01*
G01X3397681Y-138421D02*
Y-125921D01*
X3391946Y-134879D01*
X3399696D01*
G01X3408221Y-138838D02*
X3407911Y-138629D01*
Y-138213D01*
X3408221Y-138004D01*
X3408531Y-138213D01*
Y-138629D01*
X3408221Y-138838D01*
G01X3420621Y-125921D02*
X3419381Y-126338D01*
X3418451Y-127379D01*
X3417831Y-128629D01*
X3417366Y-130296D01*
X3417211Y-132171D01*
X3417366Y-134046D01*
X3417831Y-135713D01*
X3418451Y-136963D01*
X3419381Y-138004D01*
X3420621Y-138421D01*
X3421861Y-138004D01*
X3422791Y-136963D01*
X3423411Y-135713D01*
X3423876Y-134046D01*
X3424031Y-132171D01*
X3423876Y-130296D01*
X3423411Y-128629D01*
X3422791Y-127379D01*
X3421861Y-126338D01*
X3420621Y-125921D01*
G01X3345260Y3430925D02*
Y3443425D01*
X3349290Y3433008D01*
X3353320Y3443425D01*
Y3430925D01*
G01X3358745D02*
Y3443425D01*
X3364635D01*
G01X3362465Y3437383D02*
X3358745D01*
G01X3375020Y3437175D02*
X3378120D01*
Y3433425D01*
X3377190Y3432175D01*
X3376105Y3431342D01*
X3374555Y3430925D01*
X3373005Y3431342D01*
X3371920Y3432175D01*
X3370990Y3433425D01*
X3370370Y3434883D01*
X3370060Y3436550D01*
Y3438008D01*
X3370370Y3439258D01*
X3370990Y3440717D01*
X3371920Y3441967D01*
X3372850Y3442800D01*
X3374090Y3443425D01*
X3375175D01*
X3376415Y3443008D01*
X3377345Y3442175D01*
G01X3381840Y3426758D02*
X3391140D01*
G01X3395635Y3432591D02*
X3396875Y3431550D01*
X3398270Y3430925D01*
X3399510D01*
X3400750Y3431550D01*
X3401680Y3432591D01*
X3402145Y3434050D01*
X3401835Y3435508D01*
X3401060Y3436758D01*
X3399665Y3437592D01*
X3397805Y3438008D01*
X3396720Y3438842D01*
X3396255Y3440300D01*
X3396565Y3441758D01*
X3397340Y3442800D01*
X3398425Y3443425D01*
X3399510D01*
X3400595Y3443008D01*
X3401525Y3441967D01*
G01X3411290Y3443425D02*
Y3430925D01*
G01X3407725Y3443425D02*
X3414855D01*
G01X3420280D02*
Y3434467D01*
X3420900Y3432591D01*
X3422140Y3431342D01*
X3423690Y3430925D01*
X3425240Y3431342D01*
X3426480Y3432591D01*
X3427100Y3434467D01*
Y3443425D01*
G01X3437330Y3437592D02*
X3437950Y3438217D01*
X3438415Y3439258D01*
X3438725Y3440717D01*
X3438415Y3441967D01*
X3437795Y3442800D01*
X3436710Y3443425D01*
X3432525D01*
Y3430925D01*
X3437640D01*
X3438725Y3431758D01*
X3439345Y3433008D01*
X3439655Y3434467D01*
X3439345Y3435925D01*
X3438415Y3437175D01*
X3437330Y3437592D01*
X3432525D01*
G01X3348600Y2635432D02*
Y2647932D01*
X3352630Y2637515D01*
X3356660Y2647932D01*
Y2635432D01*
G01X3362085D02*
Y2647932D01*
X3367975D01*
G01X3365805Y2641890D02*
X3362085D01*
G01X3378360Y2641682D02*
X3381460D01*
Y2637932D01*
X3380530Y2636682D01*
X3379445Y2635849D01*
X3377895Y2635432D01*
X3376345Y2635849D01*
X3375260Y2636682D01*
X3374330Y2637932D01*
X3373710Y2639390D01*
X3373400Y2641057D01*
Y2642515D01*
X3373710Y2643765D01*
X3374330Y2645224D01*
X3375260Y2646474D01*
X3376190Y2647307D01*
X3377430Y2647932D01*
X3378515D01*
X3379755Y2647515D01*
X3380685Y2646682D01*
G01X3385180Y2631265D02*
X3394480D01*
G01X3398975Y2637098D02*
X3400215Y2636057D01*
X3401610Y2635432D01*
X3402850D01*
X3404090Y2636057D01*
X3405020Y2637098D01*
X3405485Y2638557D01*
X3405175Y2640015D01*
X3404400Y2641265D01*
X3403005Y2642099D01*
X3401145Y2642515D01*
X3400060Y2643349D01*
X3399595Y2644807D01*
X3399905Y2646265D01*
X3400680Y2647307D01*
X3401765Y2647932D01*
X3402850D01*
X3403935Y2647515D01*
X3404865Y2646474D01*
G01X3414630Y2647932D02*
Y2635432D01*
G01X3411065Y2647932D02*
X3418195D01*
G01X3423620D02*
Y2638974D01*
X3424240Y2637098D01*
X3425480Y2635849D01*
X3427030Y2635432D01*
X3428580Y2635849D01*
X3429820Y2637098D01*
X3430440Y2638974D01*
Y2647932D01*
G01X3440670Y2642099D02*
X3441290Y2642724D01*
X3441755Y2643765D01*
X3442065Y2645224D01*
X3441755Y2646474D01*
X3441135Y2647307D01*
X3440050Y2647932D01*
X3435865D01*
Y2635432D01*
X3440980D01*
X3442065Y2636265D01*
X3442685Y2637515D01*
X3442995Y2638974D01*
X3442685Y2640432D01*
X3441755Y2641682D01*
X3440670Y2642099D01*
X3435865D01*
G01X3349596Y2924349D02*
Y2936849D01*
X3353626Y2926432D01*
X3357656Y2936849D01*
Y2924349D01*
G01X3363081D02*
Y2936849D01*
X3368971D01*
G01X3366801Y2930807D02*
X3363081D01*
G01X3379356Y2930599D02*
X3382456D01*
Y2926849D01*
X3381526Y2925599D01*
X3380441Y2924766D01*
X3378891Y2924349D01*
X3377341Y2924766D01*
X3376256Y2925599D01*
X3375326Y2926849D01*
X3374706Y2928307D01*
X3374396Y2929974D01*
Y2931432D01*
X3374706Y2932682D01*
X3375326Y2934141D01*
X3376256Y2935391D01*
X3377186Y2936224D01*
X3378426Y2936849D01*
X3379511D01*
X3380751Y2936432D01*
X3381681Y2935599D01*
G01X3386176Y2920182D02*
X3395476D01*
G01X3399971Y2926015D02*
X3401211Y2924974D01*
X3402606Y2924349D01*
X3403846D01*
X3405086Y2924974D01*
X3406016Y2926015D01*
X3406481Y2927474D01*
X3406171Y2928932D01*
X3405396Y2930182D01*
X3404001Y2931016D01*
X3402141Y2931432D01*
X3401056Y2932266D01*
X3400591Y2933724D01*
X3400901Y2935182D01*
X3401676Y2936224D01*
X3402761Y2936849D01*
X3403846D01*
X3404931Y2936432D01*
X3405861Y2935391D01*
G01X3415626Y2936849D02*
Y2924349D01*
G01X3412061Y2936849D02*
X3419191D01*
G01X3424616D02*
Y2927891D01*
X3425236Y2926015D01*
X3426476Y2924766D01*
X3428026Y2924349D01*
X3429576Y2924766D01*
X3430816Y2926015D01*
X3431436Y2927891D01*
Y2936849D01*
G01X3441666Y2931016D02*
X3442286Y2931641D01*
X3442751Y2932682D01*
X3443061Y2934141D01*
X3442751Y2935391D01*
X3442131Y2936224D01*
X3441046Y2936849D01*
X3436861D01*
Y2924349D01*
X3441976D01*
X3443061Y2925182D01*
X3443681Y2926432D01*
X3443991Y2927891D01*
X3443681Y2929349D01*
X3442751Y2930599D01*
X3441666Y2931016D01*
X3436861D01*
G01X3349606Y3174919D02*
Y3187419D01*
X3353636Y3177002D01*
X3357666Y3187419D01*
Y3174919D01*
G01X3363091D02*
Y3187419D01*
X3368981D01*
G01X3366811Y3181377D02*
X3363091D01*
G01X3379366Y3181169D02*
X3382466D01*
Y3177419D01*
X3381536Y3176169D01*
X3380451Y3175336D01*
X3378901Y3174919D01*
X3377351Y3175336D01*
X3376266Y3176169D01*
X3375336Y3177419D01*
X3374716Y3178877D01*
X3374406Y3180544D01*
Y3182002D01*
X3374716Y3183252D01*
X3375336Y3184711D01*
X3376266Y3185961D01*
X3377196Y3186794D01*
X3378436Y3187419D01*
X3379521D01*
X3380761Y3187002D01*
X3381691Y3186169D01*
G01X3386186Y3170752D02*
X3395486D01*
G01X3399981Y3176585D02*
X3401221Y3175544D01*
X3402616Y3174919D01*
X3403856D01*
X3405096Y3175544D01*
X3406026Y3176585D01*
X3406491Y3178044D01*
X3406181Y3179502D01*
X3405406Y3180752D01*
X3404011Y3181586D01*
X3402151Y3182002D01*
X3401066Y3182836D01*
X3400601Y3184294D01*
X3400911Y3185752D01*
X3401686Y3186794D01*
X3402771Y3187419D01*
X3403856D01*
X3404941Y3187002D01*
X3405871Y3185961D01*
G01X3415636Y3187419D02*
Y3174919D01*
G01X3412071Y3187419D02*
X3419201D01*
G01X3424626D02*
Y3178461D01*
X3425246Y3176585D01*
X3426486Y3175336D01*
X3428036Y3174919D01*
X3429586Y3175336D01*
X3430826Y3176585D01*
X3431446Y3178461D01*
Y3187419D01*
G01X3441676Y3181586D02*
X3442296Y3182211D01*
X3442761Y3183252D01*
X3443071Y3184711D01*
X3442761Y3185961D01*
X3442141Y3186794D01*
X3441056Y3187419D01*
X3436871D01*
Y3174919D01*
X3441986D01*
X3443071Y3175752D01*
X3443691Y3177002D01*
X3444001Y3178461D01*
X3443691Y3179919D01*
X3442761Y3181169D01*
X3441676Y3181586D01*
X3436871D01*
G01X3350365Y3716387D02*
Y3728887D01*
X3354395Y3718470D01*
X3358425Y3728887D01*
Y3716387D01*
G01X3363850D02*
Y3728887D01*
X3369740D01*
G01X3367570Y3722845D02*
X3363850D01*
G01X3380125Y3722637D02*
X3383225D01*
Y3718887D01*
X3382295Y3717637D01*
X3381210Y3716804D01*
X3379660Y3716387D01*
X3378110Y3716804D01*
X3377025Y3717637D01*
X3376095Y3718887D01*
X3375475Y3720345D01*
X3375165Y3722012D01*
Y3723470D01*
X3375475Y3724720D01*
X3376095Y3726179D01*
X3377025Y3727429D01*
X3377955Y3728262D01*
X3379195Y3728887D01*
X3380280D01*
X3381520Y3728470D01*
X3382450Y3727637D01*
G01X3386945Y3712220D02*
X3396245D01*
G01X3400740Y3718053D02*
X3401980Y3717012D01*
X3403375Y3716387D01*
X3404615D01*
X3405855Y3717012D01*
X3406785Y3718053D01*
X3407250Y3719512D01*
X3406940Y3720970D01*
X3406165Y3722220D01*
X3404770Y3723054D01*
X3402910Y3723470D01*
X3401825Y3724304D01*
X3401360Y3725762D01*
X3401670Y3727220D01*
X3402445Y3728262D01*
X3403530Y3728887D01*
X3404615D01*
X3405700Y3728470D01*
X3406630Y3727429D01*
G01X3416395Y3728887D02*
Y3716387D01*
G01X3412830Y3728887D02*
X3419960D01*
G01X3425385D02*
Y3719929D01*
X3426005Y3718053D01*
X3427245Y3716804D01*
X3428795Y3716387D01*
X3430345Y3716804D01*
X3431585Y3718053D01*
X3432205Y3719929D01*
Y3728887D01*
G01X3442435Y3723054D02*
X3443055Y3723679D01*
X3443520Y3724720D01*
X3443830Y3726179D01*
X3443520Y3727429D01*
X3442900Y3728262D01*
X3441815Y3728887D01*
X3437630D01*
Y3716387D01*
X3442745D01*
X3443830Y3717220D01*
X3444450Y3718470D01*
X3444760Y3719929D01*
X3444450Y3721387D01*
X3443520Y3722637D01*
X3442435Y3723054D01*
X3437630D01*
G01X3369006Y43046D02*
X3373036D01*
G01X3369006Y102146D02*
X3373036D01*
G01X3369006Y161246D02*
X3373036D01*
G01X3369006Y220346D02*
X3373036D01*
G01X3369006Y279446D02*
X3373036D01*
G01X3369006Y338546D02*
X3373036D01*
G01X3369006Y397646D02*
X3373036D01*
G01X3369006Y456746D02*
X3373036D01*
G01X3369006Y515846D02*
X3373036D01*
G01X3369006Y574946D02*
X3373036D01*
G01X3369006Y634046D02*
X3373036D01*
G01X3369006Y693146D02*
X3373036D01*
G01X3369006Y752246D02*
X3373036D01*
G01X3369006Y811346D02*
X3373036D01*
G01X3369006Y870446D02*
X3373036D01*
G01X3369006Y929546D02*
X3373036D01*
G01X3369006Y988646D02*
X3373036D01*
G01X3369006Y1047746D02*
X3373036D01*
G01X3369006Y1106846D02*
X3373036D01*
G01X3369006Y1165946D02*
X3373036D01*
G01X3369006Y1225046D02*
X3373036D01*
G01X3369006Y1284146D02*
X3373036D01*
G01X3369006Y1343246D02*
X3373036D01*
G01X3369006Y1402346D02*
X3373036D01*
G01X3369006Y1461446D02*
X3373036D01*
G01X3369006Y1520546D02*
X3373036D01*
G01X3369006Y1579646D02*
X3373036D01*
G01X3369006Y1638746D02*
X3373036D01*
G01X3369006Y1697846D02*
X3373036D01*
G01X3369006Y1756946D02*
X3373036D01*
G01X3369006Y1816046D02*
X3373036D01*
G01X3369006Y1875146D02*
X3373036D01*
G01X3369006Y1934246D02*
X3373036D01*
G01X3369006Y1993346D02*
X3373036D01*
G01X3394015Y2614599D02*
X3398045D01*
G01X3395011Y2878516D02*
X3399041D01*
G01X3395011Y2903516D02*
X3399041D01*
G01X3395021Y3129086D02*
X3399051D01*
G01X3395021Y3154086D02*
X3399051D01*
G01X3390675Y3385092D02*
X3394705D01*
G01X3390675Y3410092D02*
X3394705D01*
G01X3395780Y3645554D02*
X3399810D01*
G01X3395780Y3670554D02*
X3399810D01*
G01X3395780Y3695554D02*
X3399810D01*
G01X3475956Y-197521D02*
Y-185021D01*
X3483086Y-197521D01*
Y-185021D01*
G01X3491921Y-197521D02*
X3490681Y-197313D01*
X3489596Y-196480D01*
X3488666Y-195229D01*
X3488046Y-193771D01*
X3487736Y-192104D01*
Y-190438D01*
X3488046Y-188771D01*
X3488666Y-187313D01*
X3489596Y-186063D01*
X3490681Y-185229D01*
X3491921Y-185021D01*
X3493161Y-185229D01*
X3494246Y-186063D01*
X3495176Y-187313D01*
X3495796Y-188771D01*
X3496106Y-190438D01*
Y-192104D01*
X3495796Y-193771D01*
X3495176Y-195229D01*
X3494246Y-196480D01*
X3493161Y-197313D01*
X3491921Y-197521D01*
G01X3500756D02*
Y-185021D01*
X3507886Y-197521D01*
Y-185021D01*
G01X3514706Y-193354D02*
X3518736D01*
G01X3526021Y-197521D02*
Y-185021D01*
X3529741D01*
X3530981Y-185646D01*
X3531911Y-187104D01*
X3532221Y-188771D01*
X3531911Y-190438D01*
X3531136Y-191688D01*
X3529741Y-192313D01*
X3526021D01*
G01X3538421Y-185021D02*
Y-197521D01*
X3544621D01*
G01X3550046D02*
X3553921Y-185021D01*
X3557796Y-197521D01*
G01X3556401Y-193146D02*
X3551441D01*
G01X3566321Y-185021D02*
Y-197521D01*
G01X3562756Y-185021D02*
X3569886D01*
G01X3581821Y-197521D02*
X3575621D01*
Y-185021D01*
X3581821D01*
G01X3579341Y-191063D02*
X3575621D01*
G01X3587711Y-197521D02*
Y-185021D01*
X3590811D01*
X3592051Y-185646D01*
X3592981Y-186479D01*
X3593756Y-187729D01*
X3594376Y-189188D01*
X3594531Y-191271D01*
X3594376Y-193354D01*
X3593756Y-194813D01*
X3592981Y-196063D01*
X3592051Y-196896D01*
X3590811Y-197521D01*
X3587711D01*
G01X3475956Y-138421D02*
Y-125921D01*
X3483086Y-138421D01*
Y-125921D01*
G01X3491921Y-138421D02*
X3490681Y-138213D01*
X3489596Y-137380D01*
X3488666Y-136129D01*
X3488046Y-134671D01*
X3487736Y-133004D01*
Y-131338D01*
X3488046Y-129671D01*
X3488666Y-128213D01*
X3489596Y-126963D01*
X3490681Y-126129D01*
X3491921Y-125921D01*
X3493161Y-126129D01*
X3494246Y-126963D01*
X3495176Y-128213D01*
X3495796Y-129671D01*
X3496106Y-131338D01*
Y-133004D01*
X3495796Y-134671D01*
X3495176Y-136129D01*
X3494246Y-137380D01*
X3493161Y-138213D01*
X3491921Y-138421D01*
G01X3500756D02*
Y-125921D01*
X3507886Y-138421D01*
Y-125921D01*
G01X3514706Y-134254D02*
X3518736D01*
G01X3526021Y-138421D02*
Y-125921D01*
X3529741D01*
X3530981Y-126546D01*
X3531911Y-128004D01*
X3532221Y-129671D01*
X3531911Y-131338D01*
X3531136Y-132588D01*
X3529741Y-133213D01*
X3526021D01*
G01X3538421Y-125921D02*
Y-138421D01*
X3544621D01*
G01X3550046D02*
X3553921Y-125921D01*
X3557796Y-138421D01*
G01X3556401Y-134046D02*
X3551441D01*
G01X3566321Y-125921D02*
Y-138421D01*
G01X3562756Y-125921D02*
X3569886D01*
G01X3581821Y-138421D02*
X3575621D01*
Y-125921D01*
X3581821D01*
G01X3579341Y-131963D02*
X3575621D01*
G01X3587711Y-138421D02*
Y-125921D01*
X3590811D01*
X3592051Y-126546D01*
X3592981Y-127379D01*
X3593756Y-128629D01*
X3594376Y-130088D01*
X3594531Y-132171D01*
X3594376Y-134254D01*
X3593756Y-135713D01*
X3592981Y-136963D01*
X3592051Y-137796D01*
X3590811Y-138421D01*
X3587711D01*
G01X3475956Y38879D02*
Y51379D01*
X3483086Y38879D01*
Y51379D01*
G01X3491921Y38879D02*
X3490681Y39087D01*
X3489596Y39920D01*
X3488666Y41171D01*
X3488046Y42629D01*
X3487736Y44296D01*
Y45962D01*
X3488046Y47629D01*
X3488666Y49087D01*
X3489596Y50337D01*
X3490681Y51171D01*
X3491921Y51379D01*
X3493161Y51171D01*
X3494246Y50337D01*
X3495176Y49087D01*
X3495796Y47629D01*
X3496106Y45962D01*
Y44296D01*
X3495796Y42629D01*
X3495176Y41171D01*
X3494246Y39920D01*
X3493161Y39087D01*
X3491921Y38879D01*
G01X3500756D02*
Y51379D01*
X3507886Y38879D01*
Y51379D01*
G01X3514706Y43046D02*
X3518736D01*
G01X3526021Y38879D02*
Y51379D01*
X3529741D01*
X3530981Y50754D01*
X3531911Y49296D01*
X3532221Y47629D01*
X3531911Y45962D01*
X3531136Y44712D01*
X3529741Y44087D01*
X3526021D01*
G01X3538421Y51379D02*
Y38879D01*
X3544621D01*
G01X3550046D02*
X3553921Y51379D01*
X3557796Y38879D01*
G01X3556401Y43254D02*
X3551441D01*
G01X3566321Y51379D02*
Y38879D01*
G01X3562756Y51379D02*
X3569886D01*
G01X3581821Y38879D02*
X3575621D01*
Y51379D01*
X3581821D01*
G01X3579341Y45337D02*
X3575621D01*
G01X3587711Y38879D02*
Y51379D01*
X3590811D01*
X3592051Y50754D01*
X3592981Y49921D01*
X3593756Y48671D01*
X3594376Y47212D01*
X3594531Y45129D01*
X3594376Y43046D01*
X3593756Y41587D01*
X3592981Y40337D01*
X3592051Y39504D01*
X3590811Y38879D01*
X3587711D01*
G01X3475956Y97979D02*
Y110479D01*
X3483086Y97979D01*
Y110479D01*
G01X3491921Y97979D02*
X3490681Y98187D01*
X3489596Y99020D01*
X3488666Y100271D01*
X3488046Y101729D01*
X3487736Y103396D01*
Y105062D01*
X3488046Y106729D01*
X3488666Y108187D01*
X3489596Y109437D01*
X3490681Y110271D01*
X3491921Y110479D01*
X3493161Y110271D01*
X3494246Y109437D01*
X3495176Y108187D01*
X3495796Y106729D01*
X3496106Y105062D01*
Y103396D01*
X3495796Y101729D01*
X3495176Y100271D01*
X3494246Y99020D01*
X3493161Y98187D01*
X3491921Y97979D01*
G01X3500756D02*
Y110479D01*
X3507886Y97979D01*
Y110479D01*
G01X3514706Y102146D02*
X3518736D01*
G01X3526021Y97979D02*
Y110479D01*
X3529741D01*
X3530981Y109854D01*
X3531911Y108396D01*
X3532221Y106729D01*
X3531911Y105062D01*
X3531136Y103812D01*
X3529741Y103187D01*
X3526021D01*
G01X3538421Y110479D02*
Y97979D01*
X3544621D01*
G01X3550046D02*
X3553921Y110479D01*
X3557796Y97979D01*
G01X3556401Y102354D02*
X3551441D01*
G01X3566321Y110479D02*
Y97979D01*
G01X3562756Y110479D02*
X3569886D01*
G01X3581821Y97979D02*
X3575621D01*
Y110479D01*
X3581821D01*
G01X3579341Y104437D02*
X3575621D01*
G01X3587711Y97979D02*
Y110479D01*
X3590811D01*
X3592051Y109854D01*
X3592981Y109021D01*
X3593756Y107771D01*
X3594376Y106312D01*
X3594531Y104229D01*
X3594376Y102146D01*
X3593756Y100687D01*
X3592981Y99437D01*
X3592051Y98604D01*
X3590811Y97979D01*
X3587711D01*
G01X3475956Y157079D02*
Y169579D01*
X3483086Y157079D01*
Y169579D01*
G01X3491921Y157079D02*
X3490681Y157287D01*
X3489596Y158120D01*
X3488666Y159371D01*
X3488046Y160829D01*
X3487736Y162496D01*
Y164162D01*
X3488046Y165829D01*
X3488666Y167287D01*
X3489596Y168537D01*
X3490681Y169371D01*
X3491921Y169579D01*
X3493161Y169371D01*
X3494246Y168537D01*
X3495176Y167287D01*
X3495796Y165829D01*
X3496106Y164162D01*
Y162496D01*
X3495796Y160829D01*
X3495176Y159371D01*
X3494246Y158120D01*
X3493161Y157287D01*
X3491921Y157079D01*
G01X3500756D02*
Y169579D01*
X3507886Y157079D01*
Y169579D01*
G01X3514706Y161246D02*
X3518736D01*
G01X3526021Y157079D02*
Y169579D01*
X3529741D01*
X3530981Y168954D01*
X3531911Y167496D01*
X3532221Y165829D01*
X3531911Y164162D01*
X3531136Y162912D01*
X3529741Y162287D01*
X3526021D01*
G01X3538421Y169579D02*
Y157079D01*
X3544621D01*
G01X3550046D02*
X3553921Y169579D01*
X3557796Y157079D01*
G01X3556401Y161454D02*
X3551441D01*
G01X3566321Y169579D02*
Y157079D01*
G01X3562756Y169579D02*
X3569886D01*
G01X3581821Y157079D02*
X3575621D01*
Y169579D01*
X3581821D01*
G01X3579341Y163537D02*
X3575621D01*
G01X3587711Y157079D02*
Y169579D01*
X3590811D01*
X3592051Y168954D01*
X3592981Y168121D01*
X3593756Y166871D01*
X3594376Y165412D01*
X3594531Y163329D01*
X3594376Y161246D01*
X3593756Y159787D01*
X3592981Y158537D01*
X3592051Y157704D01*
X3590811Y157079D01*
X3587711D01*
G01X3475956Y216179D02*
Y228679D01*
X3483086Y216179D01*
Y228679D01*
G01X3491921Y216179D02*
X3490681Y216387D01*
X3489596Y217220D01*
X3488666Y218471D01*
X3488046Y219929D01*
X3487736Y221596D01*
Y223262D01*
X3488046Y224929D01*
X3488666Y226387D01*
X3489596Y227637D01*
X3490681Y228471D01*
X3491921Y228679D01*
X3493161Y228471D01*
X3494246Y227637D01*
X3495176Y226387D01*
X3495796Y224929D01*
X3496106Y223262D01*
Y221596D01*
X3495796Y219929D01*
X3495176Y218471D01*
X3494246Y217220D01*
X3493161Y216387D01*
X3491921Y216179D01*
G01X3500756D02*
Y228679D01*
X3507886Y216179D01*
Y228679D01*
G01X3514706Y220346D02*
X3518736D01*
G01X3526021Y216179D02*
Y228679D01*
X3529741D01*
X3530981Y228054D01*
X3531911Y226596D01*
X3532221Y224929D01*
X3531911Y223262D01*
X3531136Y222012D01*
X3529741Y221387D01*
X3526021D01*
G01X3538421Y228679D02*
Y216179D01*
X3544621D01*
G01X3550046D02*
X3553921Y228679D01*
X3557796Y216179D01*
G01X3556401Y220554D02*
X3551441D01*
G01X3566321Y228679D02*
Y216179D01*
G01X3562756Y228679D02*
X3569886D01*
G01X3581821Y216179D02*
X3575621D01*
Y228679D01*
X3581821D01*
G01X3579341Y222637D02*
X3575621D01*
G01X3587711Y216179D02*
Y228679D01*
X3590811D01*
X3592051Y228054D01*
X3592981Y227221D01*
X3593756Y225971D01*
X3594376Y224512D01*
X3594531Y222429D01*
X3594376Y220346D01*
X3593756Y218887D01*
X3592981Y217637D01*
X3592051Y216804D01*
X3590811Y216179D01*
X3587711D01*
G01X3475956Y275279D02*
Y287779D01*
X3483086Y275279D01*
Y287779D01*
G01X3491921Y275279D02*
X3490681Y275487D01*
X3489596Y276320D01*
X3488666Y277571D01*
X3488046Y279029D01*
X3487736Y280696D01*
Y282362D01*
X3488046Y284029D01*
X3488666Y285487D01*
X3489596Y286737D01*
X3490681Y287571D01*
X3491921Y287779D01*
X3493161Y287571D01*
X3494246Y286737D01*
X3495176Y285487D01*
X3495796Y284029D01*
X3496106Y282362D01*
Y280696D01*
X3495796Y279029D01*
X3495176Y277571D01*
X3494246Y276320D01*
X3493161Y275487D01*
X3491921Y275279D01*
G01X3500756D02*
Y287779D01*
X3507886Y275279D01*
Y287779D01*
G01X3514706Y279446D02*
X3518736D01*
G01X3526021Y275279D02*
Y287779D01*
X3529741D01*
X3530981Y287154D01*
X3531911Y285696D01*
X3532221Y284029D01*
X3531911Y282362D01*
X3531136Y281112D01*
X3529741Y280487D01*
X3526021D01*
G01X3538421Y287779D02*
Y275279D01*
X3544621D01*
G01X3550046D02*
X3553921Y287779D01*
X3557796Y275279D01*
G01X3556401Y279654D02*
X3551441D01*
G01X3566321Y287779D02*
Y275279D01*
G01X3562756Y287779D02*
X3569886D01*
G01X3581821Y275279D02*
X3575621D01*
Y287779D01*
X3581821D01*
G01X3579341Y281737D02*
X3575621D01*
G01X3587711Y275279D02*
Y287779D01*
X3590811D01*
X3592051Y287154D01*
X3592981Y286321D01*
X3593756Y285071D01*
X3594376Y283612D01*
X3594531Y281529D01*
X3594376Y279446D01*
X3593756Y277987D01*
X3592981Y276737D01*
X3592051Y275904D01*
X3590811Y275279D01*
X3587711D01*
G01X3475956Y334379D02*
Y346879D01*
X3483086Y334379D01*
Y346879D01*
G01X3491921Y334379D02*
X3490681Y334587D01*
X3489596Y335420D01*
X3488666Y336671D01*
X3488046Y338129D01*
X3487736Y339796D01*
Y341462D01*
X3488046Y343129D01*
X3488666Y344587D01*
X3489596Y345837D01*
X3490681Y346671D01*
X3491921Y346879D01*
X3493161Y346671D01*
X3494246Y345837D01*
X3495176Y344587D01*
X3495796Y343129D01*
X3496106Y341462D01*
Y339796D01*
X3495796Y338129D01*
X3495176Y336671D01*
X3494246Y335420D01*
X3493161Y334587D01*
X3491921Y334379D01*
G01X3500756D02*
Y346879D01*
X3507886Y334379D01*
Y346879D01*
G01X3514706Y338546D02*
X3518736D01*
G01X3526021Y334379D02*
Y346879D01*
X3529741D01*
X3530981Y346254D01*
X3531911Y344796D01*
X3532221Y343129D01*
X3531911Y341462D01*
X3531136Y340212D01*
X3529741Y339587D01*
X3526021D01*
G01X3538421Y346879D02*
Y334379D01*
X3544621D01*
G01X3550046D02*
X3553921Y346879D01*
X3557796Y334379D01*
G01X3556401Y338754D02*
X3551441D01*
G01X3566321Y346879D02*
Y334379D01*
G01X3562756Y346879D02*
X3569886D01*
G01X3581821Y334379D02*
X3575621D01*
Y346879D01*
X3581821D01*
G01X3579341Y340837D02*
X3575621D01*
G01X3587711Y334379D02*
Y346879D01*
X3590811D01*
X3592051Y346254D01*
X3592981Y345421D01*
X3593756Y344171D01*
X3594376Y342712D01*
X3594531Y340629D01*
X3594376Y338546D01*
X3593756Y337087D01*
X3592981Y335837D01*
X3592051Y335004D01*
X3590811Y334379D01*
X3587711D01*
G01X3475956Y393479D02*
Y405979D01*
X3483086Y393479D01*
Y405979D01*
G01X3491921Y393479D02*
X3490681Y393687D01*
X3489596Y394520D01*
X3488666Y395771D01*
X3488046Y397229D01*
X3487736Y398896D01*
Y400562D01*
X3488046Y402229D01*
X3488666Y403687D01*
X3489596Y404937D01*
X3490681Y405771D01*
X3491921Y405979D01*
X3493161Y405771D01*
X3494246Y404937D01*
X3495176Y403687D01*
X3495796Y402229D01*
X3496106Y400562D01*
Y398896D01*
X3495796Y397229D01*
X3495176Y395771D01*
X3494246Y394520D01*
X3493161Y393687D01*
X3491921Y393479D01*
G01X3500756D02*
Y405979D01*
X3507886Y393479D01*
Y405979D01*
G01X3514706Y397646D02*
X3518736D01*
G01X3526021Y393479D02*
Y405979D01*
X3529741D01*
X3530981Y405354D01*
X3531911Y403896D01*
X3532221Y402229D01*
X3531911Y400562D01*
X3531136Y399312D01*
X3529741Y398687D01*
X3526021D01*
G01X3538421Y405979D02*
Y393479D01*
X3544621D01*
G01X3550046D02*
X3553921Y405979D01*
X3557796Y393479D01*
G01X3556401Y397854D02*
X3551441D01*
G01X3566321Y405979D02*
Y393479D01*
G01X3562756Y405979D02*
X3569886D01*
G01X3581821Y393479D02*
X3575621D01*
Y405979D01*
X3581821D01*
G01X3579341Y399937D02*
X3575621D01*
G01X3587711Y393479D02*
Y405979D01*
X3590811D01*
X3592051Y405354D01*
X3592981Y404521D01*
X3593756Y403271D01*
X3594376Y401812D01*
X3594531Y399729D01*
X3594376Y397646D01*
X3593756Y396187D01*
X3592981Y394937D01*
X3592051Y394104D01*
X3590811Y393479D01*
X3587711D01*
G01X3475956Y452579D02*
Y465079D01*
X3483086Y452579D01*
Y465079D01*
G01X3491921Y452579D02*
X3490681Y452787D01*
X3489596Y453620D01*
X3488666Y454871D01*
X3488046Y456329D01*
X3487736Y457996D01*
Y459662D01*
X3488046Y461329D01*
X3488666Y462787D01*
X3489596Y464037D01*
X3490681Y464871D01*
X3491921Y465079D01*
X3493161Y464871D01*
X3494246Y464037D01*
X3495176Y462787D01*
X3495796Y461329D01*
X3496106Y459662D01*
Y457996D01*
X3495796Y456329D01*
X3495176Y454871D01*
X3494246Y453620D01*
X3493161Y452787D01*
X3491921Y452579D01*
G01X3500756D02*
Y465079D01*
X3507886Y452579D01*
Y465079D01*
G01X3514706Y456746D02*
X3518736D01*
G01X3526021Y452579D02*
Y465079D01*
X3529741D01*
X3530981Y464454D01*
X3531911Y462996D01*
X3532221Y461329D01*
X3531911Y459662D01*
X3531136Y458412D01*
X3529741Y457787D01*
X3526021D01*
G01X3538421Y465079D02*
Y452579D01*
X3544621D01*
G01X3550046D02*
X3553921Y465079D01*
X3557796Y452579D01*
G01X3556401Y456954D02*
X3551441D01*
G01X3566321Y465079D02*
Y452579D01*
G01X3562756Y465079D02*
X3569886D01*
G01X3581821Y452579D02*
X3575621D01*
Y465079D01*
X3581821D01*
G01X3579341Y459037D02*
X3575621D01*
G01X3587711Y452579D02*
Y465079D01*
X3590811D01*
X3592051Y464454D01*
X3592981Y463621D01*
X3593756Y462371D01*
X3594376Y460912D01*
X3594531Y458829D01*
X3594376Y456746D01*
X3593756Y455287D01*
X3592981Y454037D01*
X3592051Y453204D01*
X3590811Y452579D01*
X3587711D01*
G01X3475956Y511679D02*
Y524179D01*
X3483086Y511679D01*
Y524179D01*
G01X3491921Y511679D02*
X3490681Y511887D01*
X3489596Y512720D01*
X3488666Y513971D01*
X3488046Y515429D01*
X3487736Y517096D01*
Y518762D01*
X3488046Y520429D01*
X3488666Y521887D01*
X3489596Y523137D01*
X3490681Y523971D01*
X3491921Y524179D01*
X3493161Y523971D01*
X3494246Y523137D01*
X3495176Y521887D01*
X3495796Y520429D01*
X3496106Y518762D01*
Y517096D01*
X3495796Y515429D01*
X3495176Y513971D01*
X3494246Y512720D01*
X3493161Y511887D01*
X3491921Y511679D01*
G01X3500756D02*
Y524179D01*
X3507886Y511679D01*
Y524179D01*
G01X3514706Y515846D02*
X3518736D01*
G01X3526021Y511679D02*
Y524179D01*
X3529741D01*
X3530981Y523554D01*
X3531911Y522096D01*
X3532221Y520429D01*
X3531911Y518762D01*
X3531136Y517512D01*
X3529741Y516887D01*
X3526021D01*
G01X3538421Y524179D02*
Y511679D01*
X3544621D01*
G01X3550046D02*
X3553921Y524179D01*
X3557796Y511679D01*
G01X3556401Y516054D02*
X3551441D01*
G01X3566321Y524179D02*
Y511679D01*
G01X3562756Y524179D02*
X3569886D01*
G01X3581821Y511679D02*
X3575621D01*
Y524179D01*
X3581821D01*
G01X3579341Y518137D02*
X3575621D01*
G01X3587711Y511679D02*
Y524179D01*
X3590811D01*
X3592051Y523554D01*
X3592981Y522721D01*
X3593756Y521471D01*
X3594376Y520012D01*
X3594531Y517929D01*
X3594376Y515846D01*
X3593756Y514387D01*
X3592981Y513137D01*
X3592051Y512304D01*
X3590811Y511679D01*
X3587711D01*
G01X3475956Y570779D02*
Y583279D01*
X3483086Y570779D01*
Y583279D01*
G01X3491921Y570779D02*
X3490681Y570987D01*
X3489596Y571820D01*
X3488666Y573071D01*
X3488046Y574529D01*
X3487736Y576196D01*
Y577862D01*
X3488046Y579529D01*
X3488666Y580987D01*
X3489596Y582237D01*
X3490681Y583071D01*
X3491921Y583279D01*
X3493161Y583071D01*
X3494246Y582237D01*
X3495176Y580987D01*
X3495796Y579529D01*
X3496106Y577862D01*
Y576196D01*
X3495796Y574529D01*
X3495176Y573071D01*
X3494246Y571820D01*
X3493161Y570987D01*
X3491921Y570779D01*
G01X3500756D02*
Y583279D01*
X3507886Y570779D01*
Y583279D01*
G01X3514706Y574946D02*
X3518736D01*
G01X3526021Y570779D02*
Y583279D01*
X3529741D01*
X3530981Y582654D01*
X3531911Y581196D01*
X3532221Y579529D01*
X3531911Y577862D01*
X3531136Y576612D01*
X3529741Y575987D01*
X3526021D01*
G01X3538421Y583279D02*
Y570779D01*
X3544621D01*
G01X3550046D02*
X3553921Y583279D01*
X3557796Y570779D01*
G01X3556401Y575154D02*
X3551441D01*
G01X3566321Y583279D02*
Y570779D01*
G01X3562756Y583279D02*
X3569886D01*
G01X3581821Y570779D02*
X3575621D01*
Y583279D01*
X3581821D01*
G01X3579341Y577237D02*
X3575621D01*
G01X3587711Y570779D02*
Y583279D01*
X3590811D01*
X3592051Y582654D01*
X3592981Y581821D01*
X3593756Y580571D01*
X3594376Y579112D01*
X3594531Y577029D01*
X3594376Y574946D01*
X3593756Y573487D01*
X3592981Y572237D01*
X3592051Y571404D01*
X3590811Y570779D01*
X3587711D01*
G01X3475956Y629879D02*
Y642379D01*
X3483086Y629879D01*
Y642379D01*
G01X3491921Y629879D02*
X3490681Y630087D01*
X3489596Y630920D01*
X3488666Y632171D01*
X3488046Y633629D01*
X3487736Y635296D01*
Y636962D01*
X3488046Y638629D01*
X3488666Y640087D01*
X3489596Y641337D01*
X3490681Y642171D01*
X3491921Y642379D01*
X3493161Y642171D01*
X3494246Y641337D01*
X3495176Y640087D01*
X3495796Y638629D01*
X3496106Y636962D01*
Y635296D01*
X3495796Y633629D01*
X3495176Y632171D01*
X3494246Y630920D01*
X3493161Y630087D01*
X3491921Y629879D01*
G01X3500756D02*
Y642379D01*
X3507886Y629879D01*
Y642379D01*
G01X3514706Y634046D02*
X3518736D01*
G01X3526021Y629879D02*
Y642379D01*
X3529741D01*
X3530981Y641754D01*
X3531911Y640296D01*
X3532221Y638629D01*
X3531911Y636962D01*
X3531136Y635712D01*
X3529741Y635087D01*
X3526021D01*
G01X3538421Y642379D02*
Y629879D01*
X3544621D01*
G01X3550046D02*
X3553921Y642379D01*
X3557796Y629879D01*
G01X3556401Y634254D02*
X3551441D01*
G01X3566321Y642379D02*
Y629879D01*
G01X3562756Y642379D02*
X3569886D01*
G01X3581821Y629879D02*
X3575621D01*
Y642379D01*
X3581821D01*
G01X3579341Y636337D02*
X3575621D01*
G01X3587711Y629879D02*
Y642379D01*
X3590811D01*
X3592051Y641754D01*
X3592981Y640921D01*
X3593756Y639671D01*
X3594376Y638212D01*
X3594531Y636129D01*
X3594376Y634046D01*
X3593756Y632587D01*
X3592981Y631337D01*
X3592051Y630504D01*
X3590811Y629879D01*
X3587711D01*
G01X3475956Y688979D02*
Y701479D01*
X3483086Y688979D01*
Y701479D01*
G01X3491921Y688979D02*
X3490681Y689187D01*
X3489596Y690020D01*
X3488666Y691271D01*
X3488046Y692729D01*
X3487736Y694396D01*
Y696062D01*
X3488046Y697729D01*
X3488666Y699187D01*
X3489596Y700437D01*
X3490681Y701271D01*
X3491921Y701479D01*
X3493161Y701271D01*
X3494246Y700437D01*
X3495176Y699187D01*
X3495796Y697729D01*
X3496106Y696062D01*
Y694396D01*
X3495796Y692729D01*
X3495176Y691271D01*
X3494246Y690020D01*
X3493161Y689187D01*
X3491921Y688979D01*
G01X3500756D02*
Y701479D01*
X3507886Y688979D01*
Y701479D01*
G01X3514706Y693146D02*
X3518736D01*
G01X3526021Y688979D02*
Y701479D01*
X3529741D01*
X3530981Y700854D01*
X3531911Y699396D01*
X3532221Y697729D01*
X3531911Y696062D01*
X3531136Y694812D01*
X3529741Y694187D01*
X3526021D01*
G01X3538421Y701479D02*
Y688979D01*
X3544621D01*
G01X3550046D02*
X3553921Y701479D01*
X3557796Y688979D01*
G01X3556401Y693354D02*
X3551441D01*
G01X3566321Y701479D02*
Y688979D01*
G01X3562756Y701479D02*
X3569886D01*
G01X3581821Y688979D02*
X3575621D01*
Y701479D01*
X3581821D01*
G01X3579341Y695437D02*
X3575621D01*
G01X3587711Y688979D02*
Y701479D01*
X3590811D01*
X3592051Y700854D01*
X3592981Y700021D01*
X3593756Y698771D01*
X3594376Y697312D01*
X3594531Y695229D01*
X3594376Y693146D01*
X3593756Y691687D01*
X3592981Y690437D01*
X3592051Y689604D01*
X3590811Y688979D01*
X3587711D01*
G01X3475956Y748079D02*
Y760579D01*
X3483086Y748079D01*
Y760579D01*
G01X3491921Y748079D02*
X3490681Y748287D01*
X3489596Y749120D01*
X3488666Y750371D01*
X3488046Y751829D01*
X3487736Y753496D01*
Y755162D01*
X3488046Y756829D01*
X3488666Y758287D01*
X3489596Y759537D01*
X3490681Y760371D01*
X3491921Y760579D01*
X3493161Y760371D01*
X3494246Y759537D01*
X3495176Y758287D01*
X3495796Y756829D01*
X3496106Y755162D01*
Y753496D01*
X3495796Y751829D01*
X3495176Y750371D01*
X3494246Y749120D01*
X3493161Y748287D01*
X3491921Y748079D01*
G01X3500756D02*
Y760579D01*
X3507886Y748079D01*
Y760579D01*
G01X3514706Y752246D02*
X3518736D01*
G01X3526021Y748079D02*
Y760579D01*
X3529741D01*
X3530981Y759954D01*
X3531911Y758496D01*
X3532221Y756829D01*
X3531911Y755162D01*
X3531136Y753912D01*
X3529741Y753287D01*
X3526021D01*
G01X3538421Y760579D02*
Y748079D01*
X3544621D01*
G01X3550046D02*
X3553921Y760579D01*
X3557796Y748079D01*
G01X3556401Y752454D02*
X3551441D01*
G01X3566321Y760579D02*
Y748079D01*
G01X3562756Y760579D02*
X3569886D01*
G01X3581821Y748079D02*
X3575621D01*
Y760579D01*
X3581821D01*
G01X3579341Y754537D02*
X3575621D01*
G01X3587711Y748079D02*
Y760579D01*
X3590811D01*
X3592051Y759954D01*
X3592981Y759121D01*
X3593756Y757871D01*
X3594376Y756412D01*
X3594531Y754329D01*
X3594376Y752246D01*
X3593756Y750787D01*
X3592981Y749537D01*
X3592051Y748704D01*
X3590811Y748079D01*
X3587711D01*
G01X3475956Y807179D02*
Y819679D01*
X3483086Y807179D01*
Y819679D01*
G01X3491921Y807179D02*
X3490681Y807387D01*
X3489596Y808220D01*
X3488666Y809471D01*
X3488046Y810929D01*
X3487736Y812596D01*
Y814262D01*
X3488046Y815929D01*
X3488666Y817387D01*
X3489596Y818637D01*
X3490681Y819471D01*
X3491921Y819679D01*
X3493161Y819471D01*
X3494246Y818637D01*
X3495176Y817387D01*
X3495796Y815929D01*
X3496106Y814262D01*
Y812596D01*
X3495796Y810929D01*
X3495176Y809471D01*
X3494246Y808220D01*
X3493161Y807387D01*
X3491921Y807179D01*
G01X3500756D02*
Y819679D01*
X3507886Y807179D01*
Y819679D01*
G01X3514706Y811346D02*
X3518736D01*
G01X3526021Y807179D02*
Y819679D01*
X3529741D01*
X3530981Y819054D01*
X3531911Y817596D01*
X3532221Y815929D01*
X3531911Y814262D01*
X3531136Y813012D01*
X3529741Y812387D01*
X3526021D01*
G01X3538421Y819679D02*
Y807179D01*
X3544621D01*
G01X3550046D02*
X3553921Y819679D01*
X3557796Y807179D01*
G01X3556401Y811554D02*
X3551441D01*
G01X3566321Y819679D02*
Y807179D01*
G01X3562756Y819679D02*
X3569886D01*
G01X3581821Y807179D02*
X3575621D01*
Y819679D01*
X3581821D01*
G01X3579341Y813637D02*
X3575621D01*
G01X3587711Y807179D02*
Y819679D01*
X3590811D01*
X3592051Y819054D01*
X3592981Y818221D01*
X3593756Y816971D01*
X3594376Y815512D01*
X3594531Y813429D01*
X3594376Y811346D01*
X3593756Y809887D01*
X3592981Y808637D01*
X3592051Y807804D01*
X3590811Y807179D01*
X3587711D01*
G01X3480726Y2899349D02*
Y2911849D01*
X3478866Y2909349D01*
G01Y2899349D02*
X3482586D01*
G01X3490181Y2909766D02*
X3491111Y2911015D01*
X3492196Y2911641D01*
X3493436Y2911849D01*
X3494986Y2911432D01*
X3496071Y2910391D01*
X3496381Y2909141D01*
X3496226Y2907890D01*
X3495606Y2906849D01*
X3492506Y2904766D01*
X3491111Y2903307D01*
X3490181Y2901224D01*
X3489871Y2899349D01*
X3496381D01*
G01X3505526Y2911849D02*
X3504286Y2911432D01*
X3503356Y2910391D01*
X3502736Y2909141D01*
X3502271Y2907474D01*
X3502116Y2905599D01*
X3502271Y2903724D01*
X3502736Y2902057D01*
X3503356Y2900807D01*
X3504286Y2899766D01*
X3505526Y2899349D01*
X3506766Y2899766D01*
X3507696Y2900807D01*
X3508316Y2902057D01*
X3508781Y2903724D01*
X3508936Y2905599D01*
X3508781Y2907474D01*
X3508316Y2909141D01*
X3507696Y2910391D01*
X3506766Y2911432D01*
X3505526Y2911849D01*
G01X3517926D02*
X3516686Y2911432D01*
X3515756Y2910391D01*
X3515136Y2909141D01*
X3514671Y2907474D01*
X3514516Y2905599D01*
X3514671Y2903724D01*
X3515136Y2902057D01*
X3515756Y2900807D01*
X3516686Y2899766D01*
X3517926Y2899349D01*
X3519166Y2899766D01*
X3520096Y2900807D01*
X3520716Y2902057D01*
X3521181Y2903724D01*
X3521336Y2905599D01*
X3521181Y2907474D01*
X3520716Y2909141D01*
X3520096Y2910391D01*
X3519166Y2911432D01*
X3517926Y2911849D01*
G01X3480736Y3149919D02*
Y3162419D01*
X3478876Y3159919D01*
G01Y3149919D02*
X3482596D01*
G01X3489726Y3152419D02*
X3490656Y3150960D01*
X3491896Y3150127D01*
X3493291Y3149919D01*
X3494531Y3150127D01*
X3495771Y3151169D01*
X3496546Y3152419D01*
X3496701Y3153669D01*
X3496391Y3155127D01*
X3495306Y3156169D01*
X3494221Y3156586D01*
X3492826D01*
G01X3494221D02*
X3495151Y3157211D01*
X3495926Y3158252D01*
X3496236Y3159502D01*
X3495926Y3160752D01*
X3495151Y3161794D01*
X3493756Y3162419D01*
X3492361Y3162211D01*
X3490966Y3161377D01*
G01X3502591Y3160336D02*
X3503521Y3161585D01*
X3504606Y3162211D01*
X3505846Y3162419D01*
X3507396Y3162002D01*
X3508481Y3160961D01*
X3508791Y3159711D01*
X3508636Y3158460D01*
X3508016Y3157419D01*
X3504916Y3155336D01*
X3503521Y3153877D01*
X3502591Y3151794D01*
X3502281Y3149919D01*
X3508791D01*
G01X3517936Y3162419D02*
X3516696Y3162002D01*
X3515766Y3160961D01*
X3515146Y3159711D01*
X3514681Y3158044D01*
X3514526Y3156169D01*
X3514681Y3154294D01*
X3515146Y3152627D01*
X3515766Y3151377D01*
X3516696Y3150336D01*
X3517936Y3149919D01*
X3519176Y3150336D01*
X3520106Y3151377D01*
X3520726Y3152627D01*
X3521191Y3154294D01*
X3521346Y3156169D01*
X3521191Y3158044D01*
X3520726Y3159711D01*
X3520106Y3160961D01*
X3519176Y3162002D01*
X3517936Y3162419D01*
G01X3476390Y3405925D02*
Y3418425D01*
X3474530Y3415925D01*
G01Y3405925D02*
X3478250D01*
G01X3488790D02*
Y3418425D01*
X3486930Y3415925D01*
G01Y3405925D02*
X3490650D01*
G01X3501190D02*
X3502275Y3406133D01*
X3503515Y3406758D01*
X3504290Y3407800D01*
X3504600Y3409258D01*
X3504290Y3410716D01*
X3503360Y3411967D01*
X3501965Y3412592D01*
X3500415D01*
X3499485Y3413008D01*
X3498710Y3414050D01*
X3498400Y3415508D01*
X3498865Y3416967D01*
X3499950Y3418008D01*
X3501190Y3418425D01*
X3502430Y3418008D01*
X3503515Y3416967D01*
X3503980Y3415508D01*
X3503670Y3414050D01*
X3502895Y3413008D01*
X3501965Y3412592D01*
X3500415D01*
X3499020Y3411967D01*
X3498090Y3410716D01*
X3497780Y3409258D01*
X3498090Y3407800D01*
X3498865Y3406758D01*
X3500105Y3406133D01*
X3501190Y3405925D01*
G01X3513590D02*
X3514675Y3406133D01*
X3515915Y3406758D01*
X3516690Y3407800D01*
X3517000Y3409258D01*
X3516690Y3410716D01*
X3515760Y3411967D01*
X3514365Y3412592D01*
X3512815D01*
X3511885Y3413008D01*
X3511110Y3414050D01*
X3510800Y3415508D01*
X3511265Y3416967D01*
X3512350Y3418008D01*
X3513590Y3418425D01*
X3514830Y3418008D01*
X3515915Y3416967D01*
X3516380Y3415508D01*
X3516070Y3414050D01*
X3515295Y3413008D01*
X3514365Y3412592D01*
X3512815D01*
X3511420Y3411967D01*
X3510490Y3410716D01*
X3510180Y3409258D01*
X3510490Y3407800D01*
X3511265Y3406758D01*
X3512505Y3406133D01*
X3513590Y3405925D01*
G01X3481495Y3691387D02*
Y3703887D01*
X3479635Y3701387D01*
G01Y3691387D02*
X3483355D01*
G01X3493895D02*
Y3703887D01*
X3492035Y3701387D01*
G01Y3691387D02*
X3495755D01*
G01X3503350Y3701804D02*
X3504280Y3703053D01*
X3505365Y3703679D01*
X3506605Y3703887D01*
X3508155Y3703470D01*
X3509240Y3702429D01*
X3509550Y3701179D01*
X3509395Y3699928D01*
X3508775Y3698887D01*
X3505675Y3696804D01*
X3504280Y3695345D01*
X3503350Y3693262D01*
X3503040Y3691387D01*
X3509550D01*
G01X3518695Y3703887D02*
X3517455Y3703470D01*
X3516525Y3702429D01*
X3515905Y3701179D01*
X3515440Y3699512D01*
X3515285Y3697637D01*
X3515440Y3695762D01*
X3515905Y3694095D01*
X3516525Y3692845D01*
X3517455Y3691804D01*
X3518695Y3691387D01*
X3519935Y3691804D01*
X3520865Y3692845D01*
X3521485Y3694095D01*
X3521950Y3695762D01*
X3522105Y3697637D01*
X3521950Y3699512D01*
X3521485Y3701179D01*
X3520865Y3702429D01*
X3519935Y3703470D01*
X3518695Y3703887D01*
G01X3498330Y2610432D02*
X3499415Y2610640D01*
X3500655Y2611265D01*
X3501430Y2612307D01*
X3501740Y2613765D01*
X3501430Y2615223D01*
X3500500Y2616474D01*
X3499105Y2617099D01*
X3497555D01*
X3496625Y2617515D01*
X3495850Y2618557D01*
X3495540Y2620015D01*
X3496005Y2621474D01*
X3497090Y2622515D01*
X3498330Y2622932D01*
X3499570Y2622515D01*
X3500655Y2621474D01*
X3501120Y2620015D01*
X3500810Y2618557D01*
X3500035Y2617515D01*
X3499105Y2617099D01*
X3497555D01*
X3496160Y2616474D01*
X3495230Y2615223D01*
X3494920Y2613765D01*
X3495230Y2612307D01*
X3496005Y2611265D01*
X3497245Y2610640D01*
X3498330Y2610432D01*
G01X3485930Y2635432D02*
X3484690Y2635640D01*
X3483605Y2636473D01*
X3482675Y2637724D01*
X3482055Y2639182D01*
X3481745Y2640849D01*
Y2642515D01*
X3482055Y2644182D01*
X3482675Y2645640D01*
X3483605Y2646890D01*
X3484690Y2647724D01*
X3485930Y2647932D01*
X3487170Y2647724D01*
X3488255Y2646890D01*
X3489185Y2645640D01*
X3489805Y2644182D01*
X3490115Y2642515D01*
Y2640849D01*
X3489805Y2639182D01*
X3489185Y2637724D01*
X3488255Y2636473D01*
X3487170Y2635640D01*
X3485930Y2635432D01*
G01X3487170Y2638765D02*
X3489030Y2635432D01*
G01X3498330Y2647932D02*
Y2635432D01*
G01X3494765Y2647932D02*
X3501895D01*
G01X3510730Y2635432D02*
Y2641057D01*
X3507630Y2647932D01*
G01X3513830D02*
X3510730Y2641057D01*
G01X3483981Y2884766D02*
X3484911Y2886015D01*
X3485996Y2886641D01*
X3487236Y2886849D01*
X3488786Y2886432D01*
X3489871Y2885391D01*
X3490181Y2884141D01*
X3490026Y2882890D01*
X3489406Y2881849D01*
X3486306Y2879766D01*
X3484911Y2878307D01*
X3483981Y2876224D01*
X3483671Y2874349D01*
X3490181D01*
G01X3496381Y2884766D02*
X3497311Y2886015D01*
X3498396Y2886641D01*
X3499636Y2886849D01*
X3501186Y2886432D01*
X3502271Y2885391D01*
X3502581Y2884141D01*
X3502426Y2882890D01*
X3501806Y2881849D01*
X3498706Y2879766D01*
X3497311Y2878307D01*
X3496381Y2876224D01*
X3496071Y2874349D01*
X3502581D01*
G01X3511726D02*
X3512811Y2874557D01*
X3514051Y2875182D01*
X3514826Y2876224D01*
X3515136Y2877682D01*
X3514826Y2879140D01*
X3513896Y2880391D01*
X3512501Y2881016D01*
X3510951D01*
X3510021Y2881432D01*
X3509246Y2882474D01*
X3508936Y2883932D01*
X3509401Y2885391D01*
X3510486Y2886432D01*
X3511726Y2886849D01*
X3512966Y2886432D01*
X3514051Y2885391D01*
X3514516Y2883932D01*
X3514206Y2882474D01*
X3513431Y2881432D01*
X3512501Y2881016D01*
X3510951D01*
X3509556Y2880391D01*
X3508626Y2879140D01*
X3508316Y2877682D01*
X3508626Y2876224D01*
X3509401Y2875182D01*
X3510641Y2874557D01*
X3511726Y2874349D01*
G01X3486926Y2924349D02*
X3485686Y2924557D01*
X3484601Y2925390D01*
X3483671Y2926641D01*
X3483051Y2928099D01*
X3482741Y2929766D01*
Y2931432D01*
X3483051Y2933099D01*
X3483671Y2934557D01*
X3484601Y2935807D01*
X3485686Y2936641D01*
X3486926Y2936849D01*
X3488166Y2936641D01*
X3489251Y2935807D01*
X3490181Y2934557D01*
X3490801Y2933099D01*
X3491111Y2931432D01*
Y2929766D01*
X3490801Y2928099D01*
X3490181Y2926641D01*
X3489251Y2925390D01*
X3488166Y2924557D01*
X3486926Y2924349D01*
G01X3488166Y2927682D02*
X3490026Y2924349D01*
G01X3499326Y2936849D02*
Y2924349D01*
G01X3495761Y2936849D02*
X3502891D01*
G01X3511726Y2924349D02*
Y2929974D01*
X3508626Y2936849D01*
G01X3514826D02*
X3511726Y2929974D01*
G01X3490191Y3135336D02*
X3491121Y3136585D01*
X3492206Y3137211D01*
X3493446Y3137419D01*
X3494996Y3137002D01*
X3496081Y3135961D01*
X3496391Y3134711D01*
X3496236Y3133460D01*
X3495616Y3132419D01*
X3492516Y3130336D01*
X3491121Y3128877D01*
X3490191Y3126794D01*
X3489881Y3124919D01*
X3496391D01*
G01X3505536D02*
X3506621Y3125127D01*
X3507861Y3125752D01*
X3508636Y3126794D01*
X3508946Y3128252D01*
X3508636Y3129710D01*
X3507706Y3130961D01*
X3506311Y3131586D01*
X3504761D01*
X3503831Y3132002D01*
X3503056Y3133044D01*
X3502746Y3134502D01*
X3503211Y3135961D01*
X3504296Y3137002D01*
X3505536Y3137419D01*
X3506776Y3137002D01*
X3507861Y3135961D01*
X3508326Y3134502D01*
X3508016Y3133044D01*
X3507241Y3132002D01*
X3506311Y3131586D01*
X3504761D01*
X3503366Y3130961D01*
X3502436Y3129710D01*
X3502126Y3128252D01*
X3502436Y3126794D01*
X3503211Y3125752D01*
X3504451Y3125127D01*
X3505536Y3124919D01*
G01X3486936Y3174919D02*
X3485696Y3175127D01*
X3484611Y3175960D01*
X3483681Y3177211D01*
X3483061Y3178669D01*
X3482751Y3180336D01*
Y3182002D01*
X3483061Y3183669D01*
X3483681Y3185127D01*
X3484611Y3186377D01*
X3485696Y3187211D01*
X3486936Y3187419D01*
X3488176Y3187211D01*
X3489261Y3186377D01*
X3490191Y3185127D01*
X3490811Y3183669D01*
X3491121Y3182002D01*
Y3180336D01*
X3490811Y3178669D01*
X3490191Y3177211D01*
X3489261Y3175960D01*
X3488176Y3175127D01*
X3486936Y3174919D01*
G01X3488176Y3178252D02*
X3490036Y3174919D01*
G01X3499336Y3187419D02*
Y3174919D01*
G01X3495771Y3187419D02*
X3502901D01*
G01X3511736Y3174919D02*
Y3180544D01*
X3508636Y3187419D01*
G01X3514836D02*
X3511736Y3180544D01*
G01X3479645Y3391342D02*
X3480575Y3392591D01*
X3481660Y3393217D01*
X3482900Y3393425D01*
X3484450Y3393008D01*
X3485535Y3391967D01*
X3485845Y3390717D01*
X3485690Y3389466D01*
X3485070Y3388425D01*
X3481970Y3386342D01*
X3480575Y3384883D01*
X3479645Y3382800D01*
X3479335Y3380925D01*
X3485845D01*
G01X3494990D02*
Y3393425D01*
X3493130Y3390925D01*
G01Y3380925D02*
X3496850D01*
G01X3504445Y3391342D02*
X3505375Y3392591D01*
X3506460Y3393217D01*
X3507700Y3393425D01*
X3509250Y3393008D01*
X3510335Y3391967D01*
X3510645Y3390717D01*
X3510490Y3389466D01*
X3509870Y3388425D01*
X3506770Y3386342D01*
X3505375Y3384883D01*
X3504445Y3382800D01*
X3504135Y3380925D01*
X3510645D01*
G01X3482590Y3430925D02*
X3481350Y3431133D01*
X3480265Y3431966D01*
X3479335Y3433217D01*
X3478715Y3434675D01*
X3478405Y3436342D01*
Y3438008D01*
X3478715Y3439675D01*
X3479335Y3441133D01*
X3480265Y3442383D01*
X3481350Y3443217D01*
X3482590Y3443425D01*
X3483830Y3443217D01*
X3484915Y3442383D01*
X3485845Y3441133D01*
X3486465Y3439675D01*
X3486775Y3438008D01*
Y3436342D01*
X3486465Y3434675D01*
X3485845Y3433217D01*
X3484915Y3431966D01*
X3483830Y3431133D01*
X3482590Y3430925D01*
G01X3483830Y3434258D02*
X3485690Y3430925D01*
G01X3494990Y3443425D02*
Y3430925D01*
G01X3491425Y3443425D02*
X3498555D01*
G01X3507390Y3430925D02*
Y3436550D01*
X3504290Y3443425D01*
G01X3510490D02*
X3507390Y3436550D01*
G01X3487695Y3641387D02*
Y3653887D01*
X3485835Y3651387D01*
G01Y3641387D02*
X3489555D01*
G01X3497150Y3651804D02*
X3498080Y3653053D01*
X3499165Y3653679D01*
X3500405Y3653887D01*
X3501955Y3653470D01*
X3503040Y3652429D01*
X3503350Y3651179D01*
X3503195Y3649928D01*
X3502575Y3648887D01*
X3499475Y3646804D01*
X3498080Y3645345D01*
X3497150Y3643262D01*
X3496840Y3641387D01*
X3503350D01*
G01X3512495D02*
X3513580Y3641595D01*
X3514820Y3642220D01*
X3515595Y3643262D01*
X3515905Y3644720D01*
X3515595Y3646178D01*
X3514665Y3647429D01*
X3513270Y3648054D01*
X3511720D01*
X3510790Y3648470D01*
X3510015Y3649512D01*
X3509705Y3650970D01*
X3510170Y3652429D01*
X3511255Y3653470D01*
X3512495Y3653887D01*
X3513735Y3653470D01*
X3514820Y3652429D01*
X3515285Y3650970D01*
X3514975Y3649512D01*
X3514200Y3648470D01*
X3513270Y3648054D01*
X3511720D01*
X3510325Y3647429D01*
X3509395Y3646178D01*
X3509085Y3644720D01*
X3509395Y3643262D01*
X3510170Y3642220D01*
X3511410Y3641595D01*
X3512495Y3641387D01*
G01X3487695Y3666387D02*
Y3678887D01*
X3485835Y3676387D01*
G01Y3666387D02*
X3489555D01*
G01X3497460Y3667845D02*
X3498545Y3666804D01*
X3499785Y3666387D01*
X3501025Y3666804D01*
X3502110Y3668053D01*
X3502885Y3669929D01*
X3503195Y3671804D01*
Y3674095D01*
X3502885Y3675970D01*
X3502110Y3677637D01*
X3501180Y3678470D01*
X3500095Y3678887D01*
X3498855Y3678470D01*
X3497925Y3677637D01*
X3497305Y3676387D01*
X3496995Y3674720D01*
X3497305Y3673262D01*
X3498080Y3671804D01*
X3499010Y3670970D01*
X3500095Y3670762D01*
X3501335Y3671178D01*
X3502265Y3672220D01*
X3503195Y3674095D01*
G01X3509550Y3671595D02*
X3510635Y3673054D01*
X3511565Y3673887D01*
X3512805Y3674304D01*
X3513890Y3673887D01*
X3514665Y3673054D01*
X3515285Y3671804D01*
X3515440Y3670345D01*
X3515285Y3669095D01*
X3514665Y3667845D01*
X3513735Y3666804D01*
X3512650Y3666387D01*
X3511410Y3666804D01*
X3510325Y3668053D01*
X3509705Y3669929D01*
X3509550Y3672012D01*
X3509860Y3674720D01*
X3510325Y3676179D01*
X3511100Y3677637D01*
X3512185Y3678679D01*
X3513270Y3678887D01*
X3514355Y3678470D01*
X3515130Y3677429D01*
G01X3487695Y3716387D02*
X3486455Y3716595D01*
X3485370Y3717428D01*
X3484440Y3718679D01*
X3483820Y3720137D01*
X3483510Y3721804D01*
Y3723470D01*
X3483820Y3725137D01*
X3484440Y3726595D01*
X3485370Y3727845D01*
X3486455Y3728679D01*
X3487695Y3728887D01*
X3488935Y3728679D01*
X3490020Y3727845D01*
X3490950Y3726595D01*
X3491570Y3725137D01*
X3491880Y3723470D01*
Y3721804D01*
X3491570Y3720137D01*
X3490950Y3718679D01*
X3490020Y3717428D01*
X3488935Y3716595D01*
X3487695Y3716387D01*
G01X3488935Y3719720D02*
X3490795Y3716387D01*
G01X3500095Y3728887D02*
Y3716387D01*
G01X3496530Y3728887D02*
X3503660D01*
G01X3512495Y3716387D02*
Y3722012D01*
X3509395Y3728887D01*
G01X3515595D02*
X3512495Y3722012D01*
G01X3501221Y-79321D02*
Y-66821D01*
X3504941D01*
X3506181Y-67446D01*
X3507111Y-68904D01*
X3507421Y-70571D01*
X3507111Y-72238D01*
X3506336Y-73488D01*
X3504941Y-74113D01*
X3501221D01*
G01X3513621Y-66821D02*
Y-79321D01*
X3519821D01*
G01X3525246D02*
X3529121Y-66821D01*
X3532996Y-79321D01*
G01X3531601Y-74946D02*
X3526641D01*
G01X3541521Y-66821D02*
Y-79321D01*
G01X3537956Y-66821D02*
X3545086D01*
G01X3557021Y-79321D02*
X3550821D01*
Y-66821D01*
X3557021D01*
G01X3554541Y-72863D02*
X3550821D01*
G01X3562911Y-79321D02*
Y-66821D01*
X3566011D01*
X3567251Y-67446D01*
X3568181Y-68279D01*
X3568956Y-69529D01*
X3569576Y-70988D01*
X3569731Y-73071D01*
X3569576Y-75154D01*
X3568956Y-76613D01*
X3568181Y-77863D01*
X3567251Y-78696D01*
X3566011Y-79321D01*
X3562911D01*
G01X3501221Y-20221D02*
Y-7721D01*
X3504941D01*
X3506181Y-8346D01*
X3507111Y-9804D01*
X3507421Y-11471D01*
X3507111Y-13138D01*
X3506336Y-14388D01*
X3504941Y-15013D01*
X3501221D01*
G01X3513621Y-7721D02*
Y-20221D01*
X3519821D01*
G01X3525246D02*
X3529121Y-7721D01*
X3532996Y-20221D01*
G01X3531601Y-15846D02*
X3526641D01*
G01X3541521Y-7721D02*
Y-20221D01*
G01X3537956Y-7721D02*
X3545086D01*
G01X3557021Y-20221D02*
X3550821D01*
Y-7721D01*
X3557021D01*
G01X3554541Y-13763D02*
X3550821D01*
G01X3562911Y-20221D02*
Y-7721D01*
X3566011D01*
X3567251Y-8346D01*
X3568181Y-9179D01*
X3568956Y-10429D01*
X3569576Y-11888D01*
X3569731Y-13971D01*
X3569576Y-16054D01*
X3568956Y-17513D01*
X3568181Y-18763D01*
X3567251Y-19596D01*
X3566011Y-20221D01*
X3562911D01*
G01X3501221Y866279D02*
Y878779D01*
X3504941D01*
X3506181Y878154D01*
X3507111Y876696D01*
X3507421Y875029D01*
X3507111Y873362D01*
X3506336Y872112D01*
X3504941Y871487D01*
X3501221D01*
G01X3513621Y878779D02*
Y866279D01*
X3519821D01*
G01X3525246D02*
X3529121Y878779D01*
X3532996Y866279D01*
G01X3531601Y870654D02*
X3526641D01*
G01X3541521Y878779D02*
Y866279D01*
G01X3537956Y878779D02*
X3545086D01*
G01X3557021Y866279D02*
X3550821D01*
Y878779D01*
X3557021D01*
G01X3554541Y872737D02*
X3550821D01*
G01X3562911Y866279D02*
Y878779D01*
X3566011D01*
X3567251Y878154D01*
X3568181Y877321D01*
X3568956Y876071D01*
X3569576Y874612D01*
X3569731Y872529D01*
X3569576Y870446D01*
X3568956Y868987D01*
X3568181Y867737D01*
X3567251Y866904D01*
X3566011Y866279D01*
X3562911D01*
G01X3501221Y925379D02*
Y937879D01*
X3504941D01*
X3506181Y937254D01*
X3507111Y935796D01*
X3507421Y934129D01*
X3507111Y932462D01*
X3506336Y931212D01*
X3504941Y930587D01*
X3501221D01*
G01X3513621Y937879D02*
Y925379D01*
X3519821D01*
G01X3525246D02*
X3529121Y937879D01*
X3532996Y925379D01*
G01X3531601Y929754D02*
X3526641D01*
G01X3541521Y937879D02*
Y925379D01*
G01X3537956Y937879D02*
X3545086D01*
G01X3557021Y925379D02*
X3550821D01*
Y937879D01*
X3557021D01*
G01X3554541Y931837D02*
X3550821D01*
G01X3562911Y925379D02*
Y937879D01*
X3566011D01*
X3567251Y937254D01*
X3568181Y936421D01*
X3568956Y935171D01*
X3569576Y933712D01*
X3569731Y931629D01*
X3569576Y929546D01*
X3568956Y928087D01*
X3568181Y926837D01*
X3567251Y926004D01*
X3566011Y925379D01*
X3562911D01*
G01X3501221Y984479D02*
Y996979D01*
X3504941D01*
X3506181Y996354D01*
X3507111Y994896D01*
X3507421Y993229D01*
X3507111Y991562D01*
X3506336Y990312D01*
X3504941Y989687D01*
X3501221D01*
G01X3513621Y996979D02*
Y984479D01*
X3519821D01*
G01X3525246D02*
X3529121Y996979D01*
X3532996Y984479D01*
G01X3531601Y988854D02*
X3526641D01*
G01X3541521Y996979D02*
Y984479D01*
G01X3537956Y996979D02*
X3545086D01*
G01X3557021Y984479D02*
X3550821D01*
Y996979D01*
X3557021D01*
G01X3554541Y990937D02*
X3550821D01*
G01X3562911Y984479D02*
Y996979D01*
X3566011D01*
X3567251Y996354D01*
X3568181Y995521D01*
X3568956Y994271D01*
X3569576Y992812D01*
X3569731Y990729D01*
X3569576Y988646D01*
X3568956Y987187D01*
X3568181Y985937D01*
X3567251Y985104D01*
X3566011Y984479D01*
X3562911D01*
G01X3501221Y1043579D02*
Y1056079D01*
X3504941D01*
X3506181Y1055454D01*
X3507111Y1053996D01*
X3507421Y1052329D01*
X3507111Y1050662D01*
X3506336Y1049412D01*
X3504941Y1048787D01*
X3501221D01*
G01X3513621Y1056079D02*
Y1043579D01*
X3519821D01*
G01X3525246D02*
X3529121Y1056079D01*
X3532996Y1043579D01*
G01X3531601Y1047954D02*
X3526641D01*
G01X3541521Y1056079D02*
Y1043579D01*
G01X3537956Y1056079D02*
X3545086D01*
G01X3557021Y1043579D02*
X3550821D01*
Y1056079D01*
X3557021D01*
G01X3554541Y1050037D02*
X3550821D01*
G01X3562911Y1043579D02*
Y1056079D01*
X3566011D01*
X3567251Y1055454D01*
X3568181Y1054621D01*
X3568956Y1053371D01*
X3569576Y1051912D01*
X3569731Y1049829D01*
X3569576Y1047746D01*
X3568956Y1046287D01*
X3568181Y1045037D01*
X3567251Y1044204D01*
X3566011Y1043579D01*
X3562911D01*
G01X3501221Y1102679D02*
Y1115179D01*
X3504941D01*
X3506181Y1114554D01*
X3507111Y1113096D01*
X3507421Y1111429D01*
X3507111Y1109762D01*
X3506336Y1108512D01*
X3504941Y1107887D01*
X3501221D01*
G01X3513621Y1115179D02*
Y1102679D01*
X3519821D01*
G01X3525246D02*
X3529121Y1115179D01*
X3532996Y1102679D01*
G01X3531601Y1107054D02*
X3526641D01*
G01X3541521Y1115179D02*
Y1102679D01*
G01X3537956Y1115179D02*
X3545086D01*
G01X3557021Y1102679D02*
X3550821D01*
Y1115179D01*
X3557021D01*
G01X3554541Y1109137D02*
X3550821D01*
G01X3562911Y1102679D02*
Y1115179D01*
X3566011D01*
X3567251Y1114554D01*
X3568181Y1113721D01*
X3568956Y1112471D01*
X3569576Y1111012D01*
X3569731Y1108929D01*
X3569576Y1106846D01*
X3568956Y1105387D01*
X3568181Y1104137D01*
X3567251Y1103304D01*
X3566011Y1102679D01*
X3562911D01*
G01X3501221Y1161779D02*
Y1174279D01*
X3504941D01*
X3506181Y1173654D01*
X3507111Y1172196D01*
X3507421Y1170529D01*
X3507111Y1168862D01*
X3506336Y1167612D01*
X3504941Y1166987D01*
X3501221D01*
G01X3513621Y1174279D02*
Y1161779D01*
X3519821D01*
G01X3525246D02*
X3529121Y1174279D01*
X3532996Y1161779D01*
G01X3531601Y1166154D02*
X3526641D01*
G01X3541521Y1174279D02*
Y1161779D01*
G01X3537956Y1174279D02*
X3545086D01*
G01X3557021Y1161779D02*
X3550821D01*
Y1174279D01*
X3557021D01*
G01X3554541Y1168237D02*
X3550821D01*
G01X3562911Y1161779D02*
Y1174279D01*
X3566011D01*
X3567251Y1173654D01*
X3568181Y1172821D01*
X3568956Y1171571D01*
X3569576Y1170112D01*
X3569731Y1168029D01*
X3569576Y1165946D01*
X3568956Y1164487D01*
X3568181Y1163237D01*
X3567251Y1162404D01*
X3566011Y1161779D01*
X3562911D01*
G01X3501221Y1220879D02*
Y1233379D01*
X3504941D01*
X3506181Y1232754D01*
X3507111Y1231296D01*
X3507421Y1229629D01*
X3507111Y1227962D01*
X3506336Y1226712D01*
X3504941Y1226087D01*
X3501221D01*
G01X3513621Y1233379D02*
Y1220879D01*
X3519821D01*
G01X3525246D02*
X3529121Y1233379D01*
X3532996Y1220879D01*
G01X3531601Y1225254D02*
X3526641D01*
G01X3541521Y1233379D02*
Y1220879D01*
G01X3537956Y1233379D02*
X3545086D01*
G01X3557021Y1220879D02*
X3550821D01*
Y1233379D01*
X3557021D01*
G01X3554541Y1227337D02*
X3550821D01*
G01X3562911Y1220879D02*
Y1233379D01*
X3566011D01*
X3567251Y1232754D01*
X3568181Y1231921D01*
X3568956Y1230671D01*
X3569576Y1229212D01*
X3569731Y1227129D01*
X3569576Y1225046D01*
X3568956Y1223587D01*
X3568181Y1222337D01*
X3567251Y1221504D01*
X3566011Y1220879D01*
X3562911D01*
G01X3501221Y1279979D02*
Y1292479D01*
X3504941D01*
X3506181Y1291854D01*
X3507111Y1290396D01*
X3507421Y1288729D01*
X3507111Y1287062D01*
X3506336Y1285812D01*
X3504941Y1285187D01*
X3501221D01*
G01X3513621Y1292479D02*
Y1279979D01*
X3519821D01*
G01X3525246D02*
X3529121Y1292479D01*
X3532996Y1279979D01*
G01X3531601Y1284354D02*
X3526641D01*
G01X3541521Y1292479D02*
Y1279979D01*
G01X3537956Y1292479D02*
X3545086D01*
G01X3557021Y1279979D02*
X3550821D01*
Y1292479D01*
X3557021D01*
G01X3554541Y1286437D02*
X3550821D01*
G01X3562911Y1279979D02*
Y1292479D01*
X3566011D01*
X3567251Y1291854D01*
X3568181Y1291021D01*
X3568956Y1289771D01*
X3569576Y1288312D01*
X3569731Y1286229D01*
X3569576Y1284146D01*
X3568956Y1282687D01*
X3568181Y1281437D01*
X3567251Y1280604D01*
X3566011Y1279979D01*
X3562911D01*
G01X3501221Y1339079D02*
Y1351579D01*
X3504941D01*
X3506181Y1350954D01*
X3507111Y1349496D01*
X3507421Y1347829D01*
X3507111Y1346162D01*
X3506336Y1344912D01*
X3504941Y1344287D01*
X3501221D01*
G01X3513621Y1351579D02*
Y1339079D01*
X3519821D01*
G01X3525246D02*
X3529121Y1351579D01*
X3532996Y1339079D01*
G01X3531601Y1343454D02*
X3526641D01*
G01X3541521Y1351579D02*
Y1339079D01*
G01X3537956Y1351579D02*
X3545086D01*
G01X3557021Y1339079D02*
X3550821D01*
Y1351579D01*
X3557021D01*
G01X3554541Y1345537D02*
X3550821D01*
G01X3562911Y1339079D02*
Y1351579D01*
X3566011D01*
X3567251Y1350954D01*
X3568181Y1350121D01*
X3568956Y1348871D01*
X3569576Y1347412D01*
X3569731Y1345329D01*
X3569576Y1343246D01*
X3568956Y1341787D01*
X3568181Y1340537D01*
X3567251Y1339704D01*
X3566011Y1339079D01*
X3562911D01*
G01X3501221Y1398179D02*
Y1410679D01*
X3504941D01*
X3506181Y1410054D01*
X3507111Y1408596D01*
X3507421Y1406929D01*
X3507111Y1405262D01*
X3506336Y1404012D01*
X3504941Y1403387D01*
X3501221D01*
G01X3513621Y1410679D02*
Y1398179D01*
X3519821D01*
G01X3525246D02*
X3529121Y1410679D01*
X3532996Y1398179D01*
G01X3531601Y1402554D02*
X3526641D01*
G01X3541521Y1410679D02*
Y1398179D01*
G01X3537956Y1410679D02*
X3545086D01*
G01X3557021Y1398179D02*
X3550821D01*
Y1410679D01*
X3557021D01*
G01X3554541Y1404637D02*
X3550821D01*
G01X3562911Y1398179D02*
Y1410679D01*
X3566011D01*
X3567251Y1410054D01*
X3568181Y1409221D01*
X3568956Y1407971D01*
X3569576Y1406512D01*
X3569731Y1404429D01*
X3569576Y1402346D01*
X3568956Y1400887D01*
X3568181Y1399637D01*
X3567251Y1398804D01*
X3566011Y1398179D01*
X3562911D01*
G01X3501221Y1457279D02*
Y1469779D01*
X3504941D01*
X3506181Y1469154D01*
X3507111Y1467696D01*
X3507421Y1466029D01*
X3507111Y1464362D01*
X3506336Y1463112D01*
X3504941Y1462487D01*
X3501221D01*
G01X3513621Y1469779D02*
Y1457279D01*
X3519821D01*
G01X3525246D02*
X3529121Y1469779D01*
X3532996Y1457279D01*
G01X3531601Y1461654D02*
X3526641D01*
G01X3541521Y1469779D02*
Y1457279D01*
G01X3537956Y1469779D02*
X3545086D01*
G01X3557021Y1457279D02*
X3550821D01*
Y1469779D01*
X3557021D01*
G01X3554541Y1463737D02*
X3550821D01*
G01X3562911Y1457279D02*
Y1469779D01*
X3566011D01*
X3567251Y1469154D01*
X3568181Y1468321D01*
X3568956Y1467071D01*
X3569576Y1465612D01*
X3569731Y1463529D01*
X3569576Y1461446D01*
X3568956Y1459987D01*
X3568181Y1458737D01*
X3567251Y1457904D01*
X3566011Y1457279D01*
X3562911D01*
G01X3501221Y1516379D02*
Y1528879D01*
X3504941D01*
X3506181Y1528254D01*
X3507111Y1526796D01*
X3507421Y1525129D01*
X3507111Y1523462D01*
X3506336Y1522212D01*
X3504941Y1521587D01*
X3501221D01*
G01X3513621Y1528879D02*
Y1516379D01*
X3519821D01*
G01X3525246D02*
X3529121Y1528879D01*
X3532996Y1516379D01*
G01X3531601Y1520754D02*
X3526641D01*
G01X3541521Y1528879D02*
Y1516379D01*
G01X3537956Y1528879D02*
X3545086D01*
G01X3557021Y1516379D02*
X3550821D01*
Y1528879D01*
X3557021D01*
G01X3554541Y1522837D02*
X3550821D01*
G01X3562911Y1516379D02*
Y1528879D01*
X3566011D01*
X3567251Y1528254D01*
X3568181Y1527421D01*
X3568956Y1526171D01*
X3569576Y1524712D01*
X3569731Y1522629D01*
X3569576Y1520546D01*
X3568956Y1519087D01*
X3568181Y1517837D01*
X3567251Y1517004D01*
X3566011Y1516379D01*
X3562911D01*
G01X3501221Y1575479D02*
Y1587979D01*
X3504941D01*
X3506181Y1587354D01*
X3507111Y1585896D01*
X3507421Y1584229D01*
X3507111Y1582562D01*
X3506336Y1581312D01*
X3504941Y1580687D01*
X3501221D01*
G01X3513621Y1587979D02*
Y1575479D01*
X3519821D01*
G01X3525246D02*
X3529121Y1587979D01*
X3532996Y1575479D01*
G01X3531601Y1579854D02*
X3526641D01*
G01X3541521Y1587979D02*
Y1575479D01*
G01X3537956Y1587979D02*
X3545086D01*
G01X3557021Y1575479D02*
X3550821D01*
Y1587979D01*
X3557021D01*
G01X3554541Y1581937D02*
X3550821D01*
G01X3562911Y1575479D02*
Y1587979D01*
X3566011D01*
X3567251Y1587354D01*
X3568181Y1586521D01*
X3568956Y1585271D01*
X3569576Y1583812D01*
X3569731Y1581729D01*
X3569576Y1579646D01*
X3568956Y1578187D01*
X3568181Y1576937D01*
X3567251Y1576104D01*
X3566011Y1575479D01*
X3562911D01*
G01X3501221Y1634579D02*
Y1647079D01*
X3504941D01*
X3506181Y1646454D01*
X3507111Y1644996D01*
X3507421Y1643329D01*
X3507111Y1641662D01*
X3506336Y1640412D01*
X3504941Y1639787D01*
X3501221D01*
G01X3513621Y1647079D02*
Y1634579D01*
X3519821D01*
G01X3525246D02*
X3529121Y1647079D01*
X3532996Y1634579D01*
G01X3531601Y1638954D02*
X3526641D01*
G01X3541521Y1647079D02*
Y1634579D01*
G01X3537956Y1647079D02*
X3545086D01*
G01X3557021Y1634579D02*
X3550821D01*
Y1647079D01*
X3557021D01*
G01X3554541Y1641037D02*
X3550821D01*
G01X3562911Y1634579D02*
Y1647079D01*
X3566011D01*
X3567251Y1646454D01*
X3568181Y1645621D01*
X3568956Y1644371D01*
X3569576Y1642912D01*
X3569731Y1640829D01*
X3569576Y1638746D01*
X3568956Y1637287D01*
X3568181Y1636037D01*
X3567251Y1635204D01*
X3566011Y1634579D01*
X3562911D01*
G01X3501221Y1693679D02*
Y1706179D01*
X3504941D01*
X3506181Y1705554D01*
X3507111Y1704096D01*
X3507421Y1702429D01*
X3507111Y1700762D01*
X3506336Y1699512D01*
X3504941Y1698887D01*
X3501221D01*
G01X3513621Y1706179D02*
Y1693679D01*
X3519821D01*
G01X3525246D02*
X3529121Y1706179D01*
X3532996Y1693679D01*
G01X3531601Y1698054D02*
X3526641D01*
G01X3541521Y1706179D02*
Y1693679D01*
G01X3537956Y1706179D02*
X3545086D01*
G01X3557021Y1693679D02*
X3550821D01*
Y1706179D01*
X3557021D01*
G01X3554541Y1700137D02*
X3550821D01*
G01X3562911Y1693679D02*
Y1706179D01*
X3566011D01*
X3567251Y1705554D01*
X3568181Y1704721D01*
X3568956Y1703471D01*
X3569576Y1702012D01*
X3569731Y1699929D01*
X3569576Y1697846D01*
X3568956Y1696387D01*
X3568181Y1695137D01*
X3567251Y1694304D01*
X3566011Y1693679D01*
X3562911D01*
G01X3501221Y1752779D02*
Y1765279D01*
X3504941D01*
X3506181Y1764654D01*
X3507111Y1763196D01*
X3507421Y1761529D01*
X3507111Y1759862D01*
X3506336Y1758612D01*
X3504941Y1757987D01*
X3501221D01*
G01X3513621Y1765279D02*
Y1752779D01*
X3519821D01*
G01X3525246D02*
X3529121Y1765279D01*
X3532996Y1752779D01*
G01X3531601Y1757154D02*
X3526641D01*
G01X3541521Y1765279D02*
Y1752779D01*
G01X3537956Y1765279D02*
X3545086D01*
G01X3557021Y1752779D02*
X3550821D01*
Y1765279D01*
X3557021D01*
G01X3554541Y1759237D02*
X3550821D01*
G01X3562911Y1752779D02*
Y1765279D01*
X3566011D01*
X3567251Y1764654D01*
X3568181Y1763821D01*
X3568956Y1762571D01*
X3569576Y1761112D01*
X3569731Y1759029D01*
X3569576Y1756946D01*
X3568956Y1755487D01*
X3568181Y1754237D01*
X3567251Y1753404D01*
X3566011Y1752779D01*
X3562911D01*
G01X3501221Y1811879D02*
Y1824379D01*
X3504941D01*
X3506181Y1823754D01*
X3507111Y1822296D01*
X3507421Y1820629D01*
X3507111Y1818962D01*
X3506336Y1817712D01*
X3504941Y1817087D01*
X3501221D01*
G01X3513621Y1824379D02*
Y1811879D01*
X3519821D01*
G01X3525246D02*
X3529121Y1824379D01*
X3532996Y1811879D01*
G01X3531601Y1816254D02*
X3526641D01*
G01X3541521Y1824379D02*
Y1811879D01*
G01X3537956Y1824379D02*
X3545086D01*
G01X3557021Y1811879D02*
X3550821D01*
Y1824379D01*
X3557021D01*
G01X3554541Y1818337D02*
X3550821D01*
G01X3562911Y1811879D02*
Y1824379D01*
X3566011D01*
X3567251Y1823754D01*
X3568181Y1822921D01*
X3568956Y1821671D01*
X3569576Y1820212D01*
X3569731Y1818129D01*
X3569576Y1816046D01*
X3568956Y1814587D01*
X3568181Y1813337D01*
X3567251Y1812504D01*
X3566011Y1811879D01*
X3562911D01*
G01X3501221Y1870979D02*
Y1883479D01*
X3504941D01*
X3506181Y1882854D01*
X3507111Y1881396D01*
X3507421Y1879729D01*
X3507111Y1878062D01*
X3506336Y1876812D01*
X3504941Y1876187D01*
X3501221D01*
G01X3513621Y1883479D02*
Y1870979D01*
X3519821D01*
G01X3525246D02*
X3529121Y1883479D01*
X3532996Y1870979D01*
G01X3531601Y1875354D02*
X3526641D01*
G01X3541521Y1883479D02*
Y1870979D01*
G01X3537956Y1883479D02*
X3545086D01*
G01X3557021Y1870979D02*
X3550821D01*
Y1883479D01*
X3557021D01*
G01X3554541Y1877437D02*
X3550821D01*
G01X3562911Y1870979D02*
Y1883479D01*
X3566011D01*
X3567251Y1882854D01*
X3568181Y1882021D01*
X3568956Y1880771D01*
X3569576Y1879312D01*
X3569731Y1877229D01*
X3569576Y1875146D01*
X3568956Y1873687D01*
X3568181Y1872437D01*
X3567251Y1871604D01*
X3566011Y1870979D01*
X3562911D01*
G01X3501221Y1930079D02*
Y1942579D01*
X3504941D01*
X3506181Y1941954D01*
X3507111Y1940496D01*
X3507421Y1938829D01*
X3507111Y1937162D01*
X3506336Y1935912D01*
X3504941Y1935287D01*
X3501221D01*
G01X3513621Y1942579D02*
Y1930079D01*
X3519821D01*
G01X3525246D02*
X3529121Y1942579D01*
X3532996Y1930079D01*
G01X3531601Y1934454D02*
X3526641D01*
G01X3541521Y1942579D02*
Y1930079D01*
G01X3537956Y1942579D02*
X3545086D01*
G01X3557021Y1930079D02*
X3550821D01*
Y1942579D01*
X3557021D01*
G01X3554541Y1936537D02*
X3550821D01*
G01X3562911Y1930079D02*
Y1942579D01*
X3566011D01*
X3567251Y1941954D01*
X3568181Y1941121D01*
X3568956Y1939871D01*
X3569576Y1938412D01*
X3569731Y1936329D01*
X3569576Y1934246D01*
X3568956Y1932787D01*
X3568181Y1931537D01*
X3567251Y1930704D01*
X3566011Y1930079D01*
X3562911D01*
G01X3501221Y1989179D02*
Y2001679D01*
X3504941D01*
X3506181Y2001054D01*
X3507111Y1999596D01*
X3507421Y1997929D01*
X3507111Y1996262D01*
X3506336Y1995012D01*
X3504941Y1994387D01*
X3501221D01*
G01X3513621Y2001679D02*
Y1989179D01*
X3519821D01*
G01X3525246D02*
X3529121Y2001679D01*
X3532996Y1989179D01*
G01X3531601Y1993554D02*
X3526641D01*
G01X3541521Y2001679D02*
Y1989179D01*
G01X3537956Y2001679D02*
X3545086D01*
G01X3557021Y1989179D02*
X3550821D01*
Y2001679D01*
X3557021D01*
G01X3554541Y1995637D02*
X3550821D01*
G01X3562911Y1989179D02*
Y2001679D01*
X3566011D01*
X3567251Y2001054D01*
X3568181Y2000221D01*
X3568956Y1998971D01*
X3569576Y1997512D01*
X3569731Y1995429D01*
X3569576Y1993346D01*
X3568956Y1991887D01*
X3568181Y1990637D01*
X3567251Y1989804D01*
X3566011Y1989179D01*
X3562911D01*
G01X3501221Y2031229D02*
Y2043729D01*
X3504941D01*
X3506181Y2043104D01*
X3507111Y2041646D01*
X3507421Y2039979D01*
X3507111Y2038312D01*
X3506336Y2037062D01*
X3504941Y2036437D01*
X3501221D01*
G01X3513621Y2043729D02*
Y2031229D01*
X3519821D01*
G01X3525246D02*
X3529121Y2043729D01*
X3532996Y2031229D01*
G01X3531601Y2035604D02*
X3526641D01*
G01X3541521Y2043729D02*
Y2031229D01*
G01X3537956Y2043729D02*
X3545086D01*
G01X3557021Y2031229D02*
X3550821D01*
Y2043729D01*
X3557021D01*
G01X3554541Y2037687D02*
X3550821D01*
G01X3562911Y2031229D02*
Y2043729D01*
X3566011D01*
X3567251Y2043104D01*
X3568181Y2042271D01*
X3568956Y2041021D01*
X3569576Y2039562D01*
X3569731Y2037479D01*
X3569576Y2035396D01*
X3568956Y2033937D01*
X3568181Y2032687D01*
X3567251Y2031854D01*
X3566011Y2031229D01*
X3562911D01*
G01X3625221Y688979D02*
Y701479D01*
X3623361Y698979D01*
G01Y688979D02*
X3627081D01*
G01X3634211Y691479D02*
X3635141Y690020D01*
X3636381Y689187D01*
X3637776Y688979D01*
X3639016Y689187D01*
X3640256Y690229D01*
X3641031Y691479D01*
X3641186Y692729D01*
X3640876Y694187D01*
X3639791Y695229D01*
X3638706Y695646D01*
X3637311D01*
G01X3638706D02*
X3639636Y696271D01*
X3640411Y697312D01*
X3640721Y698562D01*
X3640411Y699812D01*
X3639636Y700854D01*
X3638241Y701479D01*
X3636846Y701271D01*
X3635451Y700437D01*
G01X3650021Y701479D02*
X3648781Y701062D01*
X3647851Y700021D01*
X3647231Y698771D01*
X3646766Y697104D01*
X3646611Y695229D01*
X3646766Y693354D01*
X3647231Y691687D01*
X3647851Y690437D01*
X3648781Y689396D01*
X3650021Y688979D01*
X3651261Y689396D01*
X3652191Y690437D01*
X3652811Y691687D01*
X3653276Y693354D01*
X3653431Y695229D01*
X3653276Y697104D01*
X3652811Y698771D01*
X3652191Y700021D01*
X3651261Y701062D01*
X3650021Y701479D01*
G01X3621811Y1637079D02*
X3622741Y1635620D01*
X3623981Y1634787D01*
X3625376Y1634579D01*
X3626616Y1634787D01*
X3627856Y1635829D01*
X3628631Y1637079D01*
X3628786Y1638329D01*
X3628476Y1639787D01*
X3627391Y1640829D01*
X3626306Y1641246D01*
X3624911D01*
G01X3626306D02*
X3627236Y1641871D01*
X3628011Y1642912D01*
X3628321Y1644162D01*
X3628011Y1645412D01*
X3627236Y1646454D01*
X3625841Y1647079D01*
X3624446Y1646871D01*
X3623051Y1646037D01*
G01X3634211Y1637079D02*
X3635141Y1635620D01*
X3636381Y1634787D01*
X3637776Y1634579D01*
X3639016Y1634787D01*
X3640256Y1635829D01*
X3641031Y1637079D01*
X3641186Y1638329D01*
X3640876Y1639787D01*
X3639791Y1640829D01*
X3638706Y1641246D01*
X3637311D01*
G01X3638706D02*
X3639636Y1641871D01*
X3640411Y1642912D01*
X3640721Y1644162D01*
X3640411Y1645412D01*
X3639636Y1646454D01*
X3638241Y1647079D01*
X3636846Y1646871D01*
X3635451Y1646037D01*
G01X3647076Y1639787D02*
X3648161Y1641246D01*
X3649091Y1642079D01*
X3650331Y1642496D01*
X3651416Y1642079D01*
X3652191Y1641246D01*
X3652811Y1639996D01*
X3652966Y1638537D01*
X3652811Y1637287D01*
X3652191Y1636037D01*
X3651261Y1634996D01*
X3650176Y1634579D01*
X3648936Y1634996D01*
X3647851Y1636245D01*
X3647231Y1638121D01*
X3647076Y1640204D01*
X3647386Y1642912D01*
X3647851Y1644371D01*
X3648626Y1645829D01*
X3649711Y1646871D01*
X3650796Y1647079D01*
X3651881Y1646662D01*
X3652656Y1645621D01*
G01X3622276Y1698887D02*
X3623361Y1700346D01*
X3624291Y1701179D01*
X3625531Y1701596D01*
X3626616Y1701179D01*
X3627391Y1700346D01*
X3628011Y1699096D01*
X3628166Y1697637D01*
X3628011Y1696387D01*
X3627391Y1695137D01*
X3626461Y1694096D01*
X3625376Y1693679D01*
X3624136Y1694096D01*
X3623051Y1695345D01*
X3622431Y1697221D01*
X3622276Y1699304D01*
X3622586Y1702012D01*
X3623051Y1703471D01*
X3623826Y1704929D01*
X3624911Y1705971D01*
X3625996Y1706179D01*
X3627081Y1705762D01*
X3627856Y1704721D01*
G01X3637621Y1706179D02*
X3636381Y1705762D01*
X3635451Y1704721D01*
X3634831Y1703471D01*
X3634366Y1701804D01*
X3634211Y1699929D01*
X3634366Y1698054D01*
X3634831Y1696387D01*
X3635451Y1695137D01*
X3636381Y1694096D01*
X3637621Y1693679D01*
X3638861Y1694096D01*
X3639791Y1695137D01*
X3640411Y1696387D01*
X3640876Y1698054D01*
X3641031Y1699929D01*
X3640876Y1701804D01*
X3640411Y1703471D01*
X3639791Y1704721D01*
X3638861Y1705762D01*
X3637621Y1706179D01*
G01X3650021Y1693679D02*
X3651106Y1693887D01*
X3652346Y1694512D01*
X3653121Y1695554D01*
X3653431Y1697012D01*
X3653121Y1698470D01*
X3652191Y1699721D01*
X3650796Y1700346D01*
X3649246D01*
X3648316Y1700762D01*
X3647541Y1701804D01*
X3647231Y1703262D01*
X3647696Y1704721D01*
X3648781Y1705762D01*
X3650021Y1706179D01*
X3651261Y1705762D01*
X3652346Y1704721D01*
X3652811Y1703262D01*
X3652501Y1701804D01*
X3651726Y1700762D01*
X3650796Y1700346D01*
X3649246D01*
X3647851Y1699721D01*
X3646921Y1698470D01*
X3646611Y1697012D01*
X3646921Y1695554D01*
X3647696Y1694512D01*
X3648936Y1693887D01*
X3650021Y1693679D01*
G01X3612821Y1752779D02*
Y1765279D01*
X3610961Y1762779D01*
G01Y1752779D02*
X3614681D01*
G01X3627081D02*
Y1765279D01*
X3621346Y1756321D01*
X3629096D01*
G01X3637621Y1752779D02*
Y1765279D01*
X3635761Y1762779D01*
G01Y1752779D02*
X3639481D01*
G01X3650021D02*
X3651106Y1752987D01*
X3652346Y1753612D01*
X3653121Y1754654D01*
X3653431Y1756112D01*
X3653121Y1757570D01*
X3652191Y1758821D01*
X3650796Y1759446D01*
X3649246D01*
X3648316Y1759862D01*
X3647541Y1760904D01*
X3647231Y1762362D01*
X3647696Y1763821D01*
X3648781Y1764862D01*
X3650021Y1765279D01*
X3651261Y1764862D01*
X3652346Y1763821D01*
X3652811Y1762362D01*
X3652501Y1760904D01*
X3651726Y1759862D01*
X3650796Y1759446D01*
X3649246D01*
X3647851Y1758821D01*
X3646921Y1757570D01*
X3646611Y1756112D01*
X3646921Y1754654D01*
X3647696Y1753612D01*
X3648936Y1752987D01*
X3650021Y1752779D01*
G01X3659011Y1754654D02*
X3659941Y1753612D01*
X3661026Y1752987D01*
X3662421Y1752779D01*
X3663816Y1753196D01*
X3664901Y1754029D01*
X3665676Y1755487D01*
X3665831Y1757154D01*
X3665521Y1758821D01*
X3664746Y1759862D01*
X3663661Y1760696D01*
X3662576Y1760904D01*
X3661491Y1760696D01*
X3660096Y1759862D01*
X3660561Y1765279D01*
X3664746D01*
G01X3619021Y1811879D02*
Y1824379D01*
X3617161Y1821879D01*
G01Y1811879D02*
X3620881D01*
G01X3628786Y1813337D02*
X3629871Y1812296D01*
X3631111Y1811879D01*
X3632351Y1812296D01*
X3633436Y1813545D01*
X3634211Y1815421D01*
X3634521Y1817296D01*
Y1819587D01*
X3634211Y1821462D01*
X3633436Y1823129D01*
X3632506Y1823962D01*
X3631421Y1824379D01*
X3630181Y1823962D01*
X3629251Y1823129D01*
X3628631Y1821879D01*
X3628321Y1820212D01*
X3628631Y1818754D01*
X3629406Y1817296D01*
X3630336Y1816462D01*
X3631421Y1816254D01*
X3632661Y1816670D01*
X3633591Y1817712D01*
X3634521Y1819587D01*
G01X3640876Y1822296D02*
X3641806Y1823545D01*
X3642891Y1824171D01*
X3644131Y1824379D01*
X3645681Y1823962D01*
X3646766Y1822921D01*
X3647076Y1821671D01*
X3646921Y1820420D01*
X3646301Y1819379D01*
X3643201Y1817296D01*
X3641806Y1815837D01*
X3640876Y1813754D01*
X3640566Y1811879D01*
X3647076D01*
G01X3652811Y1813754D02*
X3653741Y1812712D01*
X3654826Y1812087D01*
X3656221Y1811879D01*
X3657616Y1812296D01*
X3658701Y1813129D01*
X3659476Y1814587D01*
X3659631Y1816254D01*
X3659321Y1817921D01*
X3658546Y1818962D01*
X3657461Y1819796D01*
X3656376Y1820004D01*
X3655291Y1819796D01*
X3653896Y1818962D01*
X3654361Y1824379D01*
X3658546D01*
G01X3625221Y1870979D02*
Y1883479D01*
X3623361Y1880979D01*
G01Y1870979D02*
X3627081D01*
G01X3637311D02*
X3637621Y1873687D01*
X3638086Y1875979D01*
X3638706Y1878062D01*
X3639481Y1880354D01*
X3640721Y1883479D01*
X3634521D01*
G01X3647076Y1876187D02*
X3648161Y1877646D01*
X3649091Y1878479D01*
X3650331Y1878896D01*
X3651416Y1878479D01*
X3652191Y1877646D01*
X3652811Y1876396D01*
X3652966Y1874937D01*
X3652811Y1873687D01*
X3652191Y1872437D01*
X3651261Y1871396D01*
X3650176Y1870979D01*
X3648936Y1871396D01*
X3647851Y1872645D01*
X3647231Y1874521D01*
X3647076Y1876604D01*
X3647386Y1879312D01*
X3647851Y1880771D01*
X3648626Y1882229D01*
X3649711Y1883271D01*
X3650796Y1883479D01*
X3651881Y1883062D01*
X3652656Y1882021D01*
G01X3609876Y1940496D02*
X3610806Y1941745D01*
X3611891Y1942371D01*
X3613131Y1942579D01*
X3614681Y1942162D01*
X3615766Y1941121D01*
X3616076Y1939871D01*
X3615921Y1938620D01*
X3615301Y1937579D01*
X3612201Y1935496D01*
X3610806Y1934037D01*
X3609876Y1931954D01*
X3609566Y1930079D01*
X3616076D01*
G01X3625221D02*
Y1942579D01*
X3623361Y1940079D01*
G01Y1930079D02*
X3627081D01*
G01X3634676Y1940496D02*
X3635606Y1941745D01*
X3636691Y1942371D01*
X3637931Y1942579D01*
X3639481Y1942162D01*
X3640566Y1941121D01*
X3640876Y1939871D01*
X3640721Y1938620D01*
X3640101Y1937579D01*
X3637001Y1935496D01*
X3635606Y1934037D01*
X3634676Y1931954D01*
X3634366Y1930079D01*
X3640876D01*
G01X3647076Y1935287D02*
X3648161Y1936746D01*
X3649091Y1937579D01*
X3650331Y1937996D01*
X3651416Y1937579D01*
X3652191Y1936746D01*
X3652811Y1935496D01*
X3652966Y1934037D01*
X3652811Y1932787D01*
X3652191Y1931537D01*
X3651261Y1930496D01*
X3650176Y1930079D01*
X3648936Y1930496D01*
X3647851Y1931745D01*
X3647231Y1933621D01*
X3647076Y1935704D01*
X3647386Y1938412D01*
X3647851Y1939871D01*
X3648626Y1941329D01*
X3649711Y1942371D01*
X3650796Y1942579D01*
X3651881Y1942162D01*
X3652656Y1941121D01*
G01X3662421Y1930079D02*
X3663506Y1930287D01*
X3664746Y1930912D01*
X3665521Y1931954D01*
X3665831Y1933412D01*
X3665521Y1934870D01*
X3664591Y1936121D01*
X3663196Y1936746D01*
X3661646D01*
X3660716Y1937162D01*
X3659941Y1938204D01*
X3659631Y1939662D01*
X3660096Y1941121D01*
X3661181Y1942162D01*
X3662421Y1942579D01*
X3663661Y1942162D01*
X3664746Y1941121D01*
X3665211Y1939662D01*
X3664901Y1938204D01*
X3664126Y1937162D01*
X3663196Y1936746D01*
X3661646D01*
X3660251Y1936121D01*
X3659321Y1934870D01*
X3659011Y1933412D01*
X3659321Y1931954D01*
X3660096Y1930912D01*
X3661336Y1930287D01*
X3662421Y1930079D01*
G01X3622276Y1999596D02*
X3623206Y2000845D01*
X3624291Y2001471D01*
X3625531Y2001679D01*
X3627081Y2001262D01*
X3628166Y2000221D01*
X3628476Y1998971D01*
X3628321Y1997720D01*
X3627701Y1996679D01*
X3624601Y1994596D01*
X3623206Y1993137D01*
X3622276Y1991054D01*
X3621966Y1989179D01*
X3628476D01*
G01X3637311D02*
X3637621Y1991887D01*
X3638086Y1994179D01*
X3638706Y1996262D01*
X3639481Y1998554D01*
X3640721Y2001679D01*
X3634521D01*
G01X3649711Y1989179D02*
X3650021Y1991887D01*
X3650486Y1994179D01*
X3651106Y1996262D01*
X3651881Y1998554D01*
X3653121Y2001679D01*
X3646921D01*
G01X3625221Y2031229D02*
X3623981Y2031437D01*
X3622896Y2032270D01*
X3621966Y2033521D01*
X3621346Y2034979D01*
X3621036Y2036646D01*
Y2038312D01*
X3621346Y2039979D01*
X3621966Y2041437D01*
X3622896Y2042687D01*
X3623981Y2043521D01*
X3625221Y2043729D01*
X3626461Y2043521D01*
X3627546Y2042687D01*
X3628476Y2041437D01*
X3629096Y2039979D01*
X3629406Y2038312D01*
Y2036646D01*
X3629096Y2034979D01*
X3628476Y2033521D01*
X3627546Y2032270D01*
X3626461Y2031437D01*
X3625221Y2031229D01*
G01X3626461Y2034562D02*
X3628321Y2031229D01*
G01X3637621Y2043729D02*
Y2031229D01*
G01X3634056Y2043729D02*
X3641186D01*
G01X3650021Y2031229D02*
Y2036854D01*
X3646921Y2043729D01*
G01X3653121D02*
X3650021Y2036854D01*
G01X3637621Y-197521D02*
Y-185021D01*
X3635761Y-187521D01*
G01Y-197521D02*
X3639481D01*
G01X3634676Y-128004D02*
X3635606Y-126755D01*
X3636691Y-126129D01*
X3637931Y-125921D01*
X3639481Y-126338D01*
X3640566Y-127379D01*
X3640876Y-128629D01*
X3640721Y-129880D01*
X3640101Y-130921D01*
X3637001Y-133004D01*
X3635606Y-134463D01*
X3634676Y-136546D01*
X3634366Y-138421D01*
X3640876D01*
G01X3634676Y-68904D02*
X3635606Y-67655D01*
X3636691Y-67029D01*
X3637931Y-66821D01*
X3639481Y-67238D01*
X3640566Y-68279D01*
X3640876Y-69529D01*
X3640721Y-70780D01*
X3640101Y-71821D01*
X3637001Y-73904D01*
X3635606Y-75363D01*
X3634676Y-77446D01*
X3634366Y-79321D01*
X3640876D01*
G01X3628786Y-18763D02*
X3629871Y-19804D01*
X3631111Y-20221D01*
X3632351Y-19804D01*
X3633436Y-18555D01*
X3634211Y-16679D01*
X3634521Y-14804D01*
Y-12513D01*
X3634211Y-10638D01*
X3633436Y-8971D01*
X3632506Y-8138D01*
X3631421Y-7721D01*
X3630181Y-8138D01*
X3629251Y-8971D01*
X3628631Y-10221D01*
X3628321Y-11888D01*
X3628631Y-13346D01*
X3629406Y-14804D01*
X3630336Y-15638D01*
X3631421Y-15846D01*
X3632661Y-15430D01*
X3633591Y-14388D01*
X3634521Y-12513D01*
G01X3640876Y-15013D02*
X3641961Y-13554D01*
X3642891Y-12721D01*
X3644131Y-12304D01*
X3645216Y-12721D01*
X3645991Y-13554D01*
X3646611Y-14804D01*
X3646766Y-16263D01*
X3646611Y-17513D01*
X3645991Y-18763D01*
X3645061Y-19804D01*
X3643976Y-20221D01*
X3642736Y-19804D01*
X3641651Y-18555D01*
X3641031Y-16679D01*
X3640876Y-14596D01*
X3641186Y-11888D01*
X3641651Y-10429D01*
X3642426Y-8971D01*
X3643511Y-7929D01*
X3644596Y-7721D01*
X3645681Y-8138D01*
X3646456Y-9179D01*
G01X3634676Y44087D02*
X3635761Y45546D01*
X3636691Y46379D01*
X3637931Y46796D01*
X3639016Y46379D01*
X3639791Y45546D01*
X3640411Y44296D01*
X3640566Y42837D01*
X3640411Y41587D01*
X3639791Y40337D01*
X3638861Y39296D01*
X3637776Y38879D01*
X3636536Y39296D01*
X3635451Y40545D01*
X3634831Y42421D01*
X3634676Y44504D01*
X3634986Y47212D01*
X3635451Y48671D01*
X3636226Y50129D01*
X3637311Y51171D01*
X3638396Y51379D01*
X3639481Y50962D01*
X3640256Y49921D01*
G01X3634676Y108396D02*
X3635606Y109645D01*
X3636691Y110271D01*
X3637931Y110479D01*
X3639481Y110062D01*
X3640566Y109021D01*
X3640876Y107771D01*
X3640721Y106520D01*
X3640101Y105479D01*
X3637001Y103396D01*
X3635606Y101937D01*
X3634676Y99854D01*
X3634366Y97979D01*
X3640876D01*
G01X3634676Y167496D02*
X3635606Y168745D01*
X3636691Y169371D01*
X3637931Y169579D01*
X3639481Y169162D01*
X3640566Y168121D01*
X3640876Y166871D01*
X3640721Y165620D01*
X3640101Y164579D01*
X3637001Y162496D01*
X3635606Y161037D01*
X3634676Y158954D01*
X3634366Y157079D01*
X3640876D01*
G01X3631421Y216179D02*
Y228679D01*
X3629561Y226179D01*
G01Y216179D02*
X3633281D01*
G01X3640876Y226596D02*
X3641806Y227845D01*
X3642891Y228471D01*
X3644131Y228679D01*
X3645681Y228262D01*
X3646766Y227221D01*
X3647076Y225971D01*
X3646921Y224720D01*
X3646301Y223679D01*
X3643201Y221596D01*
X3641806Y220137D01*
X3640876Y218054D01*
X3640566Y216179D01*
X3647076D01*
G01X3634676Y280487D02*
X3635761Y281946D01*
X3636691Y282779D01*
X3637931Y283196D01*
X3639016Y282779D01*
X3639791Y281946D01*
X3640411Y280696D01*
X3640566Y279237D01*
X3640411Y277987D01*
X3639791Y276737D01*
X3638861Y275696D01*
X3637776Y275279D01*
X3636536Y275696D01*
X3635451Y276945D01*
X3634831Y278821D01*
X3634676Y280904D01*
X3634986Y283612D01*
X3635451Y285071D01*
X3636226Y286529D01*
X3637311Y287571D01*
X3638396Y287779D01*
X3639481Y287362D01*
X3640256Y286321D01*
G01X3639481Y334379D02*
Y346879D01*
X3633746Y337921D01*
X3641496D01*
G01X3634211Y395979D02*
X3635141Y394520D01*
X3636381Y393687D01*
X3637776Y393479D01*
X3639016Y393687D01*
X3640256Y394729D01*
X3641031Y395979D01*
X3641186Y397229D01*
X3640876Y398687D01*
X3639791Y399729D01*
X3638706Y400146D01*
X3637311D01*
G01X3638706D02*
X3639636Y400771D01*
X3640411Y401812D01*
X3640721Y403062D01*
X3640411Y404312D01*
X3639636Y405354D01*
X3638241Y405979D01*
X3636846Y405771D01*
X3635451Y404937D01*
G01X3634676Y462996D02*
X3635606Y464245D01*
X3636691Y464871D01*
X3637931Y465079D01*
X3639481Y464662D01*
X3640566Y463621D01*
X3640876Y462371D01*
X3640721Y461120D01*
X3640101Y460079D01*
X3637001Y457996D01*
X3635606Y456537D01*
X3634676Y454454D01*
X3634366Y452579D01*
X3640876D01*
G01X3637621Y511679D02*
Y524179D01*
X3635761Y521679D01*
G01Y511679D02*
X3639481D01*
G01X3637621Y570779D02*
Y583279D01*
X3635761Y580779D01*
G01Y570779D02*
X3639481D01*
G01X3637621Y629879D02*
X3638706Y630087D01*
X3639946Y630712D01*
X3640721Y631754D01*
X3641031Y633212D01*
X3640721Y634670D01*
X3639791Y635921D01*
X3638396Y636546D01*
X3636846D01*
X3635916Y636962D01*
X3635141Y638004D01*
X3634831Y639462D01*
X3635296Y640921D01*
X3636381Y641962D01*
X3637621Y642379D01*
X3638861Y641962D01*
X3639946Y640921D01*
X3640411Y639462D01*
X3640101Y638004D01*
X3639326Y636962D01*
X3638396Y636546D01*
X3636846D01*
X3635451Y635921D01*
X3634521Y634670D01*
X3634211Y633212D01*
X3634521Y631754D01*
X3635296Y630712D01*
X3636536Y630087D01*
X3637621Y629879D01*
G01X3634676Y758496D02*
X3635606Y759745D01*
X3636691Y760371D01*
X3637931Y760579D01*
X3639481Y760162D01*
X3640566Y759121D01*
X3640876Y757871D01*
X3640721Y756620D01*
X3640101Y755579D01*
X3637001Y753496D01*
X3635606Y752037D01*
X3634676Y749954D01*
X3634366Y748079D01*
X3640876D01*
G01X3634676Y817596D02*
X3635606Y818845D01*
X3636691Y819471D01*
X3637931Y819679D01*
X3639481Y819262D01*
X3640566Y818221D01*
X3640876Y816971D01*
X3640721Y815720D01*
X3640101Y814679D01*
X3637001Y812596D01*
X3635606Y811137D01*
X3634676Y809054D01*
X3634366Y807179D01*
X3640876D01*
G01X3628476Y876696D02*
X3629406Y877945D01*
X3630491Y878571D01*
X3631731Y878779D01*
X3633281Y878362D01*
X3634366Y877321D01*
X3634676Y876071D01*
X3634521Y874820D01*
X3633901Y873779D01*
X3630801Y871696D01*
X3629406Y870237D01*
X3628476Y868154D01*
X3628166Y866279D01*
X3634676D01*
G01X3643821D02*
Y878779D01*
X3641961Y876279D01*
G01Y866279D02*
X3645681D01*
G01X3637621Y925379D02*
Y937879D01*
X3635761Y935379D01*
G01Y925379D02*
X3639481D01*
G01X3634676Y994896D02*
X3635606Y996145D01*
X3636691Y996771D01*
X3637931Y996979D01*
X3639481Y996562D01*
X3640566Y995521D01*
X3640876Y994271D01*
X3640721Y993020D01*
X3640101Y991979D01*
X3637001Y989896D01*
X3635606Y988437D01*
X3634676Y986354D01*
X3634366Y984479D01*
X3640876D01*
G01X3639481Y1043579D02*
Y1056079D01*
X3633746Y1047121D01*
X3641496D01*
G01X3634676Y1113096D02*
X3635606Y1114345D01*
X3636691Y1114971D01*
X3637931Y1115179D01*
X3639481Y1114762D01*
X3640566Y1113721D01*
X3640876Y1112471D01*
X3640721Y1111220D01*
X3640101Y1110179D01*
X3637001Y1108096D01*
X3635606Y1106637D01*
X3634676Y1104554D01*
X3634366Y1102679D01*
X3640876D01*
G01X3633281Y1161779D02*
Y1174279D01*
X3627546Y1165321D01*
X3635296D01*
G01X3643821Y1161779D02*
X3644906Y1161987D01*
X3646146Y1162612D01*
X3646921Y1163654D01*
X3647231Y1165112D01*
X3646921Y1166570D01*
X3645991Y1167821D01*
X3644596Y1168446D01*
X3643046D01*
X3642116Y1168862D01*
X3641341Y1169904D01*
X3641031Y1171362D01*
X3641496Y1172821D01*
X3642581Y1173862D01*
X3643821Y1174279D01*
X3645061Y1173862D01*
X3646146Y1172821D01*
X3646611Y1171362D01*
X3646301Y1169904D01*
X3645526Y1168862D01*
X3644596Y1168446D01*
X3643046D01*
X3641651Y1167821D01*
X3640721Y1166570D01*
X3640411Y1165112D01*
X3640721Y1163654D01*
X3641496Y1162612D01*
X3642736Y1161987D01*
X3643821Y1161779D01*
G01X3631421Y1220879D02*
Y1233379D01*
X3629561Y1230879D01*
G01Y1220879D02*
X3633281D01*
G01X3640876Y1226087D02*
X3641961Y1227546D01*
X3642891Y1228379D01*
X3644131Y1228796D01*
X3645216Y1228379D01*
X3645991Y1227546D01*
X3646611Y1226296D01*
X3646766Y1224837D01*
X3646611Y1223587D01*
X3645991Y1222337D01*
X3645061Y1221296D01*
X3643976Y1220879D01*
X3642736Y1221296D01*
X3641651Y1222545D01*
X3641031Y1224421D01*
X3640876Y1226504D01*
X3641186Y1229212D01*
X3641651Y1230671D01*
X3642426Y1232129D01*
X3643511Y1233171D01*
X3644596Y1233379D01*
X3645681Y1232962D01*
X3646456Y1231921D01*
G01X3631111Y1279979D02*
X3631421Y1282687D01*
X3631886Y1284979D01*
X3632506Y1287062D01*
X3633281Y1289354D01*
X3634521Y1292479D01*
X3628321D01*
G01X3640876Y1290396D02*
X3641806Y1291645D01*
X3642891Y1292271D01*
X3644131Y1292479D01*
X3645681Y1292062D01*
X3646766Y1291021D01*
X3647076Y1289771D01*
X3646921Y1288520D01*
X3646301Y1287479D01*
X3643201Y1285396D01*
X3641806Y1283937D01*
X3640876Y1281854D01*
X3640566Y1279979D01*
X3647076D01*
G01X3633281Y1339079D02*
Y1351579D01*
X3627546Y1342621D01*
X3635296D01*
G01X3640876Y1344287D02*
X3641961Y1345746D01*
X3642891Y1346579D01*
X3644131Y1346996D01*
X3645216Y1346579D01*
X3645991Y1345746D01*
X3646611Y1344496D01*
X3646766Y1343037D01*
X3646611Y1341787D01*
X3645991Y1340537D01*
X3645061Y1339496D01*
X3643976Y1339079D01*
X3642736Y1339496D01*
X3641651Y1340745D01*
X3641031Y1342621D01*
X3640876Y1344704D01*
X3641186Y1347412D01*
X3641651Y1348871D01*
X3642426Y1350329D01*
X3643511Y1351371D01*
X3644596Y1351579D01*
X3645681Y1351162D01*
X3646456Y1350121D01*
G01X3628476Y1403387D02*
X3629561Y1404846D01*
X3630491Y1405679D01*
X3631731Y1406096D01*
X3632816Y1405679D01*
X3633591Y1404846D01*
X3634211Y1403596D01*
X3634366Y1402137D01*
X3634211Y1400887D01*
X3633591Y1399637D01*
X3632661Y1398596D01*
X3631576Y1398179D01*
X3630336Y1398596D01*
X3629251Y1399845D01*
X3628631Y1401721D01*
X3628476Y1403804D01*
X3628786Y1406512D01*
X3629251Y1407971D01*
X3630026Y1409429D01*
X3631111Y1410471D01*
X3632196Y1410679D01*
X3633281Y1410262D01*
X3634056Y1409221D01*
G01X3643821Y1410679D02*
X3642581Y1410262D01*
X3641651Y1409221D01*
X3641031Y1407971D01*
X3640566Y1406304D01*
X3640411Y1404429D01*
X3640566Y1402554D01*
X3641031Y1400887D01*
X3641651Y1399637D01*
X3642581Y1398596D01*
X3643821Y1398179D01*
X3645061Y1398596D01*
X3645991Y1399637D01*
X3646611Y1400887D01*
X3647076Y1402554D01*
X3647231Y1404429D01*
X3647076Y1406304D01*
X3646611Y1407971D01*
X3645991Y1409221D01*
X3645061Y1410262D01*
X3643821Y1410679D01*
G01X3633281Y1457279D02*
Y1469779D01*
X3627546Y1460821D01*
X3635296D01*
G01X3643821Y1457279D02*
X3644906Y1457487D01*
X3646146Y1458112D01*
X3646921Y1459154D01*
X3647231Y1460612D01*
X3646921Y1462070D01*
X3645991Y1463321D01*
X3644596Y1463946D01*
X3643046D01*
X3642116Y1464362D01*
X3641341Y1465404D01*
X3641031Y1466862D01*
X3641496Y1468321D01*
X3642581Y1469362D01*
X3643821Y1469779D01*
X3645061Y1469362D01*
X3646146Y1468321D01*
X3646611Y1466862D01*
X3646301Y1465404D01*
X3645526Y1464362D01*
X3644596Y1463946D01*
X3643046D01*
X3641651Y1463321D01*
X3640721Y1462070D01*
X3640411Y1460612D01*
X3640721Y1459154D01*
X3641496Y1458112D01*
X3642736Y1457487D01*
X3643821Y1457279D01*
G01X3637621Y1516379D02*
Y1528879D01*
X3635761Y1526379D01*
G01Y1516379D02*
X3639481D01*
G01X3633281Y1575479D02*
Y1587979D01*
X3627546Y1579021D01*
X3635296D01*
G01X3643821Y1587979D02*
X3642581Y1587562D01*
X3641651Y1586521D01*
X3641031Y1585271D01*
X3640566Y1583604D01*
X3640411Y1581729D01*
X3640566Y1579854D01*
X3641031Y1578187D01*
X3641651Y1576937D01*
X3642581Y1575896D01*
X3643821Y1575479D01*
X3645061Y1575896D01*
X3645991Y1576937D01*
X3646611Y1578187D01*
X3647076Y1579854D01*
X3647231Y1581729D01*
X3647076Y1583604D01*
X3646611Y1585271D01*
X3645991Y1586521D01*
X3645061Y1587562D01*
X3643821Y1587979D01*
G01X3804760Y3579689D02*
X3805380Y3580314D01*
X3805845Y3581355D01*
X3806155Y3582814D01*
X3805845Y3584064D01*
X3805225Y3584897D01*
X3804140Y3585522D01*
X3799955D01*
Y3573022D01*
X3805070D01*
X3806155Y3573855D01*
X3806775Y3575105D01*
X3807085Y3576564D01*
X3806775Y3578022D01*
X3805845Y3579272D01*
X3804760Y3579689D01*
X3799955D01*
G01X3812045Y3573022D02*
X3815920Y3585522D01*
X3819795Y3573022D01*
G01X3818400Y3577397D02*
X3813440D01*
G01X3831730Y3584480D02*
X3830800Y3585105D01*
X3829715Y3585522D01*
X3828475D01*
X3827080Y3584897D01*
X3825995Y3583855D01*
X3825220Y3582605D01*
X3824600Y3580522D01*
X3824445Y3578647D01*
X3824755Y3576772D01*
X3825220Y3575522D01*
X3826150Y3574272D01*
X3827235Y3573439D01*
X3828320Y3573022D01*
X3829405D01*
X3830490Y3573439D01*
X3831420Y3574063D01*
X3832195Y3574897D01*
G01X3837310Y3573022D02*
Y3585522D01*
G01X3843200D02*
X3837310Y3577813D01*
G01X3844130Y3573022D02*
X3839945Y3581355D01*
G01X3849710Y3573022D02*
Y3585522D01*
X3852810D01*
X3854050Y3584897D01*
X3854980Y3584064D01*
X3855755Y3582814D01*
X3856375Y3581355D01*
X3856530Y3579272D01*
X3856375Y3577189D01*
X3855755Y3575730D01*
X3854980Y3574480D01*
X3854050Y3573647D01*
X3852810Y3573022D01*
X3849710D01*
G01X3862420D02*
Y3585522D01*
X3866295D01*
X3867535Y3584897D01*
X3868310Y3584064D01*
X3868620Y3582397D01*
X3868310Y3580730D01*
X3867380Y3579689D01*
X3866295Y3579064D01*
X3862420D01*
G01X3866295D02*
X3868620Y3573022D01*
G01X3876060Y3585522D02*
X3879780D01*
G01X3877920D02*
Y3573022D01*
G01X3876060D02*
X3879780D01*
G01X3887220Y3585522D02*
Y3573022D01*
X3893420D01*
G01X3899620Y3585522D02*
Y3573022D01*
X3905820D01*
G01X3924265Y3574688D02*
X3925505Y3573647D01*
X3926900Y3573022D01*
X3928140D01*
X3929380Y3573647D01*
X3930310Y3574688D01*
X3930775Y3576147D01*
X3930465Y3577605D01*
X3929690Y3578855D01*
X3928295Y3579689D01*
X3926435Y3580105D01*
X3925350Y3580939D01*
X3924885Y3582397D01*
X3925195Y3583855D01*
X3925970Y3584897D01*
X3927055Y3585522D01*
X3928140D01*
X3929225Y3585105D01*
X3930155Y3584064D01*
G01X3939920Y3585522D02*
Y3573022D01*
G01X3936355Y3585522D02*
X3943485D01*
G01X3948910D02*
Y3576564D01*
X3949530Y3574688D01*
X3950770Y3573439D01*
X3952320Y3573022D01*
X3953870Y3573439D01*
X3955110Y3574688D01*
X3955730Y3576564D01*
Y3585522D01*
G01X3965960Y3579689D02*
X3966580Y3580314D01*
X3967045Y3581355D01*
X3967355Y3582814D01*
X3967045Y3584064D01*
X3966425Y3584897D01*
X3965340Y3585522D01*
X3961155D01*
Y3573022D01*
X3966270D01*
X3967355Y3573855D01*
X3967975Y3575105D01*
X3968285Y3576564D01*
X3967975Y3578022D01*
X3967045Y3579272D01*
X3965960Y3579689D01*
X3961155D01*
G01X3986420Y3585522D02*
Y3573022D01*
X3992620D01*
G01X4005020D02*
X3998820D01*
Y3585522D01*
X4005020D01*
G01X4002540Y3579480D02*
X3998820D01*
G01X4010755Y3573022D02*
Y3585522D01*
X4017885Y3573022D01*
Y3585522D01*
G01X4027650Y3579272D02*
X4030750D01*
Y3575522D01*
X4029820Y3574272D01*
X4028735Y3573439D01*
X4027185Y3573022D01*
X4025635Y3573439D01*
X4024550Y3574272D01*
X4023620Y3575522D01*
X4023000Y3576980D01*
X4022690Y3578647D01*
Y3580105D01*
X4023000Y3581355D01*
X4023620Y3582814D01*
X4024550Y3584064D01*
X4025480Y3584897D01*
X4026720Y3585522D01*
X4027805D01*
X4029045Y3585105D01*
X4029975Y3584272D01*
G01X4039120Y3585522D02*
Y3573022D01*
G01X4035555Y3585522D02*
X4042685D01*
G01X4048265Y3573022D02*
Y3585522D01*
G01X4054775D02*
Y3573022D01*
G01Y3579272D02*
X4048265D01*
G01X4076320Y3585522D02*
Y3573022D01*
G01X4072755Y3585522D02*
X4079885D01*
G01X4088720Y3573022D02*
X4087480Y3573230D01*
X4086395Y3574063D01*
X4085465Y3575314D01*
X4084845Y3576772D01*
X4084535Y3578439D01*
Y3580105D01*
X4084845Y3581772D01*
X4085465Y3583230D01*
X4086395Y3584480D01*
X4087480Y3585314D01*
X4088720Y3585522D01*
X4089960Y3585314D01*
X4091045Y3584480D01*
X4091975Y3583230D01*
X4092595Y3581772D01*
X4092905Y3580105D01*
Y3578439D01*
X4092595Y3576772D01*
X4091975Y3575314D01*
X4091045Y3574063D01*
X4089960Y3573230D01*
X4088720Y3573022D01*
G01X4098020Y3585522D02*
Y3573022D01*
X4104220D01*
G01X4116620D02*
X4110420D01*
Y3585522D01*
X4116620D01*
G01X4114140Y3579480D02*
X4110420D01*
G01X4122820Y3573022D02*
Y3585522D01*
X4126695D01*
X4127935Y3584897D01*
X4128710Y3584064D01*
X4129020Y3582397D01*
X4128710Y3580730D01*
X4127780Y3579689D01*
X4126695Y3579064D01*
X4122820D01*
G01X4126695D02*
X4129020Y3573022D01*
G01X4134445D02*
X4138320Y3585522D01*
X4142195Y3573022D01*
G01X4140800Y3577397D02*
X4135840D01*
G01X4147155Y3573022D02*
Y3585522D01*
X4154285Y3573022D01*
Y3585522D01*
G01X4166530Y3584480D02*
X4165600Y3585105D01*
X4164515Y3585522D01*
X4163275D01*
X4161880Y3584897D01*
X4160795Y3583855D01*
X4160020Y3582605D01*
X4159400Y3580522D01*
X4159245Y3578647D01*
X4159555Y3576772D01*
X4160020Y3575522D01*
X4160950Y3574272D01*
X4162035Y3573439D01*
X4163120Y3573022D01*
X4164205D01*
X4165290Y3573439D01*
X4166220Y3574063D01*
X4166995Y3574897D01*
G01X4178620Y3573022D02*
X4172420D01*
Y3585522D01*
X4178620D01*
G01X4176140Y3579480D02*
X4172420D01*
G01X4200320Y3585522D02*
Y3573022D01*
G01X4196755Y3585522D02*
X4203885D01*
G01X4212720Y3573022D02*
X4211480Y3573230D01*
X4210395Y3574063D01*
X4209465Y3575314D01*
X4208845Y3576772D01*
X4208535Y3578439D01*
Y3580105D01*
X4208845Y3581772D01*
X4209465Y3583230D01*
X4210395Y3584480D01*
X4211480Y3585314D01*
X4212720Y3585522D01*
X4213960Y3585314D01*
X4215045Y3584480D01*
X4215975Y3583230D01*
X4216595Y3581772D01*
X4216905Y3580105D01*
Y3578439D01*
X4216595Y3576772D01*
X4215975Y3575314D01*
X4215045Y3574063D01*
X4213960Y3573230D01*
X4212720Y3573022D01*
G01X4238760Y3579689D02*
X4239380Y3580314D01*
X4239845Y3581355D01*
X4240155Y3582814D01*
X4239845Y3584064D01*
X4239225Y3584897D01*
X4238140Y3585522D01*
X4233955D01*
Y3573022D01*
X4239070D01*
X4240155Y3573855D01*
X4240775Y3575105D01*
X4241085Y3576564D01*
X4240775Y3578022D01*
X4239845Y3579272D01*
X4238760Y3579689D01*
X4233955D01*
G01X4253020Y3573022D02*
X4246820D01*
Y3585522D01*
X4253020D01*
G01X4250540Y3579480D02*
X4246820D01*
G01X4274410Y3573022D02*
X4274720Y3575730D01*
X4275185Y3578022D01*
X4275805Y3580105D01*
X4276580Y3582397D01*
X4277820Y3585522D01*
X4271620D01*
G01X4297815Y3577189D02*
X4301535D01*
G01X4299520Y3579897D02*
Y3574480D01*
G01X4309130Y3572605D02*
X4314710Y3585522D01*
G01X4322305Y3577189D02*
X4326335D01*
G01X4333310Y3574897D02*
X4334240Y3573855D01*
X4335325Y3573230D01*
X4336720Y3573022D01*
X4338115Y3573439D01*
X4339200Y3574272D01*
X4339975Y3575730D01*
X4340130Y3577397D01*
X4339820Y3579064D01*
X4339045Y3580105D01*
X4337960Y3580939D01*
X4336875Y3581147D01*
X4335790Y3580939D01*
X4334395Y3580105D01*
X4334860Y3585522D01*
X4339045D01*
G01X4357490Y3573022D02*
Y3585522D01*
X4361520Y3575105D01*
X4365550Y3585522D01*
Y3573022D01*
G01X4372060Y3585522D02*
X4375780D01*
G01X4373920D02*
Y3573022D01*
G01X4372060D02*
X4375780D01*
G01X4383220Y3585522D02*
Y3573022D01*
X4389420D01*
G01X4395465Y3574688D02*
X4396705Y3573647D01*
X4398100Y3573022D01*
X4399340D01*
X4400580Y3573647D01*
X4401510Y3574688D01*
X4401975Y3576147D01*
X4401665Y3577605D01*
X4400890Y3578855D01*
X4399495Y3579689D01*
X4397635Y3580105D01*
X4396550Y3580939D01*
X4396085Y3582397D01*
X4396395Y3583855D01*
X4397170Y3584897D01*
X4398255Y3585522D01*
X4399340D01*
X4400425Y3585105D01*
X4401355Y3584064D01*
G01X3640305Y3595939D02*
X3644335D01*
G01X3663090Y3591772D02*
Y3604272D01*
X3667120Y3593855D01*
X3671150Y3604272D01*
Y3591772D01*
G01X3676575D02*
Y3604272D01*
X3682465D01*
G01X3680295Y3598230D02*
X3676575D01*
G01X3692850Y3598022D02*
X3695950D01*
Y3594272D01*
X3695020Y3593022D01*
X3693935Y3592189D01*
X3692385Y3591772D01*
X3690835Y3592189D01*
X3689750Y3593022D01*
X3688820Y3594272D01*
X3688200Y3595730D01*
X3687890Y3597397D01*
Y3598855D01*
X3688200Y3600105D01*
X3688820Y3601564D01*
X3689750Y3602814D01*
X3690680Y3603647D01*
X3691920Y3604272D01*
X3693005D01*
X3694245Y3603855D01*
X3695175Y3603022D01*
G01X3699670Y3587605D02*
X3708970D01*
G01X3713465Y3593438D02*
X3714705Y3592397D01*
X3716100Y3591772D01*
X3717340D01*
X3718580Y3592397D01*
X3719510Y3593438D01*
X3719975Y3594897D01*
X3719665Y3596355D01*
X3718890Y3597605D01*
X3717495Y3598439D01*
X3715635Y3598855D01*
X3714550Y3599689D01*
X3714085Y3601147D01*
X3714395Y3602605D01*
X3715170Y3603647D01*
X3716255Y3604272D01*
X3717340D01*
X3718425Y3603855D01*
X3719355Y3602814D01*
G01X3729120Y3604272D02*
Y3591772D01*
G01X3725555Y3604272D02*
X3732685D01*
G01X3738110D02*
Y3595314D01*
X3738730Y3593438D01*
X3739970Y3592189D01*
X3741520Y3591772D01*
X3743070Y3592189D01*
X3744310Y3593438D01*
X3744930Y3595314D01*
Y3604272D01*
G01X3755160Y3598439D02*
X3755780Y3599064D01*
X3756245Y3600105D01*
X3756555Y3601564D01*
X3756245Y3602814D01*
X3755625Y3603647D01*
X3754540Y3604272D01*
X3750355D01*
Y3591772D01*
X3755470D01*
X3756555Y3592605D01*
X3757175Y3593855D01*
X3757485Y3595314D01*
X3757175Y3596772D01*
X3756245Y3598022D01*
X3755160Y3598439D01*
X3750355D01*
G01X3778720Y3591355D02*
X3778410Y3591564D01*
Y3591980D01*
X3778720Y3592189D01*
X3779030Y3591980D01*
Y3591564D01*
X3778720Y3591355D01*
G01Y3596980D02*
X3778410Y3597189D01*
Y3597605D01*
X3778720Y3597814D01*
X3779030Y3597605D01*
Y3597189D01*
X3778720Y3596980D01*
G01X3799490Y3591772D02*
Y3604272D01*
X3803520Y3593855D01*
X3807550Y3604272D01*
Y3591772D01*
G01X3812045D02*
X3815920Y3604272D01*
X3819795Y3591772D01*
G01X3818400Y3596147D02*
X3813440D01*
G01X3824755Y3591772D02*
Y3604272D01*
X3831885Y3591772D01*
Y3604272D01*
G01X3837310D02*
Y3595314D01*
X3837930Y3593438D01*
X3839170Y3592189D01*
X3840720Y3591772D01*
X3842270Y3592189D01*
X3843510Y3593438D01*
X3844130Y3595314D01*
Y3604272D01*
G01X3850175Y3591772D02*
Y3604272D01*
X3856065D01*
G01X3853895Y3598230D02*
X3850175D01*
G01X3861645Y3591772D02*
X3865520Y3604272D01*
X3869395Y3591772D01*
G01X3868000Y3596147D02*
X3863040D01*
G01X3881330Y3603230D02*
X3880400Y3603855D01*
X3879315Y3604272D01*
X3878075D01*
X3876680Y3603647D01*
X3875595Y3602605D01*
X3874820Y3601355D01*
X3874200Y3599272D01*
X3874045Y3597397D01*
X3874355Y3595522D01*
X3874820Y3594272D01*
X3875750Y3593022D01*
X3876835Y3592189D01*
X3877920Y3591772D01*
X3879005D01*
X3880090Y3592189D01*
X3881020Y3592813D01*
X3881795Y3593647D01*
G01X3890320Y3604272D02*
Y3591772D01*
G01X3886755Y3604272D02*
X3893885D01*
G01X3899310D02*
Y3595314D01*
X3899930Y3593438D01*
X3901170Y3592189D01*
X3902720Y3591772D01*
X3904270Y3592189D01*
X3905510Y3593438D01*
X3906130Y3595314D01*
Y3604272D01*
G01X3912020Y3591772D02*
Y3604272D01*
X3915895D01*
X3917135Y3603647D01*
X3917910Y3602814D01*
X3918220Y3601147D01*
X3917910Y3599480D01*
X3916980Y3598439D01*
X3915895Y3597814D01*
X3912020D01*
G01X3915895D02*
X3918220Y3591772D01*
G01X3925660Y3604272D02*
X3929380D01*
G01X3927520D02*
Y3591772D01*
G01X3925660D02*
X3929380D01*
G01X3936355D02*
Y3604272D01*
X3943485Y3591772D01*
Y3604272D01*
G01X3953250Y3598022D02*
X3956350D01*
Y3594272D01*
X3955420Y3593022D01*
X3954335Y3592189D01*
X3952785Y3591772D01*
X3951235Y3592189D01*
X3950150Y3593022D01*
X3949220Y3594272D01*
X3948600Y3595730D01*
X3948290Y3597397D01*
Y3598855D01*
X3948600Y3600105D01*
X3949220Y3601564D01*
X3950150Y3602814D01*
X3951080Y3603647D01*
X3952320Y3604272D01*
X3953405D01*
X3954645Y3603855D01*
X3955575Y3603022D01*
G01X3973865Y3593438D02*
X3975105Y3592397D01*
X3976500Y3591772D01*
X3977740D01*
X3978980Y3592397D01*
X3979910Y3593438D01*
X3980375Y3594897D01*
X3980065Y3596355D01*
X3979290Y3597605D01*
X3977895Y3598439D01*
X3976035Y3598855D01*
X3974950Y3599689D01*
X3974485Y3601147D01*
X3974795Y3602605D01*
X3975570Y3603647D01*
X3976655Y3604272D01*
X3977740D01*
X3978825Y3603855D01*
X3979755Y3602814D01*
G01X3989520Y3604272D02*
Y3591772D01*
G01X3985955Y3604272D02*
X3993085D01*
G01X3998510D02*
Y3595314D01*
X3999130Y3593438D01*
X4000370Y3592189D01*
X4001920Y3591772D01*
X4003470Y3592189D01*
X4004710Y3593438D01*
X4005330Y3595314D01*
Y3604272D01*
G01X4015560Y3598439D02*
X4016180Y3599064D01*
X4016645Y3600105D01*
X4016955Y3601564D01*
X4016645Y3602814D01*
X4016025Y3603647D01*
X4014940Y3604272D01*
X4010755D01*
Y3591772D01*
X4015870D01*
X4016955Y3592605D01*
X4017575Y3593855D01*
X4017885Y3595314D01*
X4017575Y3596772D01*
X4016645Y3598022D01*
X4015560Y3598439D01*
X4010755D01*
G01X4036020Y3604272D02*
Y3591772D01*
X4042220D01*
G01X4054620D02*
X4048420D01*
Y3604272D01*
X4054620D01*
G01X4052140Y3598230D02*
X4048420D01*
G01X4060355Y3591772D02*
Y3604272D01*
X4067485Y3591772D01*
Y3604272D01*
G01X4077250Y3598022D02*
X4080350D01*
Y3594272D01*
X4079420Y3593022D01*
X4078335Y3592189D01*
X4076785Y3591772D01*
X4075235Y3592189D01*
X4074150Y3593022D01*
X4073220Y3594272D01*
X4072600Y3595730D01*
X4072290Y3597397D01*
Y3598855D01*
X4072600Y3600105D01*
X4073220Y3601564D01*
X4074150Y3602814D01*
X4075080Y3603647D01*
X4076320Y3604272D01*
X4077405D01*
X4078645Y3603855D01*
X4079575Y3603022D01*
G01X4088720Y3604272D02*
Y3591772D01*
G01X4085155Y3604272D02*
X4092285D01*
G01X4097865Y3591772D02*
Y3604272D01*
G01X4104375D02*
Y3591772D01*
G01Y3598022D02*
X4097865D01*
G01X3800265Y3612188D02*
X3801505Y3611147D01*
X3802900Y3610522D01*
X3804140D01*
X3805380Y3611147D01*
X3806310Y3612188D01*
X3806775Y3613647D01*
X3806465Y3615105D01*
X3805690Y3616355D01*
X3804295Y3617189D01*
X3802435Y3617605D01*
X3801350Y3618439D01*
X3800885Y3619897D01*
X3801195Y3621355D01*
X3801970Y3622397D01*
X3803055Y3623022D01*
X3804140D01*
X3805225Y3622605D01*
X3806155Y3621564D01*
G01X3812510Y3623022D02*
Y3614064D01*
X3813130Y3612188D01*
X3814370Y3610939D01*
X3815920Y3610522D01*
X3817470Y3610939D01*
X3818710Y3612188D01*
X3819330Y3614064D01*
Y3623022D01*
G01X3825220Y3610522D02*
Y3623022D01*
X3829095D01*
X3830335Y3622397D01*
X3831110Y3621564D01*
X3831420Y3619897D01*
X3831110Y3618230D01*
X3830180Y3617189D01*
X3829095Y3616564D01*
X3825220D01*
G01X3829095D02*
X3831420Y3610522D01*
G01X3837775D02*
Y3623022D01*
X3843665D01*
G01X3841495Y3616980D02*
X3837775D01*
G01X3849245Y3610522D02*
X3853120Y3623022D01*
X3856995Y3610522D01*
G01X3855600Y3614897D02*
X3850640D01*
G01X3868930Y3621980D02*
X3868000Y3622605D01*
X3866915Y3623022D01*
X3865675D01*
X3864280Y3622397D01*
X3863195Y3621355D01*
X3862420Y3620105D01*
X3861800Y3618022D01*
X3861645Y3616147D01*
X3861955Y3614272D01*
X3862420Y3613022D01*
X3863350Y3611772D01*
X3864435Y3610939D01*
X3865520Y3610522D01*
X3866605D01*
X3867690Y3610939D01*
X3868620Y3611563D01*
X3869395Y3612397D01*
G01X3881020Y3610522D02*
X3874820D01*
Y3623022D01*
X3881020D01*
G01X3878540Y3616980D02*
X3874820D01*
G01X3902720Y3610522D02*
X3901480Y3610730D01*
X3900395Y3611563D01*
X3899465Y3612814D01*
X3898845Y3614272D01*
X3898535Y3615939D01*
Y3617605D01*
X3898845Y3619272D01*
X3899465Y3620730D01*
X3900395Y3621980D01*
X3901480Y3622814D01*
X3902720Y3623022D01*
X3903960Y3622814D01*
X3905045Y3621980D01*
X3905975Y3620730D01*
X3906595Y3619272D01*
X3906905Y3617605D01*
Y3615939D01*
X3906595Y3614272D01*
X3905975Y3612814D01*
X3905045Y3611563D01*
X3903960Y3610730D01*
X3902720Y3610522D01*
G01X3912175D02*
Y3623022D01*
X3918065D01*
G01X3915895Y3616980D02*
X3912175D01*
G01X3935890Y3610522D02*
Y3623022D01*
X3939920Y3612605D01*
X3943950Y3623022D01*
Y3610522D01*
G01X3948910Y3623022D02*
Y3614064D01*
X3949530Y3612188D01*
X3950770Y3610939D01*
X3952320Y3610522D01*
X3953870Y3610939D01*
X3955110Y3612188D01*
X3955730Y3614064D01*
Y3623022D01*
G01X3961465Y3612188D02*
X3962705Y3611147D01*
X3964100Y3610522D01*
X3965340D01*
X3966580Y3611147D01*
X3967510Y3612188D01*
X3967975Y3613647D01*
X3967665Y3615105D01*
X3966890Y3616355D01*
X3965495Y3617189D01*
X3963635Y3617605D01*
X3962550Y3618439D01*
X3962085Y3619897D01*
X3962395Y3621355D01*
X3963170Y3622397D01*
X3964255Y3623022D01*
X3965340D01*
X3966425Y3622605D01*
X3967355Y3621564D01*
G01X3977120Y3623022D02*
Y3610522D01*
G01X3973555Y3623022D02*
X3980685D01*
G01X3987505Y3614689D02*
X3991535D01*
G01X3998355Y3610522D02*
Y3623022D01*
X4005485Y3610522D01*
Y3623022D01*
G01X4014320Y3610522D02*
X4013080Y3610730D01*
X4011995Y3611563D01*
X4011065Y3612814D01*
X4010445Y3614272D01*
X4010135Y3615939D01*
Y3617605D01*
X4010445Y3619272D01*
X4011065Y3620730D01*
X4011995Y3621980D01*
X4013080Y3622814D01*
X4014320Y3623022D01*
X4015560Y3622814D01*
X4016645Y3621980D01*
X4017575Y3620730D01*
X4018195Y3619272D01*
X4018505Y3617605D01*
Y3615939D01*
X4018195Y3614272D01*
X4017575Y3612814D01*
X4016645Y3611563D01*
X4015560Y3610730D01*
X4014320Y3610522D01*
G01X4026720Y3623022D02*
Y3610522D01*
G01X4023155Y3623022D02*
X4030285D01*
G01X4037105Y3614689D02*
X4041135D01*
G01X4054930Y3621980D02*
X4054000Y3622605D01*
X4052915Y3623022D01*
X4051675D01*
X4050280Y3622397D01*
X4049195Y3621355D01*
X4048420Y3620105D01*
X4047800Y3618022D01*
X4047645Y3616147D01*
X4047955Y3614272D01*
X4048420Y3613022D01*
X4049350Y3611772D01*
X4050435Y3610939D01*
X4051520Y3610522D01*
X4052605D01*
X4053690Y3610939D01*
X4054620Y3611563D01*
X4055395Y3612397D01*
G01X4060510Y3623022D02*
Y3614064D01*
X4061130Y3612188D01*
X4062370Y3610939D01*
X4063920Y3610522D01*
X4065470Y3610939D01*
X4066710Y3612188D01*
X4067330Y3614064D01*
Y3623022D01*
G01X4076320D02*
Y3610522D01*
G01X4072755Y3623022D02*
X4079885D01*
G01X4086705Y3614689D02*
X4090735D01*
G01X4098020Y3623022D02*
Y3610522D01*
X4104220D01*
G01X4109645D02*
X4113520Y3623022D01*
X4117395Y3610522D01*
G01X4116000Y3614897D02*
X4111040D01*
G01X4125920Y3610522D02*
Y3616147D01*
X4122820Y3623022D01*
G01X4129020D02*
X4125920Y3616147D01*
G01X4141420Y3610522D02*
X4135220D01*
Y3623022D01*
X4141420D01*
G01X4138940Y3616980D02*
X4135220D01*
G01X4147620Y3610522D02*
Y3623022D01*
X4151495D01*
X4152735Y3622397D01*
X4153510Y3621564D01*
X4153820Y3619897D01*
X4153510Y3618230D01*
X4152580Y3617189D01*
X4151495Y3616564D01*
X4147620D01*
G01X4151495D02*
X4153820Y3610522D01*
G01X3640305Y3633439D02*
X3644335D01*
G01X3663090Y3629272D02*
Y3641772D01*
X3667120Y3631355D01*
X3671150Y3641772D01*
Y3629272D01*
G01X3675645D02*
X3679520Y3641772D01*
X3683395Y3629272D01*
G01X3682000Y3633647D02*
X3677040D01*
G01X3688665Y3629272D02*
X3695175Y3641772D01*
G01X3688665D02*
X3695175Y3629272D01*
G01X3699670Y3625105D02*
X3708970D01*
G01X3713310Y3629272D02*
Y3641772D01*
X3716410D01*
X3717650Y3641147D01*
X3718580Y3640314D01*
X3719355Y3639064D01*
X3719975Y3637605D01*
X3720130Y3635522D01*
X3719975Y3633439D01*
X3719355Y3631980D01*
X3718580Y3630730D01*
X3717650Y3629897D01*
X3716410Y3629272D01*
X3713310D01*
G01X3732220D02*
X3726020D01*
Y3641772D01*
X3732220D01*
G01X3729740Y3635730D02*
X3726020D01*
G01X3738420Y3629272D02*
Y3641772D01*
X3742140D01*
X3743380Y3641147D01*
X3744310Y3639689D01*
X3744620Y3638022D01*
X3744310Y3636355D01*
X3743535Y3635105D01*
X3742140Y3634480D01*
X3738420D01*
G01X3753920Y3641772D02*
Y3629272D01*
G01X3750355Y3641772D02*
X3757485D01*
G01X3763065Y3629272D02*
Y3641772D01*
G01X3769575D02*
Y3629272D01*
G01Y3635522D02*
X3763065D01*
G01X3778720Y3628855D02*
X3778410Y3629064D01*
Y3629480D01*
X3778720Y3629689D01*
X3779030Y3629480D01*
Y3629064D01*
X3778720Y3628855D01*
G01Y3634480D02*
X3778410Y3634689D01*
Y3635105D01*
X3778720Y3635314D01*
X3779030Y3635105D01*
Y3634689D01*
X3778720Y3634480D01*
G01X3800110Y3629272D02*
Y3641772D01*
X3803210D01*
X3804450Y3641147D01*
X3805380Y3640314D01*
X3806155Y3639064D01*
X3806775Y3637605D01*
X3806930Y3635522D01*
X3806775Y3633439D01*
X3806155Y3631980D01*
X3805380Y3630730D01*
X3804450Y3629897D01*
X3803210Y3629272D01*
X3800110D01*
G01X3819020D02*
X3812820D01*
Y3641772D01*
X3819020D01*
G01X3816540Y3635730D02*
X3812820D01*
G01X3825220Y3629272D02*
Y3641772D01*
X3828940D01*
X3830180Y3641147D01*
X3831110Y3639689D01*
X3831420Y3638022D01*
X3831110Y3636355D01*
X3830335Y3635105D01*
X3828940Y3634480D01*
X3825220D01*
G01X3840720Y3641772D02*
Y3629272D01*
G01X3837155Y3641772D02*
X3844285D01*
G01X3849865Y3629272D02*
Y3641772D01*
G01X3856375D02*
Y3629272D01*
G01Y3635522D02*
X3849865D01*
G01X3874975Y3629272D02*
Y3641772D01*
X3880865D01*
G01X3878695Y3635730D02*
X3874975D01*
G01X3887220Y3629272D02*
Y3641772D01*
X3891095D01*
X3892335Y3641147D01*
X3893110Y3640314D01*
X3893420Y3638647D01*
X3893110Y3636980D01*
X3892180Y3635939D01*
X3891095Y3635314D01*
X3887220D01*
G01X3891095D02*
X3893420Y3629272D01*
G01X3902720D02*
X3901480Y3629480D01*
X3900395Y3630313D01*
X3899465Y3631564D01*
X3898845Y3633022D01*
X3898535Y3634689D01*
Y3636355D01*
X3898845Y3638022D01*
X3899465Y3639480D01*
X3900395Y3640730D01*
X3901480Y3641564D01*
X3902720Y3641772D01*
X3903960Y3641564D01*
X3905045Y3640730D01*
X3905975Y3639480D01*
X3906595Y3638022D01*
X3906905Y3636355D01*
Y3634689D01*
X3906595Y3633022D01*
X3905975Y3631564D01*
X3905045Y3630313D01*
X3903960Y3629480D01*
X3902720Y3629272D01*
G01X3911090D02*
Y3641772D01*
X3915120Y3631355D01*
X3919150Y3641772D01*
Y3629272D01*
G01X3936665Y3630938D02*
X3937905Y3629897D01*
X3939300Y3629272D01*
X3940540D01*
X3941780Y3629897D01*
X3942710Y3630938D01*
X3943175Y3632397D01*
X3942865Y3633855D01*
X3942090Y3635105D01*
X3940695Y3635939D01*
X3938835Y3636355D01*
X3937750Y3637189D01*
X3937285Y3638647D01*
X3937595Y3640105D01*
X3938370Y3641147D01*
X3939455Y3641772D01*
X3940540D01*
X3941625Y3641355D01*
X3942555Y3640314D01*
G01X3952320Y3641772D02*
Y3629272D01*
G01X3948755Y3641772D02*
X3955885D01*
G01X3960845Y3629272D02*
X3964720Y3641772D01*
X3968595Y3629272D01*
G01X3967200Y3633647D02*
X3962240D01*
G01X3974020Y3629272D02*
Y3641772D01*
X3977895D01*
X3979135Y3641147D01*
X3979910Y3640314D01*
X3980220Y3638647D01*
X3979910Y3636980D01*
X3978980Y3635939D01*
X3977895Y3635314D01*
X3974020D01*
G01X3977895D02*
X3980220Y3629272D01*
G01X3989520Y3641772D02*
Y3629272D01*
G01X3985955Y3641772D02*
X3993085D01*
G01X4011220D02*
Y3629272D01*
X4017420D01*
G01X4022845D02*
X4026720Y3641772D01*
X4030595Y3629272D01*
G01X4029200Y3633647D02*
X4024240D01*
G01X4039120Y3629272D02*
Y3634897D01*
X4036020Y3641772D01*
G01X4042220D02*
X4039120Y3634897D01*
G01X4054620Y3629272D02*
X4048420D01*
Y3641772D01*
X4054620D01*
G01X4052140Y3635730D02*
X4048420D01*
G01X4060820Y3629272D02*
Y3641772D01*
X4064695D01*
X4065935Y3641147D01*
X4066710Y3640314D01*
X4067020Y3638647D01*
X4066710Y3636980D01*
X4065780Y3635939D01*
X4064695Y3635314D01*
X4060820D01*
G01X4064695D02*
X4067020Y3629272D01*
G01X4088720Y3641772D02*
Y3629272D01*
G01X4085155Y3641772D02*
X4092285D01*
G01X4101120Y3629272D02*
X4099880Y3629480D01*
X4098795Y3630313D01*
X4097865Y3631564D01*
X4097245Y3633022D01*
X4096935Y3634689D01*
Y3636355D01*
X4097245Y3638022D01*
X4097865Y3639480D01*
X4098795Y3640730D01*
X4099880Y3641564D01*
X4101120Y3641772D01*
X4102360Y3641564D01*
X4103445Y3640730D01*
X4104375Y3639480D01*
X4104995Y3638022D01*
X4105305Y3636355D01*
Y3634689D01*
X4104995Y3633022D01*
X4104375Y3631564D01*
X4103445Y3630313D01*
X4102360Y3629480D01*
X4101120Y3629272D01*
G01X4125920Y3641772D02*
Y3629272D01*
G01X4122355Y3641772D02*
X4129485D01*
G01X4135065Y3629272D02*
Y3641772D01*
G01X4141575D02*
Y3629272D01*
G01Y3635522D02*
X4135065D01*
G01X4153820Y3629272D02*
X4147620D01*
Y3641772D01*
X4153820D01*
G01X4151340Y3635730D02*
X4147620D01*
G01X3640305Y3652189D02*
X3644335D01*
G01X3663090Y3648022D02*
Y3660522D01*
X3667120Y3650105D01*
X3671150Y3660522D01*
Y3648022D01*
G01X3675955D02*
Y3660522D01*
X3683085Y3648022D01*
Y3660522D01*
G01X3695330Y3659480D02*
X3694400Y3660105D01*
X3693315Y3660522D01*
X3692075D01*
X3690680Y3659897D01*
X3689595Y3658855D01*
X3688820Y3657605D01*
X3688200Y3655522D01*
X3688045Y3653647D01*
X3688355Y3651772D01*
X3688820Y3650522D01*
X3689750Y3649272D01*
X3690835Y3648439D01*
X3691920Y3648022D01*
X3693005D01*
X3694090Y3648439D01*
X3695020Y3649063D01*
X3695795Y3649897D01*
G01X3699670Y3643855D02*
X3708970D01*
G01X3713620Y3660522D02*
Y3648022D01*
X3719820D01*
G01X3725245D02*
X3729120Y3660522D01*
X3732995Y3648022D01*
G01X3731600Y3652397D02*
X3726640D01*
G01X3741520Y3648022D02*
Y3653647D01*
X3738420Y3660522D01*
G01X3744620D02*
X3741520Y3653647D01*
G01X3757020Y3648022D02*
X3750820D01*
Y3660522D01*
X3757020D01*
G01X3754540Y3654480D02*
X3750820D01*
G01X3763220Y3648022D02*
Y3660522D01*
X3767095D01*
X3768335Y3659897D01*
X3769110Y3659064D01*
X3769420Y3657397D01*
X3769110Y3655730D01*
X3768180Y3654689D01*
X3767095Y3654064D01*
X3763220D01*
G01X3767095D02*
X3769420Y3648022D01*
G01X3778720Y3647605D02*
X3778410Y3647814D01*
Y3648230D01*
X3778720Y3648439D01*
X3779030Y3648230D01*
Y3647814D01*
X3778720Y3647605D01*
G01Y3653230D02*
X3778410Y3653439D01*
Y3653855D01*
X3778720Y3654064D01*
X3779030Y3653855D01*
Y3653439D01*
X3778720Y3653230D01*
G01X3799490Y3648022D02*
Y3660522D01*
X3803520Y3650105D01*
X3807550Y3660522D01*
Y3648022D01*
G01X3812510Y3660522D02*
Y3651564D01*
X3813130Y3649688D01*
X3814370Y3648439D01*
X3815920Y3648022D01*
X3817470Y3648439D01*
X3818710Y3649688D01*
X3819330Y3651564D01*
Y3660522D01*
G01X3825065Y3649688D02*
X3826305Y3648647D01*
X3827700Y3648022D01*
X3828940D01*
X3830180Y3648647D01*
X3831110Y3649688D01*
X3831575Y3651147D01*
X3831265Y3652605D01*
X3830490Y3653855D01*
X3829095Y3654689D01*
X3827235Y3655105D01*
X3826150Y3655939D01*
X3825685Y3657397D01*
X3825995Y3658855D01*
X3826770Y3659897D01*
X3827855Y3660522D01*
X3828940D01*
X3830025Y3660105D01*
X3830955Y3659064D01*
G01X3840720Y3660522D02*
Y3648022D01*
G01X3837155Y3660522D02*
X3844285D01*
G01X3851105Y3652189D02*
X3855135D01*
G01X3861955Y3648022D02*
Y3660522D01*
X3869085Y3648022D01*
Y3660522D01*
G01X3877920Y3648022D02*
X3876680Y3648230D01*
X3875595Y3649063D01*
X3874665Y3650314D01*
X3874045Y3651772D01*
X3873735Y3653439D01*
Y3655105D01*
X3874045Y3656772D01*
X3874665Y3658230D01*
X3875595Y3659480D01*
X3876680Y3660314D01*
X3877920Y3660522D01*
X3879160Y3660314D01*
X3880245Y3659480D01*
X3881175Y3658230D01*
X3881795Y3656772D01*
X3882105Y3655105D01*
Y3653439D01*
X3881795Y3651772D01*
X3881175Y3650314D01*
X3880245Y3649063D01*
X3879160Y3648230D01*
X3877920Y3648022D01*
G01X3890320Y3660522D02*
Y3648022D01*
G01X3886755Y3660522D02*
X3893885D01*
G01X3900705Y3652189D02*
X3904735D01*
G01X3918530Y3659480D02*
X3917600Y3660105D01*
X3916515Y3660522D01*
X3915275D01*
X3913880Y3659897D01*
X3912795Y3658855D01*
X3912020Y3657605D01*
X3911400Y3655522D01*
X3911245Y3653647D01*
X3911555Y3651772D01*
X3912020Y3650522D01*
X3912950Y3649272D01*
X3914035Y3648439D01*
X3915120Y3648022D01*
X3916205D01*
X3917290Y3648439D01*
X3918220Y3649063D01*
X3918995Y3649897D01*
G01X3924110Y3660522D02*
Y3651564D01*
X3924730Y3649688D01*
X3925970Y3648439D01*
X3927520Y3648022D01*
X3929070Y3648439D01*
X3930310Y3649688D01*
X3930930Y3651564D01*
Y3660522D01*
G01X3939920D02*
Y3648022D01*
G01X3936355Y3660522D02*
X3943485D01*
G01X3950305Y3652189D02*
X3954335D01*
G01X3961620Y3660522D02*
Y3648022D01*
X3967820D01*
G01X3973245D02*
X3977120Y3660522D01*
X3980995Y3648022D01*
G01X3979600Y3652397D02*
X3974640D01*
G01X3989520Y3648022D02*
Y3653647D01*
X3986420Y3660522D01*
G01X3992620D02*
X3989520Y3653647D01*
G01X4005020Y3648022D02*
X3998820D01*
Y3660522D01*
X4005020D01*
G01X4002540Y3654480D02*
X3998820D01*
G01X4011220Y3648022D02*
Y3660522D01*
X4015095D01*
X4016335Y3659897D01*
X4017110Y3659064D01*
X4017420Y3657397D01*
X4017110Y3655730D01*
X4016180Y3654689D01*
X4015095Y3654064D01*
X4011220D01*
G01X4015095D02*
X4017420Y3648022D01*
G01X3638755Y3666772D02*
Y3679272D01*
X3645885Y3666772D01*
Y3679272D01*
G01X3654720Y3666772D02*
X3653480Y3666980D01*
X3652395Y3667813D01*
X3651465Y3669064D01*
X3650845Y3670522D01*
X3650535Y3672189D01*
Y3673855D01*
X3650845Y3675522D01*
X3651465Y3676980D01*
X3652395Y3678230D01*
X3653480Y3679064D01*
X3654720Y3679272D01*
X3655960Y3679064D01*
X3657045Y3678230D01*
X3657975Y3676980D01*
X3658595Y3675522D01*
X3658905Y3673855D01*
Y3672189D01*
X3658595Y3670522D01*
X3657975Y3669064D01*
X3657045Y3667813D01*
X3655960Y3666980D01*
X3654720Y3666772D01*
G01X3667120Y3679272D02*
Y3666772D01*
G01X3663555Y3679272D02*
X3670685D01*
G01X3682620Y3666772D02*
X3676420D01*
Y3679272D01*
X3682620D01*
G01X3680140Y3673230D02*
X3676420D01*
G01X3688665Y3668438D02*
X3689905Y3667397D01*
X3691300Y3666772D01*
X3692540D01*
X3693780Y3667397D01*
X3694710Y3668438D01*
X3695175Y3669897D01*
X3694865Y3671355D01*
X3694090Y3672605D01*
X3692695Y3673439D01*
X3690835Y3673855D01*
X3689750Y3674689D01*
X3689285Y3676147D01*
X3689595Y3677605D01*
X3690370Y3678647D01*
X3691455Y3679272D01*
X3692540D01*
X3693625Y3678855D01*
X3694555Y3677814D01*
G01X3704320Y3666355D02*
X3704010Y3666564D01*
Y3666980D01*
X3704320Y3667189D01*
X3704630Y3666980D01*
Y3666564D01*
X3704320Y3666355D01*
G01Y3671980D02*
X3704010Y3672189D01*
Y3672605D01*
X3704320Y3672814D01*
X3704630Y3672605D01*
Y3672189D01*
X3704320Y3671980D01*
G01X3648675Y3716772D02*
Y3729272D01*
X3654565D01*
G01X3652395Y3723230D02*
X3648675D01*
G01X3662160Y3729272D02*
X3665880D01*
G01X3664020D02*
Y3716772D01*
G01X3662160D02*
X3665880D01*
G01X3677350Y3723022D02*
X3680450D01*
Y3719272D01*
X3679520Y3718022D01*
X3678435Y3717189D01*
X3676885Y3716772D01*
X3675335Y3717189D01*
X3674250Y3718022D01*
X3673320Y3719272D01*
X3672700Y3720730D01*
X3672390Y3722397D01*
Y3723855D01*
X3672700Y3725105D01*
X3673320Y3726564D01*
X3674250Y3727814D01*
X3675180Y3728647D01*
X3676420Y3729272D01*
X3677505D01*
X3678745Y3728855D01*
X3679675Y3728022D01*
G01X3685410Y3729272D02*
Y3720314D01*
X3686030Y3718438D01*
X3687270Y3717189D01*
X3688820Y3716772D01*
X3690370Y3717189D01*
X3691610Y3718438D01*
X3692230Y3720314D01*
Y3729272D01*
G01X3698120Y3716772D02*
Y3729272D01*
X3701995D01*
X3703235Y3728647D01*
X3704010Y3727814D01*
X3704320Y3726147D01*
X3704010Y3724480D01*
X3703080Y3723439D01*
X3701995Y3722814D01*
X3698120D01*
G01X3701995D02*
X3704320Y3716772D01*
G01X3716720D02*
X3710520D01*
Y3729272D01*
X3716720D01*
G01X3714240Y3723230D02*
X3710520D01*
G01X3755160Y3723439D02*
X3755780Y3724064D01*
X3756245Y3725105D01*
X3756555Y3726564D01*
X3756245Y3727814D01*
X3755625Y3728647D01*
X3754540Y3729272D01*
X3750355D01*
Y3716772D01*
X3755470D01*
X3756555Y3717605D01*
X3757175Y3718855D01*
X3757485Y3720314D01*
X3757175Y3721772D01*
X3756245Y3723022D01*
X3755160Y3723439D01*
X3750355D01*
G01X3762910Y3716772D02*
Y3729272D01*
X3766010D01*
X3767250Y3728647D01*
X3768180Y3727814D01*
X3768955Y3726564D01*
X3769575Y3725105D01*
X3769730Y3723022D01*
X3769575Y3720939D01*
X3768955Y3719480D01*
X3768180Y3718230D01*
X3767250Y3717397D01*
X3766010Y3716772D01*
X3762910D01*
G01X3774070Y3712605D02*
X3783370D01*
G01X3787865Y3718438D02*
X3789105Y3717397D01*
X3790500Y3716772D01*
X3791740D01*
X3792980Y3717397D01*
X3793910Y3718438D01*
X3794375Y3719897D01*
X3794065Y3721355D01*
X3793290Y3722605D01*
X3791895Y3723439D01*
X3790035Y3723855D01*
X3788950Y3724689D01*
X3788485Y3726147D01*
X3788795Y3727605D01*
X3789570Y3728647D01*
X3790655Y3729272D01*
X3791740D01*
X3792825Y3728855D01*
X3793755Y3727814D01*
G01X3801660Y3729272D02*
X3805380D01*
G01X3803520D02*
Y3716772D01*
G01X3801660D02*
X3805380D01*
G01X3812975Y3729272D02*
X3818865D01*
X3812975Y3716772D01*
X3818865D01*
G01X3831420D02*
X3825220D01*
Y3729272D01*
X3831420D01*
G01X3828940Y3723230D02*
X3825220D01*
G01X3772520Y3691772D02*
Y3704272D01*
X3770660Y3701772D01*
G01Y3691772D02*
X3774380D01*
G01X3784610D02*
X3784920Y3694480D01*
X3785385Y3696772D01*
X3786005Y3698855D01*
X3786780Y3701147D01*
X3788020Y3704272D01*
X3781820D01*
G01X3797320Y3691355D02*
X3797010Y3691564D01*
Y3691980D01*
X3797320Y3692189D01*
X3797630Y3691980D01*
Y3691564D01*
X3797320Y3691355D01*
G01X3809410Y3691772D02*
X3809720Y3694480D01*
X3810185Y3696772D01*
X3810805Y3698855D01*
X3811580Y3701147D01*
X3812820Y3704272D01*
X3806620D01*
G01X3816201Y1635504D02*
Y1643004D01*
X3818628Y1636754D01*
X3821055Y1643004D01*
Y1635504D01*
G01X3823795D02*
X3826128Y1643004D01*
X3828461Y1635504D01*
G01X3827621Y1638129D02*
X3824635D01*
G01X3831761Y1635504D02*
Y1643004D01*
X3834095D01*
X3834841Y1642629D01*
X3835308Y1642129D01*
X3835495Y1641129D01*
X3835308Y1640129D01*
X3834748Y1639504D01*
X3834095Y1639129D01*
X3831761D01*
G01X3834095D02*
X3835495Y1635504D01*
G01X3839075D02*
Y1643004D01*
G01X3842621D02*
X3839075Y1638379D01*
G01X3843181Y1635504D02*
X3840661Y1640504D01*
G01X3848628Y1635254D02*
X3848441Y1635379D01*
Y1635629D01*
X3848628Y1635754D01*
X3848815Y1635629D01*
Y1635379D01*
X3848628Y1635254D01*
G01Y1638629D02*
X3848441Y1638754D01*
Y1639004D01*
X3848628Y1639129D01*
X3848815Y1639004D01*
Y1638754D01*
X3848628Y1638629D01*
G01X3856128Y1643004D02*
Y1635504D01*
G01X3853981Y1643004D02*
X3858275D01*
G01X3862508D02*
X3864748D01*
G01X3863628D02*
Y1635504D01*
G01X3862508D02*
X3864748D01*
G01X3868981D02*
Y1643004D01*
X3873275Y1635504D01*
Y1643004D01*
G01X3884261D02*
Y1635504D01*
X3887995D01*
G01X3895495D02*
X3891761D01*
Y1643004D01*
X3895495D01*
G01X3894001Y1639379D02*
X3891761D01*
G01X3898795Y1635504D02*
X3901128Y1643004D01*
X3903461Y1635504D01*
G01X3902621Y1638129D02*
X3899635D01*
G01X3906575Y1635504D02*
Y1643004D01*
X3908441D01*
X3909188Y1642629D01*
X3909748Y1642129D01*
X3910215Y1641379D01*
X3910588Y1640504D01*
X3910681Y1639254D01*
X3910588Y1638004D01*
X3910215Y1637129D01*
X3909748Y1636379D01*
X3909188Y1635879D01*
X3908441Y1635504D01*
X3906575D01*
G01X3916128Y1635254D02*
X3915941Y1635379D01*
Y1635629D01*
X3916128Y1635754D01*
X3916315Y1635629D01*
Y1635379D01*
X3916128Y1635254D01*
G01Y1638629D02*
X3915941Y1638754D01*
Y1639004D01*
X3916128Y1639129D01*
X3916315Y1639004D01*
Y1638754D01*
X3916128Y1638629D01*
G01X3921761Y1635504D02*
Y1643004D01*
X3924095D01*
X3924841Y1642629D01*
X3925308Y1642129D01*
X3925495Y1641129D01*
X3925308Y1640129D01*
X3924748Y1639504D01*
X3924095Y1639129D01*
X3921761D01*
G01X3924095D02*
X3925495Y1635504D01*
G01X3932995D02*
X3929261D01*
Y1643004D01*
X3932995D01*
G01X3931501Y1639379D02*
X3929261D01*
G01X3940681Y1642379D02*
X3940121Y1642754D01*
X3939468Y1643004D01*
X3938721D01*
X3937881Y1642629D01*
X3937228Y1642004D01*
X3936761Y1641254D01*
X3936388Y1640004D01*
X3936295Y1638879D01*
X3936481Y1637754D01*
X3936761Y1637004D01*
X3937321Y1636254D01*
X3937975Y1635754D01*
X3938628Y1635504D01*
X3939281D01*
X3939935Y1635754D01*
X3940495Y1636129D01*
X3940961Y1636629D01*
G01X3946128Y1635504D02*
X3945381Y1635629D01*
X3944728Y1636129D01*
X3944168Y1636879D01*
X3943795Y1637754D01*
X3943608Y1638754D01*
Y1639754D01*
X3943795Y1640754D01*
X3944168Y1641629D01*
X3944728Y1642379D01*
X3945381Y1642879D01*
X3946128Y1643004D01*
X3946875Y1642879D01*
X3947528Y1642379D01*
X3948088Y1641629D01*
X3948461Y1640754D01*
X3948648Y1639754D01*
Y1638754D01*
X3948461Y1637754D01*
X3948088Y1636879D01*
X3947528Y1636129D01*
X3946875Y1635629D01*
X3946128Y1635504D01*
G01X3951201D02*
Y1643004D01*
X3953628Y1636754D01*
X3956055Y1643004D01*
Y1635504D01*
G01X3958701D02*
Y1643004D01*
X3961128Y1636754D01*
X3963555Y1643004D01*
Y1635504D01*
G01X3970495D02*
X3966761D01*
Y1643004D01*
X3970495D01*
G01X3969001Y1639379D02*
X3966761D01*
G01X3973981Y1635504D02*
Y1643004D01*
X3978275Y1635504D01*
Y1643004D01*
G01X3981575Y1635504D02*
Y1643004D01*
X3983441D01*
X3984188Y1642629D01*
X3984748Y1642129D01*
X3985215Y1641379D01*
X3985588Y1640504D01*
X3985681Y1639254D01*
X3985588Y1638004D01*
X3985215Y1637129D01*
X3984748Y1636379D01*
X3984188Y1635879D01*
X3983441Y1635504D01*
X3981575D01*
G01X3992995D02*
X3989261D01*
Y1643004D01*
X3992995D01*
G01X3991501Y1639379D02*
X3989261D01*
G01X3996575Y1635504D02*
Y1643004D01*
X3998441D01*
X3999188Y1642629D01*
X3999748Y1642129D01*
X4000215Y1641379D01*
X4000588Y1640504D01*
X4000681Y1639254D01*
X4000588Y1638004D01*
X4000215Y1637129D01*
X3999748Y1636379D01*
X3999188Y1635879D01*
X3998441Y1635504D01*
X3996575D01*
G01X4011575D02*
Y1643004D01*
X4013441D01*
X4014188Y1642629D01*
X4014748Y1642129D01*
X4015215Y1641379D01*
X4015588Y1640504D01*
X4015681Y1639254D01*
X4015588Y1638004D01*
X4015215Y1637129D01*
X4014748Y1636379D01*
X4014188Y1635879D01*
X4013441Y1635504D01*
X4011575D01*
G01X4019261D02*
Y1643004D01*
X4021595D01*
X4022341Y1642629D01*
X4022808Y1642129D01*
X4022995Y1641129D01*
X4022808Y1640129D01*
X4022248Y1639504D01*
X4021595Y1639129D01*
X4019261D01*
G01X4021595D02*
X4022995Y1635504D01*
G01X4027508Y1643004D02*
X4029748D01*
G01X4028628D02*
Y1635504D01*
G01X4027508D02*
X4029748D01*
G01X4034261Y1643004D02*
Y1635504D01*
X4037995D01*
G01X4041761Y1643004D02*
Y1635504D01*
X4045495D01*
G01X4056668Y1636504D02*
X4057415Y1635879D01*
X4058255Y1635504D01*
X4059001D01*
X4059748Y1635879D01*
X4060308Y1636504D01*
X4060588Y1637379D01*
X4060401Y1638254D01*
X4059935Y1639004D01*
X4059095Y1639504D01*
X4057975Y1639754D01*
X4057321Y1640254D01*
X4057041Y1641129D01*
X4057228Y1642004D01*
X4057695Y1642629D01*
X4058348Y1643004D01*
X4059001D01*
X4059655Y1642754D01*
X4060215Y1642129D01*
G01X4065008Y1643004D02*
X4067248D01*
G01X4066128D02*
Y1635504D01*
G01X4065008D02*
X4067248D01*
G01X4071855Y1643004D02*
X4075401D01*
X4071855Y1635504D01*
X4075401D01*
G01X4082995D02*
X4079261D01*
Y1643004D01*
X4082995D01*
G01X4081501Y1639379D02*
X4079261D01*
G01X4094355Y1635504D02*
Y1643004D01*
X4097901D01*
G01X4096595Y1639379D02*
X4094355D01*
G01X4103628Y1635504D02*
X4102881Y1635629D01*
X4102228Y1636129D01*
X4101668Y1636879D01*
X4101295Y1637754D01*
X4101108Y1638754D01*
Y1639754D01*
X4101295Y1640754D01*
X4101668Y1641629D01*
X4102228Y1642379D01*
X4102881Y1642879D01*
X4103628Y1643004D01*
X4104375Y1642879D01*
X4105028Y1642379D01*
X4105588Y1641629D01*
X4105961Y1640754D01*
X4106148Y1639754D01*
Y1638754D01*
X4105961Y1637754D01*
X4105588Y1636879D01*
X4105028Y1636129D01*
X4104375Y1635629D01*
X4103628Y1635504D01*
G01X4109261D02*
Y1643004D01*
X4111595D01*
X4112341Y1642629D01*
X4112808Y1642129D01*
X4112995Y1641129D01*
X4112808Y1640129D01*
X4112248Y1639504D01*
X4111595Y1639129D01*
X4109261D01*
G01X4111595D02*
X4112995Y1635504D01*
G01X4126128Y1643004D02*
X4125381Y1642754D01*
X4124821Y1642129D01*
X4124448Y1641379D01*
X4124168Y1640379D01*
X4124075Y1639254D01*
X4124168Y1638129D01*
X4124448Y1637129D01*
X4124821Y1636379D01*
X4125381Y1635754D01*
X4126128Y1635504D01*
X4126875Y1635754D01*
X4127435Y1636379D01*
X4127808Y1637129D01*
X4128088Y1638129D01*
X4128181Y1639254D01*
X4128088Y1640379D01*
X4127808Y1641379D01*
X4127435Y1642129D01*
X4126875Y1642754D01*
X4126128Y1643004D01*
G01X4133628Y1635254D02*
X4133441Y1635379D01*
Y1635629D01*
X4133628Y1635754D01*
X4133815Y1635629D01*
Y1635379D01*
X4133628Y1635254D01*
G01X4139075Y1636629D02*
X4139635Y1636004D01*
X4140288Y1635629D01*
X4141128Y1635504D01*
X4141968Y1635754D01*
X4142621Y1636254D01*
X4143088Y1637129D01*
X4143181Y1638129D01*
X4142995Y1639129D01*
X4142528Y1639754D01*
X4141875Y1640254D01*
X4141221Y1640379D01*
X4140568Y1640254D01*
X4139728Y1639754D01*
X4140008Y1643004D01*
X4142528D01*
G01X4146201Y1635504D02*
Y1643004D01*
X4148628Y1636754D01*
X4151055Y1643004D01*
Y1635504D01*
G01X4153701D02*
Y1643004D01*
X4156128Y1636754D01*
X4158555Y1643004D01*
Y1635504D01*
G01X4169355D02*
Y1643004D01*
X4172901D01*
G01X4171595Y1639379D02*
X4169355D01*
G01X4177508Y1643004D02*
X4179748D01*
G01X4178628D02*
Y1635504D01*
G01X4177508D02*
X4179748D01*
G01X4183981D02*
Y1643004D01*
X4188275Y1635504D01*
Y1643004D01*
G01X4192508D02*
X4194748D01*
G01X4193628D02*
Y1635504D01*
G01X4192508D02*
X4194748D01*
G01X4199168Y1636504D02*
X4199915Y1635879D01*
X4200755Y1635504D01*
X4201501D01*
X4202248Y1635879D01*
X4202808Y1636504D01*
X4203088Y1637379D01*
X4202901Y1638254D01*
X4202435Y1639004D01*
X4201595Y1639504D01*
X4200475Y1639754D01*
X4199821Y1640254D01*
X4199541Y1641129D01*
X4199728Y1642004D01*
X4200195Y1642629D01*
X4200848Y1643004D01*
X4201501D01*
X4202155Y1642754D01*
X4202715Y1642129D01*
G01X4206668Y1635504D02*
Y1643004D01*
G01X4210588D02*
Y1635504D01*
G01Y1639254D02*
X4206668D01*
G01X4217995Y1635504D02*
X4214261D01*
Y1643004D01*
X4217995D01*
G01X4216501Y1639379D02*
X4214261D01*
G01X4221575Y1635504D02*
Y1643004D01*
X4223441D01*
X4224188Y1642629D01*
X4224748Y1642129D01*
X4225215Y1641379D01*
X4225588Y1640504D01*
X4225681Y1639254D01*
X4225588Y1638004D01*
X4225215Y1637129D01*
X4224748Y1636379D01*
X4224188Y1635879D01*
X4223441Y1635504D01*
X4221575D01*
G01X4236761D02*
Y1643004D01*
X4239001D01*
X4239748Y1642629D01*
X4240308Y1641754D01*
X4240495Y1640754D01*
X4240308Y1639754D01*
X4239841Y1639004D01*
X4239001Y1638629D01*
X4236761D01*
G01X4246128Y1643004D02*
Y1635504D01*
G01X4243981Y1643004D02*
X4248275D01*
G01X4251668Y1635504D02*
Y1643004D01*
G01X4255588D02*
Y1635504D01*
G01Y1639254D02*
X4251668D01*
G01X4267508Y1643004D02*
X4269748D01*
G01X4268628D02*
Y1635504D01*
G01X4267508D02*
X4269748D01*
G01X4274168Y1636504D02*
X4274915Y1635879D01*
X4275755Y1635504D01*
X4276501D01*
X4277248Y1635879D01*
X4277808Y1636504D01*
X4278088Y1637379D01*
X4277901Y1638254D01*
X4277435Y1639004D01*
X4276595Y1639504D01*
X4275475Y1639754D01*
X4274821Y1640254D01*
X4274541Y1641129D01*
X4274728Y1642004D01*
X4275195Y1642629D01*
X4275848Y1643004D01*
X4276501D01*
X4277155Y1642754D01*
X4277715Y1642129D01*
G01X4291128Y1643004D02*
X4290381Y1642754D01*
X4289821Y1642129D01*
X4289448Y1641379D01*
X4289168Y1640379D01*
X4289075Y1639254D01*
X4289168Y1638129D01*
X4289448Y1637129D01*
X4289821Y1636379D01*
X4290381Y1635754D01*
X4291128Y1635504D01*
X4291875Y1635754D01*
X4292435Y1636379D01*
X4292808Y1637129D01*
X4293088Y1638129D01*
X4293181Y1639254D01*
X4293088Y1640379D01*
X4292808Y1641379D01*
X4292435Y1642129D01*
X4291875Y1642754D01*
X4291128Y1643004D01*
G01X4298628Y1635254D02*
X4298441Y1635379D01*
Y1635629D01*
X4298628Y1635754D01*
X4298815Y1635629D01*
Y1635379D01*
X4298628Y1635254D01*
G01X4304355Y1638629D02*
X4305008Y1639504D01*
X4305568Y1640004D01*
X4306315Y1640254D01*
X4306968Y1640004D01*
X4307435Y1639504D01*
X4307808Y1638754D01*
X4307901Y1637879D01*
X4307808Y1637129D01*
X4307435Y1636379D01*
X4306875Y1635754D01*
X4306221Y1635504D01*
X4305475Y1635754D01*
X4304821Y1636504D01*
X4304448Y1637629D01*
X4304355Y1638879D01*
X4304541Y1640504D01*
X4304821Y1641379D01*
X4305288Y1642254D01*
X4305941Y1642879D01*
X4306595Y1643004D01*
X4307248Y1642754D01*
X4307715Y1642129D01*
G01X4311201Y1635504D02*
Y1643004D01*
X4313628Y1636754D01*
X4316055Y1643004D01*
Y1635504D01*
G01X4318701D02*
Y1643004D01*
X4321128Y1636754D01*
X4323555Y1643004D01*
Y1635504D01*
G01X4333701D02*
Y1643004D01*
X4336128Y1636754D01*
X4338555Y1643004D01*
Y1635504D01*
G01X4345495D02*
X4341761D01*
Y1643004D01*
X4345495D01*
G01X4344001Y1639379D02*
X4341761D01*
G01X4351128Y1643004D02*
Y1635504D01*
G01X4348981Y1643004D02*
X4353275D01*
G01X4356761Y1635504D02*
Y1643004D01*
X4359095D01*
X4359841Y1642629D01*
X4360308Y1642129D01*
X4360495Y1641129D01*
X4360308Y1640129D01*
X4359748Y1639504D01*
X4359095Y1639129D01*
X4356761D01*
G01X4359095D02*
X4360495Y1635504D01*
G01X4365008Y1643004D02*
X4367248D01*
G01X4366128D02*
Y1635504D01*
G01X4365008D02*
X4367248D01*
G01X4375681Y1642379D02*
X4375121Y1642754D01*
X4374468Y1643004D01*
X4373721D01*
X4372881Y1642629D01*
X4372228Y1642004D01*
X4371761Y1641254D01*
X4371388Y1640004D01*
X4371295Y1638879D01*
X4371481Y1637754D01*
X4371761Y1637004D01*
X4372321Y1636254D01*
X4372975Y1635754D01*
X4373628Y1635504D01*
X4374281D01*
X4374935Y1635754D01*
X4375495Y1636129D01*
X4375961Y1636629D01*
G01X4386575Y1635504D02*
Y1643004D01*
X4388441D01*
X4389188Y1642629D01*
X4389748Y1642129D01*
X4390215Y1641379D01*
X4390588Y1640504D01*
X4390681Y1639254D01*
X4390588Y1638004D01*
X4390215Y1637129D01*
X4389748Y1636379D01*
X4389188Y1635879D01*
X4388441Y1635504D01*
X4386575D01*
G01X4394261D02*
Y1643004D01*
X4396595D01*
X4397341Y1642629D01*
X4397808Y1642129D01*
X4397995Y1641129D01*
X4397808Y1640129D01*
X4397248Y1639504D01*
X4396595Y1639129D01*
X4394261D01*
G01X4396595D02*
X4397995Y1635504D01*
G01X4402508Y1643004D02*
X4404748D01*
G01X4403628D02*
Y1635504D01*
G01X4402508D02*
X4404748D01*
G01X4409261Y1643004D02*
Y1635504D01*
X4412995D01*
G01X4416761Y1643004D02*
Y1635504D01*
X4420495D01*
G01X4425661Y1633004D02*
X4424728Y1634254D01*
X4424261Y1635504D01*
Y1640504D01*
X4424728Y1641754D01*
X4425661Y1643004D01*
G01X4433628D02*
X4432881Y1642754D01*
X4432321Y1642129D01*
X4431948Y1641379D01*
X4431668Y1640379D01*
X4431575Y1639254D01*
X4431668Y1638129D01*
X4431948Y1637129D01*
X4432321Y1636379D01*
X4432881Y1635754D01*
X4433628Y1635504D01*
X4434375Y1635754D01*
X4434935Y1636379D01*
X4435308Y1637129D01*
X4435588Y1638129D01*
X4435681Y1639254D01*
X4435588Y1640379D01*
X4435308Y1641379D01*
X4434935Y1642129D01*
X4434375Y1642754D01*
X4433628Y1643004D01*
G01X4441128Y1635254D02*
X4440941Y1635379D01*
Y1635629D01*
X4441128Y1635754D01*
X4441315Y1635629D01*
Y1635379D01*
X4441128Y1635254D01*
G01X4448628Y1643004D02*
X4447881Y1642754D01*
X4447321Y1642129D01*
X4446948Y1641379D01*
X4446668Y1640379D01*
X4446575Y1639254D01*
X4446668Y1638129D01*
X4446948Y1637129D01*
X4447321Y1636379D01*
X4447881Y1635754D01*
X4448628Y1635504D01*
X4449375Y1635754D01*
X4449935Y1636379D01*
X4450308Y1637129D01*
X4450588Y1638129D01*
X4450681Y1639254D01*
X4450588Y1640379D01*
X4450308Y1641379D01*
X4449935Y1642129D01*
X4449375Y1642754D01*
X4448628Y1643004D01*
G01X4454355Y1641754D02*
X4454915Y1642504D01*
X4455568Y1642879D01*
X4456315Y1643004D01*
X4457248Y1642754D01*
X4457901Y1642129D01*
X4458088Y1641379D01*
X4457995Y1640629D01*
X4457621Y1640004D01*
X4455755Y1638754D01*
X4454915Y1637879D01*
X4454355Y1636629D01*
X4454168Y1635504D01*
X4458088D01*
G01X4461575Y1637004D02*
X4462135Y1636129D01*
X4462881Y1635629D01*
X4463721Y1635504D01*
X4464468Y1635629D01*
X4465215Y1636254D01*
X4465681Y1637004D01*
X4465775Y1637754D01*
X4465588Y1638629D01*
X4464935Y1639254D01*
X4464281Y1639504D01*
X4463441D01*
G01X4464281D02*
X4464841Y1639879D01*
X4465308Y1640504D01*
X4465495Y1641254D01*
X4465308Y1642004D01*
X4464841Y1642629D01*
X4464001Y1643004D01*
X4463161Y1642879D01*
X4462321Y1642379D01*
G01X4469355Y1638629D02*
X4470008Y1639504D01*
X4470568Y1640004D01*
X4471315Y1640254D01*
X4471968Y1640004D01*
X4472435Y1639504D01*
X4472808Y1638754D01*
X4472901Y1637879D01*
X4472808Y1637129D01*
X4472435Y1636379D01*
X4471875Y1635754D01*
X4471221Y1635504D01*
X4470475Y1635754D01*
X4469821Y1636504D01*
X4469448Y1637629D01*
X4469355Y1638879D01*
X4469541Y1640504D01*
X4469821Y1641379D01*
X4470288Y1642254D01*
X4470941Y1642879D01*
X4471595Y1643004D01*
X4472248Y1642754D01*
X4472715Y1642129D01*
G01X4477788Y1641379D02*
X4478255Y1643004D01*
G01X4479468D02*
X4479001Y1641379D01*
G01X4486595Y1633004D02*
X4487528Y1634254D01*
X4487995Y1635504D01*
Y1640504D01*
X4487528Y1641754D01*
X4486595Y1643004D01*
G01X4493628Y1635254D02*
X4493441Y1635379D01*
Y1635629D01*
X4493628Y1635754D01*
X4493815Y1635629D01*
Y1635379D01*
X4493628Y1635254D01*
G01X3829359Y1401649D02*
Y1409149D01*
X3831693D01*
X3832439Y1408774D01*
X3832906Y1408274D01*
X3833093Y1407274D01*
X3832906Y1406274D01*
X3832346Y1405649D01*
X3831693Y1405274D01*
X3829359D01*
G01X3831693D02*
X3833093Y1401649D01*
G01X3840593D02*
X3836859D01*
Y1409149D01*
X3840593D01*
G01X3839099Y1405524D02*
X3836859D01*
G01X3848279Y1408524D02*
X3847719Y1408899D01*
X3847066Y1409149D01*
X3846319D01*
X3845479Y1408774D01*
X3844826Y1408149D01*
X3844359Y1407399D01*
X3843986Y1406149D01*
X3843893Y1405024D01*
X3844079Y1403899D01*
X3844359Y1403149D01*
X3844919Y1402399D01*
X3845573Y1401899D01*
X3846226Y1401649D01*
X3846879D01*
X3847533Y1401899D01*
X3848093Y1402274D01*
X3848559Y1402774D01*
G01X3853726Y1401649D02*
X3852979Y1401774D01*
X3852326Y1402274D01*
X3851766Y1403024D01*
X3851393Y1403899D01*
X3851206Y1404899D01*
Y1405899D01*
X3851393Y1406899D01*
X3851766Y1407774D01*
X3852326Y1408524D01*
X3852979Y1409024D01*
X3853726Y1409149D01*
X3854473Y1409024D01*
X3855126Y1408524D01*
X3855686Y1407774D01*
X3856059Y1406899D01*
X3856246Y1405899D01*
Y1404899D01*
X3856059Y1403899D01*
X3855686Y1403024D01*
X3855126Y1402274D01*
X3854473Y1401774D01*
X3853726Y1401649D01*
G01X3858799D02*
Y1409149D01*
X3861226Y1402899D01*
X3863653Y1409149D01*
Y1401649D01*
G01X3866299D02*
Y1409149D01*
X3868726Y1402899D01*
X3871153Y1409149D01*
Y1401649D01*
G01X3878093D02*
X3874359D01*
Y1409149D01*
X3878093D01*
G01X3876599Y1405524D02*
X3874359D01*
G01X3881579Y1401649D02*
Y1409149D01*
X3885873Y1401649D01*
Y1409149D01*
G01X3889173Y1401649D02*
Y1409149D01*
X3891039D01*
X3891786Y1408774D01*
X3892346Y1408274D01*
X3892813Y1407524D01*
X3893186Y1406649D01*
X3893279Y1405399D01*
X3893186Y1404149D01*
X3892813Y1403274D01*
X3892346Y1402524D01*
X3891786Y1402024D01*
X3891039Y1401649D01*
X3889173D01*
G01X3900593D02*
X3896859D01*
Y1409149D01*
X3900593D01*
G01X3899099Y1405524D02*
X3896859D01*
G01X3904173Y1401649D02*
Y1409149D01*
X3906039D01*
X3906786Y1408774D01*
X3907346Y1408274D01*
X3907813Y1407524D01*
X3908186Y1406649D01*
X3908279Y1405399D01*
X3908186Y1404149D01*
X3907813Y1403274D01*
X3907346Y1402524D01*
X3906786Y1402024D01*
X3906039Y1401649D01*
X3904173D01*
G01X3919173D02*
Y1409149D01*
X3921039D01*
X3921786Y1408774D01*
X3922346Y1408274D01*
X3922813Y1407524D01*
X3923186Y1406649D01*
X3923279Y1405399D01*
X3923186Y1404149D01*
X3922813Y1403274D01*
X3922346Y1402524D01*
X3921786Y1402024D01*
X3921039Y1401649D01*
X3919173D01*
G01X3926859D02*
Y1409149D01*
X3929193D01*
X3929939Y1408774D01*
X3930406Y1408274D01*
X3930593Y1407274D01*
X3930406Y1406274D01*
X3929846Y1405649D01*
X3929193Y1405274D01*
X3926859D01*
G01X3929193D02*
X3930593Y1401649D01*
G01X3935106Y1409149D02*
X3937346D01*
G01X3936226D02*
Y1401649D01*
G01X3935106D02*
X3937346D01*
G01X3941859Y1409149D02*
Y1401649D01*
X3945593D01*
G01X3949359Y1409149D02*
Y1401649D01*
X3953093D01*
G01X3964266Y1402649D02*
X3965013Y1402024D01*
X3965853Y1401649D01*
X3966599D01*
X3967346Y1402024D01*
X3967906Y1402649D01*
X3968186Y1403524D01*
X3967999Y1404399D01*
X3967533Y1405149D01*
X3966693Y1405649D01*
X3965573Y1405899D01*
X3964919Y1406399D01*
X3964639Y1407274D01*
X3964826Y1408149D01*
X3965293Y1408774D01*
X3965946Y1409149D01*
X3966599D01*
X3967253Y1408899D01*
X3967813Y1408274D01*
G01X3972606Y1409149D02*
X3974846D01*
G01X3973726D02*
Y1401649D01*
G01X3972606D02*
X3974846D01*
G01X3979453Y1409149D02*
X3982999D01*
X3979453Y1401649D01*
X3982999D01*
G01X3990593D02*
X3986859D01*
Y1409149D01*
X3990593D01*
G01X3989099Y1405524D02*
X3986859D01*
G01X4001953Y1401649D02*
Y1409149D01*
X4005499D01*
G01X4004193Y1405524D02*
X4001953D01*
G01X4011226Y1401649D02*
X4010479Y1401774D01*
X4009826Y1402274D01*
X4009266Y1403024D01*
X4008893Y1403899D01*
X4008706Y1404899D01*
Y1405899D01*
X4008893Y1406899D01*
X4009266Y1407774D01*
X4009826Y1408524D01*
X4010479Y1409024D01*
X4011226Y1409149D01*
X4011973Y1409024D01*
X4012626Y1408524D01*
X4013186Y1407774D01*
X4013559Y1406899D01*
X4013746Y1405899D01*
Y1404899D01*
X4013559Y1403899D01*
X4013186Y1403024D01*
X4012626Y1402274D01*
X4011973Y1401774D01*
X4011226Y1401649D01*
G01X4016859D02*
Y1409149D01*
X4019193D01*
X4019939Y1408774D01*
X4020406Y1408274D01*
X4020593Y1407274D01*
X4020406Y1406274D01*
X4019846Y1405649D01*
X4019193Y1405274D01*
X4016859D01*
G01X4019193D02*
X4020593Y1401649D01*
G01X4033726D02*
Y1409149D01*
X4032606Y1407649D01*
G01Y1401649D02*
X4034846D01*
G01X4041226Y1401399D02*
X4041039Y1401524D01*
Y1401774D01*
X4041226Y1401899D01*
X4041413Y1401774D01*
Y1401524D01*
X4041226Y1401399D01*
G01X4048726Y1409149D02*
X4047979Y1408899D01*
X4047419Y1408274D01*
X4047046Y1407524D01*
X4046766Y1406524D01*
X4046673Y1405399D01*
X4046766Y1404274D01*
X4047046Y1403274D01*
X4047419Y1402524D01*
X4047979Y1401899D01*
X4048726Y1401649D01*
X4049473Y1401899D01*
X4050033Y1402524D01*
X4050406Y1403274D01*
X4050686Y1404274D01*
X4050779Y1405399D01*
X4050686Y1406524D01*
X4050406Y1407524D01*
X4050033Y1408274D01*
X4049473Y1408899D01*
X4048726Y1409149D01*
G01X4054453Y1407899D02*
X4055013Y1408649D01*
X4055666Y1409024D01*
X4056413Y1409149D01*
X4057346Y1408899D01*
X4057999Y1408274D01*
X4058186Y1407524D01*
X4058093Y1406774D01*
X4057719Y1406149D01*
X4055853Y1404899D01*
X4055013Y1404024D01*
X4054453Y1402774D01*
X4054266Y1401649D01*
X4058186D01*
G01X4061299D02*
Y1409149D01*
X4063726Y1402899D01*
X4066153Y1409149D01*
Y1401649D01*
G01X4068799D02*
Y1409149D01*
X4071226Y1402899D01*
X4073653Y1409149D01*
Y1401649D01*
G01X4084453D02*
Y1409149D01*
X4087999D01*
G01X4086693Y1405524D02*
X4084453D01*
G01X4092606Y1409149D02*
X4094846D01*
G01X4093726D02*
Y1401649D01*
G01X4092606D02*
X4094846D01*
G01X4099079D02*
Y1409149D01*
X4103373Y1401649D01*
Y1409149D01*
G01X4107606D02*
X4109846D01*
G01X4108726D02*
Y1401649D01*
G01X4107606D02*
X4109846D01*
G01X4114266Y1402649D02*
X4115013Y1402024D01*
X4115853Y1401649D01*
X4116599D01*
X4117346Y1402024D01*
X4117906Y1402649D01*
X4118186Y1403524D01*
X4117999Y1404399D01*
X4117533Y1405149D01*
X4116693Y1405649D01*
X4115573Y1405899D01*
X4114919Y1406399D01*
X4114639Y1407274D01*
X4114826Y1408149D01*
X4115293Y1408774D01*
X4115946Y1409149D01*
X4116599D01*
X4117253Y1408899D01*
X4117813Y1408274D01*
G01X4121766Y1401649D02*
Y1409149D01*
G01X4125686D02*
Y1401649D01*
G01Y1405399D02*
X4121766D01*
G01X4133093Y1401649D02*
X4129359D01*
Y1409149D01*
X4133093D01*
G01X4131599Y1405524D02*
X4129359D01*
G01X4136673Y1401649D02*
Y1409149D01*
X4138539D01*
X4139286Y1408774D01*
X4139846Y1408274D01*
X4140313Y1407524D01*
X4140686Y1406649D01*
X4140779Y1405399D01*
X4140686Y1404149D01*
X4140313Y1403274D01*
X4139846Y1402524D01*
X4139286Y1402024D01*
X4138539Y1401649D01*
X4136673D01*
G01X4151859D02*
Y1409149D01*
X4154099D01*
X4154846Y1408774D01*
X4155406Y1407899D01*
X4155593Y1406899D01*
X4155406Y1405899D01*
X4154939Y1405149D01*
X4154099Y1404774D01*
X4151859D01*
G01X4161226Y1409149D02*
Y1401649D01*
G01X4159079Y1409149D02*
X4163373D01*
G01X4166766Y1401649D02*
Y1409149D01*
G01X4170686D02*
Y1401649D01*
G01Y1405399D02*
X4166766D01*
G01X4182606Y1409149D02*
X4184846D01*
G01X4183726D02*
Y1401649D01*
G01X4182606D02*
X4184846D01*
G01X4189266Y1402649D02*
X4190013Y1402024D01*
X4190853Y1401649D01*
X4191599D01*
X4192346Y1402024D01*
X4192906Y1402649D01*
X4193186Y1403524D01*
X4192999Y1404399D01*
X4192533Y1405149D01*
X4191693Y1405649D01*
X4190573Y1405899D01*
X4189919Y1406399D01*
X4189639Y1407274D01*
X4189826Y1408149D01*
X4190293Y1408774D01*
X4190946Y1409149D01*
X4191599D01*
X4192253Y1408899D01*
X4192813Y1408274D01*
G01X4206226Y1401649D02*
Y1409149D01*
X4205106Y1407649D01*
G01Y1401649D02*
X4207346D01*
G01X4213726Y1401399D02*
X4213539Y1401524D01*
Y1401774D01*
X4213726Y1401899D01*
X4213913Y1401774D01*
Y1401524D01*
X4213726Y1401399D01*
G01X4221226Y1401649D02*
Y1409149D01*
X4220106Y1407649D01*
G01Y1401649D02*
X4222346D01*
G01X4226673Y1402774D02*
X4227233Y1402149D01*
X4227886Y1401774D01*
X4228726Y1401649D01*
X4229566Y1401899D01*
X4230219Y1402399D01*
X4230686Y1403274D01*
X4230779Y1404274D01*
X4230593Y1405274D01*
X4230126Y1405899D01*
X4229473Y1406399D01*
X4228819Y1406524D01*
X4228166Y1406399D01*
X4227326Y1405899D01*
X4227606Y1409149D01*
X4230126D01*
G01X4235199Y1404149D02*
X4237439D01*
G01X4236226Y1405774D02*
Y1402524D01*
G01X4242046Y1401399D02*
X4245406Y1409149D01*
G01X4250013Y1404149D02*
X4252439D01*
G01X4258726Y1409149D02*
X4257979Y1408899D01*
X4257419Y1408274D01*
X4257046Y1407524D01*
X4256766Y1406524D01*
X4256673Y1405399D01*
X4256766Y1404274D01*
X4257046Y1403274D01*
X4257419Y1402524D01*
X4257979Y1401899D01*
X4258726Y1401649D01*
X4259473Y1401899D01*
X4260033Y1402524D01*
X4260406Y1403274D01*
X4260686Y1404274D01*
X4260779Y1405399D01*
X4260686Y1406524D01*
X4260406Y1407524D01*
X4260033Y1408274D01*
X4259473Y1408899D01*
X4258726Y1409149D01*
G01X4266226Y1401399D02*
X4266039Y1401524D01*
Y1401774D01*
X4266226Y1401899D01*
X4266413Y1401774D01*
Y1401524D01*
X4266226Y1401399D01*
G01X4273726Y1409149D02*
X4272979Y1408899D01*
X4272419Y1408274D01*
X4272046Y1407524D01*
X4271766Y1406524D01*
X4271673Y1405399D01*
X4271766Y1404274D01*
X4272046Y1403274D01*
X4272419Y1402524D01*
X4272979Y1401899D01*
X4273726Y1401649D01*
X4274473Y1401899D01*
X4275033Y1402524D01*
X4275406Y1403274D01*
X4275686Y1404274D01*
X4275779Y1405399D01*
X4275686Y1406524D01*
X4275406Y1407524D01*
X4275033Y1408274D01*
X4274473Y1408899D01*
X4273726Y1409149D01*
G01X4279453Y1407899D02*
X4280013Y1408649D01*
X4280666Y1409024D01*
X4281413Y1409149D01*
X4282346Y1408899D01*
X4282999Y1408274D01*
X4283186Y1407524D01*
X4283093Y1406774D01*
X4282719Y1406149D01*
X4280853Y1404899D01*
X4280013Y1404024D01*
X4279453Y1402774D01*
X4279266Y1401649D01*
X4283186D01*
G01X4286673Y1402774D02*
X4287233Y1402149D01*
X4287886Y1401774D01*
X4288726Y1401649D01*
X4289566Y1401899D01*
X4290219Y1402399D01*
X4290686Y1403274D01*
X4290779Y1404274D01*
X4290593Y1405274D01*
X4290126Y1405899D01*
X4289473Y1406399D01*
X4288819Y1406524D01*
X4288166Y1406399D01*
X4287326Y1405899D01*
X4287606Y1409149D01*
X4290126D01*
G01X4293799Y1401649D02*
Y1409149D01*
X4296226Y1402899D01*
X4298653Y1409149D01*
Y1401649D01*
G01X4301299D02*
Y1409149D01*
X4303726Y1402899D01*
X4306153Y1409149D01*
Y1401649D01*
G01X3820854Y1693662D02*
Y1701162D01*
X3825148Y1693662D01*
Y1701162D01*
G01X3830501Y1693662D02*
X3829754Y1693787D01*
X3829101Y1694287D01*
X3828541Y1695037D01*
X3828168Y1695912D01*
X3827981Y1696912D01*
Y1697912D01*
X3828168Y1698912D01*
X3828541Y1699787D01*
X3829101Y1700537D01*
X3829754Y1701037D01*
X3830501Y1701162D01*
X3831248Y1701037D01*
X3831901Y1700537D01*
X3832461Y1699787D01*
X3832834Y1698912D01*
X3833021Y1697912D01*
Y1696912D01*
X3832834Y1695912D01*
X3832461Y1695037D01*
X3831901Y1694287D01*
X3831248Y1693787D01*
X3830501Y1693662D01*
G01X3835854D02*
Y1701162D01*
X3840148Y1693662D01*
Y1701162D01*
G01X3844288Y1696162D02*
X3846714D01*
G01X3850574Y1693662D02*
Y1701162D01*
X3853001Y1694912D01*
X3855428Y1701162D01*
Y1693662D01*
G01X3858168D02*
X3860501Y1701162D01*
X3862834Y1693662D01*
G01X3861994Y1696287D02*
X3859008D01*
G01X3866134Y1693662D02*
Y1701162D01*
X3868468D01*
X3869214Y1700787D01*
X3869681Y1700287D01*
X3869868Y1699287D01*
X3869681Y1698287D01*
X3869121Y1697662D01*
X3868468Y1697287D01*
X3866134D01*
G01X3868468D02*
X3869868Y1693662D01*
G01X3873448D02*
Y1701162D01*
G01X3876994D02*
X3873448Y1696537D01*
G01X3877554Y1693662D02*
X3875034Y1698662D01*
G01X3883001Y1693412D02*
X3882814Y1693537D01*
Y1693787D01*
X3883001Y1693912D01*
X3883188Y1693787D01*
Y1693537D01*
X3883001Y1693412D01*
G01Y1696787D02*
X3882814Y1696912D01*
Y1697162D01*
X3883001Y1697287D01*
X3883188Y1697162D01*
Y1696912D01*
X3883001Y1696787D01*
G01X3890501Y1701162D02*
Y1693662D01*
G01X3888354Y1701162D02*
X3892648D01*
G01X3896881D02*
X3899121D01*
G01X3898001D02*
Y1693662D01*
G01X3896881D02*
X3899121D01*
G01X3903354D02*
Y1701162D01*
X3907648Y1693662D01*
Y1701162D01*
G01X3918634D02*
Y1693662D01*
X3922368D01*
G01X3929868D02*
X3926134D01*
Y1701162D01*
X3929868D01*
G01X3928374Y1697537D02*
X3926134D01*
G01X3933168Y1693662D02*
X3935501Y1701162D01*
X3937834Y1693662D01*
G01X3936994Y1696287D02*
X3934008D01*
G01X3940948Y1693662D02*
Y1701162D01*
X3942814D01*
X3943561Y1700787D01*
X3944121Y1700287D01*
X3944588Y1699537D01*
X3944961Y1698662D01*
X3945054Y1697412D01*
X3944961Y1696162D01*
X3944588Y1695287D01*
X3944121Y1694537D01*
X3943561Y1694037D01*
X3942814Y1693662D01*
X3940948D01*
G01X3950501Y1693412D02*
X3950314Y1693537D01*
Y1693787D01*
X3950501Y1693912D01*
X3950688Y1693787D01*
Y1693537D01*
X3950501Y1693412D01*
G01Y1696787D02*
X3950314Y1696912D01*
Y1697162D01*
X3950501Y1697287D01*
X3950688Y1697162D01*
Y1696912D01*
X3950501Y1696787D01*
G01X3956134Y1693662D02*
Y1701162D01*
X3958468D01*
X3959214Y1700787D01*
X3959681Y1700287D01*
X3959868Y1699287D01*
X3959681Y1698287D01*
X3959121Y1697662D01*
X3958468Y1697287D01*
X3956134D01*
G01X3958468D02*
X3959868Y1693662D01*
G01X3967368D02*
X3963634D01*
Y1701162D01*
X3967368D01*
G01X3965874Y1697537D02*
X3963634D01*
G01X3975054Y1700537D02*
X3974494Y1700912D01*
X3973841Y1701162D01*
X3973094D01*
X3972254Y1700787D01*
X3971601Y1700162D01*
X3971134Y1699412D01*
X3970761Y1698162D01*
X3970668Y1697037D01*
X3970854Y1695912D01*
X3971134Y1695162D01*
X3971694Y1694412D01*
X3972348Y1693912D01*
X3973001Y1693662D01*
X3973654D01*
X3974308Y1693912D01*
X3974868Y1694287D01*
X3975334Y1694787D01*
G01X3980501Y1693662D02*
X3979754Y1693787D01*
X3979101Y1694287D01*
X3978541Y1695037D01*
X3978168Y1695912D01*
X3977981Y1696912D01*
Y1697912D01*
X3978168Y1698912D01*
X3978541Y1699787D01*
X3979101Y1700537D01*
X3979754Y1701037D01*
X3980501Y1701162D01*
X3981248Y1701037D01*
X3981901Y1700537D01*
X3982461Y1699787D01*
X3982834Y1698912D01*
X3983021Y1697912D01*
Y1696912D01*
X3982834Y1695912D01*
X3982461Y1695037D01*
X3981901Y1694287D01*
X3981248Y1693787D01*
X3980501Y1693662D01*
G01X3985574D02*
Y1701162D01*
X3988001Y1694912D01*
X3990428Y1701162D01*
Y1693662D01*
G01X3993074D02*
Y1701162D01*
X3995501Y1694912D01*
X3997928Y1701162D01*
Y1693662D01*
G01X4004868D02*
X4001134D01*
Y1701162D01*
X4004868D01*
G01X4003374Y1697537D02*
X4001134D01*
G01X4008354Y1693662D02*
Y1701162D01*
X4012648Y1693662D01*
Y1701162D01*
G01X4015948Y1693662D02*
Y1701162D01*
X4017814D01*
X4018561Y1700787D01*
X4019121Y1700287D01*
X4019588Y1699537D01*
X4019961Y1698662D01*
X4020054Y1697412D01*
X4019961Y1696162D01*
X4019588Y1695287D01*
X4019121Y1694537D01*
X4018561Y1694037D01*
X4017814Y1693662D01*
X4015948D01*
G01X4027368D02*
X4023634D01*
Y1701162D01*
X4027368D01*
G01X4025874Y1697537D02*
X4023634D01*
G01X4030948Y1693662D02*
Y1701162D01*
X4032814D01*
X4033561Y1700787D01*
X4034121Y1700287D01*
X4034588Y1699537D01*
X4034961Y1698662D01*
X4035054Y1697412D01*
X4034961Y1696162D01*
X4034588Y1695287D01*
X4034121Y1694537D01*
X4033561Y1694037D01*
X4032814Y1693662D01*
X4030948D01*
G01X4045948D02*
Y1701162D01*
X4047814D01*
X4048561Y1700787D01*
X4049121Y1700287D01*
X4049588Y1699537D01*
X4049961Y1698662D01*
X4050054Y1697412D01*
X4049961Y1696162D01*
X4049588Y1695287D01*
X4049121Y1694537D01*
X4048561Y1694037D01*
X4047814Y1693662D01*
X4045948D01*
G01X4053634D02*
Y1701162D01*
X4055968D01*
X4056714Y1700787D01*
X4057181Y1700287D01*
X4057368Y1699287D01*
X4057181Y1698287D01*
X4056621Y1697662D01*
X4055968Y1697287D01*
X4053634D01*
G01X4055968D02*
X4057368Y1693662D01*
G01X4061881Y1701162D02*
X4064121D01*
G01X4063001D02*
Y1693662D01*
G01X4061881D02*
X4064121D01*
G01X4068634Y1701162D02*
Y1693662D01*
X4072368D01*
G01X4076134Y1701162D02*
Y1693662D01*
X4079868D01*
G01X4091041Y1694662D02*
X4091788Y1694037D01*
X4092628Y1693662D01*
X4093374D01*
X4094121Y1694037D01*
X4094681Y1694662D01*
X4094961Y1695537D01*
X4094774Y1696412D01*
X4094308Y1697162D01*
X4093468Y1697662D01*
X4092348Y1697912D01*
X4091694Y1698412D01*
X4091414Y1699287D01*
X4091601Y1700162D01*
X4092068Y1700787D01*
X4092721Y1701162D01*
X4093374D01*
X4094028Y1700912D01*
X4094588Y1700287D01*
G01X4099381Y1701162D02*
X4101621D01*
G01X4100501D02*
Y1693662D01*
G01X4099381D02*
X4101621D01*
G01X4106228Y1701162D02*
X4109774D01*
X4106228Y1693662D01*
X4109774D01*
G01X4117368D02*
X4113634D01*
Y1701162D01*
X4117368D01*
G01X4115874Y1697537D02*
X4113634D01*
G01X4128728Y1693662D02*
Y1701162D01*
X4132274D01*
G01X4130968Y1697537D02*
X4128728D01*
G01X4138001Y1693662D02*
X4137254Y1693787D01*
X4136601Y1694287D01*
X4136041Y1695037D01*
X4135668Y1695912D01*
X4135481Y1696912D01*
Y1697912D01*
X4135668Y1698912D01*
X4136041Y1699787D01*
X4136601Y1700537D01*
X4137254Y1701037D01*
X4138001Y1701162D01*
X4138748Y1701037D01*
X4139401Y1700537D01*
X4139961Y1699787D01*
X4140334Y1698912D01*
X4140521Y1697912D01*
Y1696912D01*
X4140334Y1695912D01*
X4139961Y1695037D01*
X4139401Y1694287D01*
X4138748Y1693787D01*
X4138001Y1693662D01*
G01X4143634D02*
Y1701162D01*
X4145968D01*
X4146714Y1700787D01*
X4147181Y1700287D01*
X4147368Y1699287D01*
X4147181Y1698287D01*
X4146621Y1697662D01*
X4145968Y1697287D01*
X4143634D01*
G01X4145968D02*
X4147368Y1693662D01*
G01X4160501Y1701162D02*
X4159754Y1700912D01*
X4159194Y1700287D01*
X4158821Y1699537D01*
X4158541Y1698537D01*
X4158448Y1697412D01*
X4158541Y1696287D01*
X4158821Y1695287D01*
X4159194Y1694537D01*
X4159754Y1693912D01*
X4160501Y1693662D01*
X4161248Y1693912D01*
X4161808Y1694537D01*
X4162181Y1695287D01*
X4162461Y1696287D01*
X4162554Y1697412D01*
X4162461Y1698537D01*
X4162181Y1699537D01*
X4161808Y1700287D01*
X4161248Y1700912D01*
X4160501Y1701162D01*
G01X4168001Y1693412D02*
X4167814Y1693537D01*
Y1693787D01*
X4168001Y1693912D01*
X4168188Y1693787D01*
Y1693537D01*
X4168001Y1693412D01*
G01X4173448Y1695162D02*
X4174008Y1694287D01*
X4174754Y1693787D01*
X4175594Y1693662D01*
X4176341Y1693787D01*
X4177088Y1694412D01*
X4177554Y1695162D01*
X4177648Y1695912D01*
X4177461Y1696787D01*
X4176808Y1697412D01*
X4176154Y1697662D01*
X4175314D01*
G01X4176154D02*
X4176714Y1698037D01*
X4177181Y1698662D01*
X4177368Y1699412D01*
X4177181Y1700162D01*
X4176714Y1700787D01*
X4175874Y1701162D01*
X4175034Y1701037D01*
X4174194Y1700537D01*
G01X4181228Y1696787D02*
X4181881Y1697662D01*
X4182441Y1698162D01*
X4183188Y1698412D01*
X4183841Y1698162D01*
X4184308Y1697662D01*
X4184681Y1696912D01*
X4184774Y1696037D01*
X4184681Y1695287D01*
X4184308Y1694537D01*
X4183748Y1693912D01*
X4183094Y1693662D01*
X4182348Y1693912D01*
X4181694Y1694662D01*
X4181321Y1695787D01*
X4181228Y1697037D01*
X4181414Y1698662D01*
X4181694Y1699537D01*
X4182161Y1700412D01*
X4182814Y1701037D01*
X4183468Y1701162D01*
X4184121Y1700912D01*
X4184588Y1700287D01*
G01X4188074Y1693662D02*
Y1701162D01*
X4190501Y1694912D01*
X4192928Y1701162D01*
Y1693662D01*
G01X4195574D02*
Y1701162D01*
X4198001Y1694912D01*
X4200428Y1701162D01*
Y1693662D01*
G01X4211228D02*
Y1701162D01*
X4214774D01*
G01X4213468Y1697537D02*
X4211228D01*
G01X4219381Y1701162D02*
X4221621D01*
G01X4220501D02*
Y1693662D01*
G01X4219381D02*
X4221621D01*
G01X4225854D02*
Y1701162D01*
X4230148Y1693662D01*
Y1701162D01*
G01X4234381D02*
X4236621D01*
G01X4235501D02*
Y1693662D01*
G01X4234381D02*
X4236621D01*
G01X4241041Y1694662D02*
X4241788Y1694037D01*
X4242628Y1693662D01*
X4243374D01*
X4244121Y1694037D01*
X4244681Y1694662D01*
X4244961Y1695537D01*
X4244774Y1696412D01*
X4244308Y1697162D01*
X4243468Y1697662D01*
X4242348Y1697912D01*
X4241694Y1698412D01*
X4241414Y1699287D01*
X4241601Y1700162D01*
X4242068Y1700787D01*
X4242721Y1701162D01*
X4243374D01*
X4244028Y1700912D01*
X4244588Y1700287D01*
G01X4248541Y1693662D02*
Y1701162D01*
G01X4252461D02*
Y1693662D01*
G01Y1697412D02*
X4248541D01*
G01X4259868Y1693662D02*
X4256134D01*
Y1701162D01*
X4259868D01*
G01X4258374Y1697537D02*
X4256134D01*
G01X4263448Y1693662D02*
Y1701162D01*
X4265314D01*
X4266061Y1700787D01*
X4266621Y1700287D01*
X4267088Y1699537D01*
X4267461Y1698662D01*
X4267554Y1697412D01*
X4267461Y1696162D01*
X4267088Y1695287D01*
X4266621Y1694537D01*
X4266061Y1694037D01*
X4265314Y1693662D01*
X4263448D01*
G01X4278634D02*
Y1701162D01*
X4280874D01*
X4281621Y1700787D01*
X4282181Y1699912D01*
X4282368Y1698912D01*
X4282181Y1697912D01*
X4281714Y1697162D01*
X4280874Y1696787D01*
X4278634D01*
G01X4288001Y1701162D02*
Y1693662D01*
G01X4285854Y1701162D02*
X4290148D01*
G01X4293541Y1693662D02*
Y1701162D01*
G01X4297461D02*
Y1693662D01*
G01Y1697412D02*
X4293541D01*
G01X4309381Y1701162D02*
X4311621D01*
G01X4310501D02*
Y1693662D01*
G01X4309381D02*
X4311621D01*
G01X4316041Y1694662D02*
X4316788Y1694037D01*
X4317628Y1693662D01*
X4318374D01*
X4319121Y1694037D01*
X4319681Y1694662D01*
X4319961Y1695537D01*
X4319774Y1696412D01*
X4319308Y1697162D01*
X4318468Y1697662D01*
X4317348Y1697912D01*
X4316694Y1698412D01*
X4316414Y1699287D01*
X4316601Y1700162D01*
X4317068Y1700787D01*
X4317721Y1701162D01*
X4318374D01*
X4319028Y1700912D01*
X4319588Y1700287D01*
G01X4333001Y1701162D02*
X4332254Y1700912D01*
X4331694Y1700287D01*
X4331321Y1699537D01*
X4331041Y1698537D01*
X4330948Y1697412D01*
X4331041Y1696287D01*
X4331321Y1695287D01*
X4331694Y1694537D01*
X4332254Y1693912D01*
X4333001Y1693662D01*
X4333748Y1693912D01*
X4334308Y1694537D01*
X4334681Y1695287D01*
X4334961Y1696287D01*
X4335054Y1697412D01*
X4334961Y1698537D01*
X4334681Y1699537D01*
X4334308Y1700287D01*
X4333748Y1700912D01*
X4333001Y1701162D01*
G01X4340501Y1693412D02*
X4340314Y1693537D01*
Y1693787D01*
X4340501Y1693912D01*
X4340688Y1693787D01*
Y1693537D01*
X4340501Y1693412D01*
G01X4349121Y1693662D02*
Y1701162D01*
X4345668Y1695787D01*
X4350334D01*
G01X4353448Y1694787D02*
X4354008Y1694162D01*
X4354661Y1693787D01*
X4355501Y1693662D01*
X4356341Y1693912D01*
X4356994Y1694412D01*
X4357461Y1695287D01*
X4357554Y1696287D01*
X4357368Y1697287D01*
X4356901Y1697912D01*
X4356248Y1698412D01*
X4355594Y1698537D01*
X4354941Y1698412D01*
X4354101Y1697912D01*
X4354381Y1701162D01*
X4356901D01*
G01X4360574Y1693662D02*
Y1701162D01*
X4363001Y1694912D01*
X4365428Y1701162D01*
Y1693662D01*
G01X4368074D02*
Y1701162D01*
X4370501Y1694912D01*
X4372928Y1701162D01*
Y1693662D01*
G01X4383074D02*
Y1701162D01*
X4385501Y1694912D01*
X4387928Y1701162D01*
Y1693662D01*
G01X4394868D02*
X4391134D01*
Y1701162D01*
X4394868D01*
G01X4393374Y1697537D02*
X4391134D01*
G01X4400501Y1701162D02*
Y1693662D01*
G01X4398354Y1701162D02*
X4402648D01*
G01X4406134Y1693662D02*
Y1701162D01*
X4408468D01*
X4409214Y1700787D01*
X4409681Y1700287D01*
X4409868Y1699287D01*
X4409681Y1698287D01*
X4409121Y1697662D01*
X4408468Y1697287D01*
X4406134D01*
G01X4408468D02*
X4409868Y1693662D01*
G01X4414381Y1701162D02*
X4416621D01*
G01X4415501D02*
Y1693662D01*
G01X4414381D02*
X4416621D01*
G01X4425054Y1700537D02*
X4424494Y1700912D01*
X4423841Y1701162D01*
X4423094D01*
X4422254Y1700787D01*
X4421601Y1700162D01*
X4421134Y1699412D01*
X4420761Y1698162D01*
X4420668Y1697037D01*
X4420854Y1695912D01*
X4421134Y1695162D01*
X4421694Y1694412D01*
X4422348Y1693912D01*
X4423001Y1693662D01*
X4423654D01*
X4424308Y1693912D01*
X4424868Y1694287D01*
X4425334Y1694787D01*
G01X4435948Y1693662D02*
Y1701162D01*
X4437814D01*
X4438561Y1700787D01*
X4439121Y1700287D01*
X4439588Y1699537D01*
X4439961Y1698662D01*
X4440054Y1697412D01*
X4439961Y1696162D01*
X4439588Y1695287D01*
X4439121Y1694537D01*
X4438561Y1694037D01*
X4437814Y1693662D01*
X4435948D01*
G01X4443634D02*
Y1701162D01*
X4445968D01*
X4446714Y1700787D01*
X4447181Y1700287D01*
X4447368Y1699287D01*
X4447181Y1698287D01*
X4446621Y1697662D01*
X4445968Y1697287D01*
X4443634D01*
G01X4445968D02*
X4447368Y1693662D01*
G01X4451881Y1701162D02*
X4454121D01*
G01X4453001D02*
Y1693662D01*
G01X4451881D02*
X4454121D01*
G01X4458634Y1701162D02*
Y1693662D01*
X4462368D01*
G01X4466134Y1701162D02*
Y1693662D01*
X4469868D01*
G01X4475034Y1691162D02*
X4474101Y1692412D01*
X4473634Y1693662D01*
Y1698662D01*
X4474101Y1699912D01*
X4475034Y1701162D01*
G01X4483001D02*
X4482254Y1700912D01*
X4481694Y1700287D01*
X4481321Y1699537D01*
X4481041Y1698537D01*
X4480948Y1697412D01*
X4481041Y1696287D01*
X4481321Y1695287D01*
X4481694Y1694537D01*
X4482254Y1693912D01*
X4483001Y1693662D01*
X4483748Y1693912D01*
X4484308Y1694537D01*
X4484681Y1695287D01*
X4484961Y1696287D01*
X4485054Y1697412D01*
X4484961Y1698537D01*
X4484681Y1699537D01*
X4484308Y1700287D01*
X4483748Y1700912D01*
X4483001Y1701162D01*
G01X4490501Y1693412D02*
X4490314Y1693537D01*
Y1693787D01*
X4490501Y1693912D01*
X4490688Y1693787D01*
Y1693537D01*
X4490501Y1693412D01*
G01X4498001Y1701162D02*
X4497254Y1700912D01*
X4496694Y1700287D01*
X4496321Y1699537D01*
X4496041Y1698537D01*
X4495948Y1697412D01*
X4496041Y1696287D01*
X4496321Y1695287D01*
X4496694Y1694537D01*
X4497254Y1693912D01*
X4498001Y1693662D01*
X4498748Y1693912D01*
X4499308Y1694537D01*
X4499681Y1695287D01*
X4499961Y1696287D01*
X4500054Y1697412D01*
X4499961Y1698537D01*
X4499681Y1699537D01*
X4499308Y1700287D01*
X4498748Y1700912D01*
X4498001Y1701162D01*
G01X4505501Y1693662D02*
Y1701162D01*
X4504381Y1699662D01*
G01Y1693662D02*
X4506621D01*
G01X4512814D02*
X4513001Y1695287D01*
X4513281Y1696662D01*
X4513654Y1697912D01*
X4514121Y1699287D01*
X4514868Y1701162D01*
X4511134D01*
G01X4520314Y1693662D02*
X4520501Y1695287D01*
X4520781Y1696662D01*
X4521154Y1697912D01*
X4521621Y1699287D01*
X4522368Y1701162D01*
X4518634D01*
G01X4527161Y1699537D02*
X4527628Y1701162D01*
G01X4528841D02*
X4528374Y1699537D01*
G01X4535968Y1691162D02*
X4536901Y1692412D01*
X4537368Y1693662D01*
Y1698662D01*
X4536901Y1699912D01*
X4535968Y1701162D01*
G01X4543001Y1693412D02*
X4542814Y1693537D01*
Y1693787D01*
X4543001Y1693912D01*
X4543188Y1693787D01*
Y1693537D01*
X4543001Y1693412D01*
G01X3849619Y1668882D02*
X3850366Y1668257D01*
X3851206Y1667882D01*
X3851952D01*
X3852699Y1668257D01*
X3853259Y1668882D01*
X3853539Y1669757D01*
X3853352Y1670632D01*
X3852886Y1671382D01*
X3852046Y1671882D01*
X3850926Y1672132D01*
X3850272Y1672632D01*
X3849992Y1673507D01*
X3850179Y1674382D01*
X3850646Y1675007D01*
X3851299Y1675382D01*
X3851952D01*
X3852606Y1675132D01*
X3853166Y1674507D01*
G01X3857959Y1675382D02*
X3860199D01*
G01X3859079D02*
Y1667882D01*
G01X3857959D02*
X3860199D01*
G01X3864712Y1675382D02*
Y1667882D01*
X3868446D01*
G01X3871746Y1675382D02*
X3874079Y1667882D01*
X3876412Y1675382D01*
G01X3883446Y1667882D02*
X3879712D01*
Y1675382D01*
X3883446D01*
G01X3881952Y1671757D02*
X3879712D01*
G01X3887212Y1667882D02*
Y1675382D01*
X3889546D01*
X3890292Y1675007D01*
X3890759Y1674507D01*
X3890946Y1673507D01*
X3890759Y1672507D01*
X3890199Y1671882D01*
X3889546Y1671507D01*
X3887212D01*
G01X3889546D02*
X3890946Y1667882D01*
G01X3896112Y1665382D02*
X3895179Y1666632D01*
X3894712Y1667882D01*
Y1672882D01*
X3895179Y1674132D01*
X3896112Y1675382D01*
G01X3902959D02*
X3905199D01*
G01X3904079D02*
Y1667882D01*
G01X3902959D02*
X3905199D01*
G01X3909152D02*
Y1675382D01*
X3911579Y1669132D01*
X3914006Y1675382D01*
Y1667882D01*
G01X3916652D02*
Y1675382D01*
X3919079Y1669132D01*
X3921506Y1675382D01*
Y1667882D01*
G01X3928446D02*
X3924712D01*
Y1675382D01*
X3928446D01*
G01X3926952Y1671757D02*
X3924712D01*
G01X3932212Y1667882D02*
Y1675382D01*
X3934546D01*
X3935292Y1675007D01*
X3935759Y1674507D01*
X3935946Y1673507D01*
X3935759Y1672507D01*
X3935199Y1671882D01*
X3934546Y1671507D01*
X3932212D01*
G01X3934546D02*
X3935946Y1667882D01*
G01X3939619Y1668882D02*
X3940366Y1668257D01*
X3941206Y1667882D01*
X3941952D01*
X3942699Y1668257D01*
X3943259Y1668882D01*
X3943539Y1669757D01*
X3943352Y1670632D01*
X3942886Y1671382D01*
X3942046Y1671882D01*
X3940926Y1672132D01*
X3940272Y1672632D01*
X3939992Y1673507D01*
X3940179Y1674382D01*
X3940646Y1675007D01*
X3941299Y1675382D01*
X3941952D01*
X3942606Y1675132D01*
X3943166Y1674507D01*
G01X3947959Y1675382D02*
X3950199D01*
G01X3949079D02*
Y1667882D01*
G01X3947959D02*
X3950199D01*
G01X3956579D02*
X3955832Y1668007D01*
X3955179Y1668507D01*
X3954619Y1669257D01*
X3954246Y1670132D01*
X3954059Y1671132D01*
Y1672132D01*
X3954246Y1673132D01*
X3954619Y1674007D01*
X3955179Y1674757D01*
X3955832Y1675257D01*
X3956579Y1675382D01*
X3957326Y1675257D01*
X3957979Y1674757D01*
X3958539Y1674007D01*
X3958912Y1673132D01*
X3959099Y1672132D01*
Y1671132D01*
X3958912Y1670132D01*
X3958539Y1669257D01*
X3957979Y1668507D01*
X3957326Y1668007D01*
X3956579Y1667882D01*
G01X3961932D02*
Y1675382D01*
X3966226Y1667882D01*
Y1675382D01*
G01X3972046Y1665382D02*
X3972979Y1666632D01*
X3973446Y1667882D01*
Y1672882D01*
X3972979Y1674132D01*
X3972046Y1675382D01*
G01X3979079Y1667632D02*
X3978892Y1667757D01*
Y1668007D01*
X3979079Y1668132D01*
X3979266Y1668007D01*
Y1667757D01*
X3979079Y1667632D01*
G01Y1671007D02*
X3978892Y1671132D01*
Y1671382D01*
X3979079Y1671507D01*
X3979266Y1671382D01*
Y1671132D01*
X3979079Y1671007D01*
G01X3984712Y1667882D02*
Y1675382D01*
X3987046D01*
X3987792Y1675007D01*
X3988259Y1674507D01*
X3988446Y1673507D01*
X3988259Y1672507D01*
X3987699Y1671882D01*
X3987046Y1671507D01*
X3984712D01*
G01X3987046D02*
X3988446Y1667882D01*
G01X3995946D02*
X3992212D01*
Y1675382D01*
X3995946D01*
G01X3994452Y1671757D02*
X3992212D01*
G01X4003632Y1674757D02*
X4003072Y1675132D01*
X4002419Y1675382D01*
X4001672D01*
X4000832Y1675007D01*
X4000179Y1674382D01*
X3999712Y1673632D01*
X3999339Y1672382D01*
X3999246Y1671257D01*
X3999432Y1670132D01*
X3999712Y1669382D01*
X4000272Y1668632D01*
X4000926Y1668132D01*
X4001579Y1667882D01*
X4002232D01*
X4002886Y1668132D01*
X4003446Y1668507D01*
X4003912Y1669007D01*
G01X4009079Y1667882D02*
X4008332Y1668007D01*
X4007679Y1668507D01*
X4007119Y1669257D01*
X4006746Y1670132D01*
X4006559Y1671132D01*
Y1672132D01*
X4006746Y1673132D01*
X4007119Y1674007D01*
X4007679Y1674757D01*
X4008332Y1675257D01*
X4009079Y1675382D01*
X4009826Y1675257D01*
X4010479Y1674757D01*
X4011039Y1674007D01*
X4011412Y1673132D01*
X4011599Y1672132D01*
Y1671132D01*
X4011412Y1670132D01*
X4011039Y1669257D01*
X4010479Y1668507D01*
X4009826Y1668007D01*
X4009079Y1667882D01*
G01X4014152D02*
Y1675382D01*
X4016579Y1669132D01*
X4019006Y1675382D01*
Y1667882D01*
G01X4021652D02*
Y1675382D01*
X4024079Y1669132D01*
X4026506Y1675382D01*
Y1667882D01*
G01X4033446D02*
X4029712D01*
Y1675382D01*
X4033446D01*
G01X4031952Y1671757D02*
X4029712D01*
G01X4036932Y1667882D02*
Y1675382D01*
X4041226Y1667882D01*
Y1675382D01*
G01X4044526Y1667882D02*
Y1675382D01*
X4046392D01*
X4047139Y1675007D01*
X4047699Y1674507D01*
X4048166Y1673757D01*
X4048539Y1672882D01*
X4048632Y1671632D01*
X4048539Y1670382D01*
X4048166Y1669507D01*
X4047699Y1668757D01*
X4047139Y1668257D01*
X4046392Y1667882D01*
X4044526D01*
G01X4055946D02*
X4052212D01*
Y1675382D01*
X4055946D01*
G01X4054452Y1671757D02*
X4052212D01*
G01X4059526Y1667882D02*
Y1675382D01*
X4061392D01*
X4062139Y1675007D01*
X4062699Y1674507D01*
X4063166Y1673757D01*
X4063539Y1672882D01*
X4063632Y1671632D01*
X4063539Y1670382D01*
X4063166Y1669507D01*
X4062699Y1668757D01*
X4062139Y1668257D01*
X4061392Y1667882D01*
X4059526D01*
G01X4074526D02*
Y1675382D01*
X4076392D01*
X4077139Y1675007D01*
X4077699Y1674507D01*
X4078166Y1673757D01*
X4078539Y1672882D01*
X4078632Y1671632D01*
X4078539Y1670382D01*
X4078166Y1669507D01*
X4077699Y1668757D01*
X4077139Y1668257D01*
X4076392Y1667882D01*
X4074526D01*
G01X4082212D02*
Y1675382D01*
X4084546D01*
X4085292Y1675007D01*
X4085759Y1674507D01*
X4085946Y1673507D01*
X4085759Y1672507D01*
X4085199Y1671882D01*
X4084546Y1671507D01*
X4082212D01*
G01X4084546D02*
X4085946Y1667882D01*
G01X4090459Y1675382D02*
X4092699D01*
G01X4091579D02*
Y1667882D01*
G01X4090459D02*
X4092699D01*
G01X4097212Y1675382D02*
Y1667882D01*
X4100946D01*
G01X4104712Y1675382D02*
Y1667882D01*
X4108446D01*
G01X4119619Y1668882D02*
X4120366Y1668257D01*
X4121206Y1667882D01*
X4121952D01*
X4122699Y1668257D01*
X4123259Y1668882D01*
X4123539Y1669757D01*
X4123352Y1670632D01*
X4122886Y1671382D01*
X4122046Y1671882D01*
X4120926Y1672132D01*
X4120272Y1672632D01*
X4119992Y1673507D01*
X4120179Y1674382D01*
X4120646Y1675007D01*
X4121299Y1675382D01*
X4121952D01*
X4122606Y1675132D01*
X4123166Y1674507D01*
G01X4127959Y1675382D02*
X4130199D01*
G01X4129079D02*
Y1667882D01*
G01X4127959D02*
X4130199D01*
G01X4134806Y1675382D02*
X4138352D01*
X4134806Y1667882D01*
X4138352D01*
G01X4145946D02*
X4142212D01*
Y1675382D01*
X4145946D01*
G01X4144452Y1671757D02*
X4142212D01*
G01X4157306Y1667882D02*
Y1675382D01*
X4160852D01*
G01X4159546Y1671757D02*
X4157306D01*
G01X4166579Y1667882D02*
X4165832Y1668007D01*
X4165179Y1668507D01*
X4164619Y1669257D01*
X4164246Y1670132D01*
X4164059Y1671132D01*
Y1672132D01*
X4164246Y1673132D01*
X4164619Y1674007D01*
X4165179Y1674757D01*
X4165832Y1675257D01*
X4166579Y1675382D01*
X4167326Y1675257D01*
X4167979Y1674757D01*
X4168539Y1674007D01*
X4168912Y1673132D01*
X4169099Y1672132D01*
Y1671132D01*
X4168912Y1670132D01*
X4168539Y1669257D01*
X4167979Y1668507D01*
X4167326Y1668007D01*
X4166579Y1667882D01*
G01X4172212D02*
Y1675382D01*
X4174546D01*
X4175292Y1675007D01*
X4175759Y1674507D01*
X4175946Y1673507D01*
X4175759Y1672507D01*
X4175199Y1671882D01*
X4174546Y1671507D01*
X4172212D01*
G01X4174546D02*
X4175946Y1667882D01*
G01X4189079Y1675382D02*
X4188332Y1675132D01*
X4187772Y1674507D01*
X4187399Y1673757D01*
X4187119Y1672757D01*
X4187026Y1671632D01*
X4187119Y1670507D01*
X4187399Y1669507D01*
X4187772Y1668757D01*
X4188332Y1668132D01*
X4189079Y1667882D01*
X4189826Y1668132D01*
X4190386Y1668757D01*
X4190759Y1669507D01*
X4191039Y1670507D01*
X4191132Y1671632D01*
X4191039Y1672757D01*
X4190759Y1673757D01*
X4190386Y1674507D01*
X4189826Y1675132D01*
X4189079Y1675382D01*
G01X4196579Y1667632D02*
X4196392Y1667757D01*
Y1668007D01*
X4196579Y1668132D01*
X4196766Y1668007D01*
Y1667757D01*
X4196579Y1667632D01*
G01X4202026Y1669382D02*
X4202586Y1668507D01*
X4203332Y1668007D01*
X4204172Y1667882D01*
X4204919Y1668007D01*
X4205666Y1668632D01*
X4206132Y1669382D01*
X4206226Y1670132D01*
X4206039Y1671007D01*
X4205386Y1671632D01*
X4204732Y1671882D01*
X4203892D01*
G01X4204732D02*
X4205292Y1672257D01*
X4205759Y1672882D01*
X4205946Y1673632D01*
X4205759Y1674382D01*
X4205292Y1675007D01*
X4204452Y1675382D01*
X4203612Y1675257D01*
X4202772Y1674757D01*
G01X4209806Y1671007D02*
X4210459Y1671882D01*
X4211019Y1672382D01*
X4211766Y1672632D01*
X4212419Y1672382D01*
X4212886Y1671882D01*
X4213259Y1671132D01*
X4213352Y1670257D01*
X4213259Y1669507D01*
X4212886Y1668757D01*
X4212326Y1668132D01*
X4211672Y1667882D01*
X4210926Y1668132D01*
X4210272Y1668882D01*
X4209899Y1670007D01*
X4209806Y1671257D01*
X4209992Y1672882D01*
X4210272Y1673757D01*
X4210739Y1674632D01*
X4211392Y1675257D01*
X4212046Y1675382D01*
X4212699Y1675132D01*
X4213166Y1674507D01*
G01X4216652Y1667882D02*
Y1675382D01*
X4219079Y1669132D01*
X4221506Y1675382D01*
Y1667882D01*
G01X4224152D02*
Y1675382D01*
X4226579Y1669132D01*
X4229006Y1675382D01*
Y1667882D01*
G01X4239806D02*
Y1675382D01*
X4243352D01*
G01X4242046Y1671757D02*
X4239806D01*
G01X4247959Y1675382D02*
X4250199D01*
G01X4249079D02*
Y1667882D01*
G01X4247959D02*
X4250199D01*
G01X4254432D02*
Y1675382D01*
X4258726Y1667882D01*
Y1675382D01*
G01X4262959D02*
X4265199D01*
G01X4264079D02*
Y1667882D01*
G01X4262959D02*
X4265199D01*
G01X4269619Y1668882D02*
X4270366Y1668257D01*
X4271206Y1667882D01*
X4271952D01*
X4272699Y1668257D01*
X4273259Y1668882D01*
X4273539Y1669757D01*
X4273352Y1670632D01*
X4272886Y1671382D01*
X4272046Y1671882D01*
X4270926Y1672132D01*
X4270272Y1672632D01*
X4269992Y1673507D01*
X4270179Y1674382D01*
X4270646Y1675007D01*
X4271299Y1675382D01*
X4271952D01*
X4272606Y1675132D01*
X4273166Y1674507D01*
G01X4277119Y1667882D02*
Y1675382D01*
G01X4281039D02*
Y1667882D01*
G01Y1671632D02*
X4277119D01*
G01X4288446Y1667882D02*
X4284712D01*
Y1675382D01*
X4288446D01*
G01X4286952Y1671757D02*
X4284712D01*
G01X4292026Y1667882D02*
Y1675382D01*
X4293892D01*
X4294639Y1675007D01*
X4295199Y1674507D01*
X4295666Y1673757D01*
X4296039Y1672882D01*
X4296132Y1671632D01*
X4296039Y1670382D01*
X4295666Y1669507D01*
X4295199Y1668757D01*
X4294639Y1668257D01*
X4293892Y1667882D01*
X4292026D01*
G01X4307212D02*
Y1675382D01*
X4309452D01*
X4310199Y1675007D01*
X4310759Y1674132D01*
X4310946Y1673132D01*
X4310759Y1672132D01*
X4310292Y1671382D01*
X4309452Y1671007D01*
X4307212D01*
G01X4316579Y1675382D02*
Y1667882D01*
G01X4314432Y1675382D02*
X4318726D01*
G01X4322119Y1667882D02*
Y1675382D01*
G01X4326039D02*
Y1667882D01*
G01Y1671632D02*
X4322119D01*
G01X4337959Y1675382D02*
X4340199D01*
G01X4339079D02*
Y1667882D01*
G01X4337959D02*
X4340199D01*
G01X4344619Y1668882D02*
X4345366Y1668257D01*
X4346206Y1667882D01*
X4346952D01*
X4347699Y1668257D01*
X4348259Y1668882D01*
X4348539Y1669757D01*
X4348352Y1670632D01*
X4347886Y1671382D01*
X4347046Y1671882D01*
X4345926Y1672132D01*
X4345272Y1672632D01*
X4344992Y1673507D01*
X4345179Y1674382D01*
X4345646Y1675007D01*
X4346299Y1675382D01*
X4346952D01*
X4347606Y1675132D01*
X4348166Y1674507D01*
G01X4361579Y1675382D02*
X4360832Y1675132D01*
X4360272Y1674507D01*
X4359899Y1673757D01*
X4359619Y1672757D01*
X4359526Y1671632D01*
X4359619Y1670507D01*
X4359899Y1669507D01*
X4360272Y1668757D01*
X4360832Y1668132D01*
X4361579Y1667882D01*
X4362326Y1668132D01*
X4362886Y1668757D01*
X4363259Y1669507D01*
X4363539Y1670507D01*
X4363632Y1671632D01*
X4363539Y1672757D01*
X4363259Y1673757D01*
X4362886Y1674507D01*
X4362326Y1675132D01*
X4361579Y1675382D01*
G01X4369079Y1667632D02*
X4368892Y1667757D01*
Y1668007D01*
X4369079Y1668132D01*
X4369266Y1668007D01*
Y1667757D01*
X4369079Y1667632D01*
G01X4377699Y1667882D02*
Y1675382D01*
X4374246Y1670007D01*
X4378912D01*
G01X4382026Y1669007D02*
X4382586Y1668382D01*
X4383239Y1668007D01*
X4384079Y1667882D01*
X4384919Y1668132D01*
X4385572Y1668632D01*
X4386039Y1669507D01*
X4386132Y1670507D01*
X4385946Y1671507D01*
X4385479Y1672132D01*
X4384826Y1672632D01*
X4384172Y1672757D01*
X4383519Y1672632D01*
X4382679Y1672132D01*
X4382959Y1675382D01*
X4385479D01*
G01X4389152Y1667882D02*
Y1675382D01*
X4391579Y1669132D01*
X4394006Y1675382D01*
Y1667882D01*
G01X4396652D02*
Y1675382D01*
X4399079Y1669132D01*
X4401506Y1675382D01*
Y1667882D01*
G01X4411652D02*
Y1675382D01*
X4414079Y1669132D01*
X4416506Y1675382D01*
Y1667882D01*
G01X4423446D02*
X4419712D01*
Y1675382D01*
X4423446D01*
G01X4421952Y1671757D02*
X4419712D01*
G01X4429079Y1675382D02*
Y1667882D01*
G01X4426932Y1675382D02*
X4431226D01*
G01X4434712Y1667882D02*
Y1675382D01*
X4437046D01*
X4437792Y1675007D01*
X4438259Y1674507D01*
X4438446Y1673507D01*
X4438259Y1672507D01*
X4437699Y1671882D01*
X4437046Y1671507D01*
X4434712D01*
G01X4437046D02*
X4438446Y1667882D01*
G01X4442959Y1675382D02*
X4445199D01*
G01X4444079D02*
Y1667882D01*
G01X4442959D02*
X4445199D01*
G01X4453632Y1674757D02*
X4453072Y1675132D01*
X4452419Y1675382D01*
X4451672D01*
X4450832Y1675007D01*
X4450179Y1674382D01*
X4449712Y1673632D01*
X4449339Y1672382D01*
X4449246Y1671257D01*
X4449432Y1670132D01*
X4449712Y1669382D01*
X4450272Y1668632D01*
X4450926Y1668132D01*
X4451579Y1667882D01*
X4452232D01*
X4452886Y1668132D01*
X4453446Y1668507D01*
X4453912Y1669007D01*
G01X4464526Y1667882D02*
Y1675382D01*
X4466392D01*
X4467139Y1675007D01*
X4467699Y1674507D01*
X4468166Y1673757D01*
X4468539Y1672882D01*
X4468632Y1671632D01*
X4468539Y1670382D01*
X4468166Y1669507D01*
X4467699Y1668757D01*
X4467139Y1668257D01*
X4466392Y1667882D01*
X4464526D01*
G01X4472212D02*
Y1675382D01*
X4474546D01*
X4475292Y1675007D01*
X4475759Y1674507D01*
X4475946Y1673507D01*
X4475759Y1672507D01*
X4475199Y1671882D01*
X4474546Y1671507D01*
X4472212D01*
G01X4474546D02*
X4475946Y1667882D01*
G01X4480459Y1675382D02*
X4482699D01*
G01X4481579D02*
Y1667882D01*
G01X4480459D02*
X4482699D01*
G01X4487212Y1675382D02*
Y1667882D01*
X4490946D01*
G01X4494712Y1675382D02*
Y1667882D01*
X4498446D01*
G01X4503612Y1665382D02*
X4502679Y1666632D01*
X4502212Y1667882D01*
Y1672882D01*
X4502679Y1674132D01*
X4503612Y1675382D01*
G01X4511579D02*
X4510832Y1675132D01*
X4510272Y1674507D01*
X4509899Y1673757D01*
X4509619Y1672757D01*
X4509526Y1671632D01*
X4509619Y1670507D01*
X4509899Y1669507D01*
X4510272Y1668757D01*
X4510832Y1668132D01*
X4511579Y1667882D01*
X4512326Y1668132D01*
X4512886Y1668757D01*
X4513259Y1669507D01*
X4513539Y1670507D01*
X4513632Y1671632D01*
X4513539Y1672757D01*
X4513259Y1673757D01*
X4512886Y1674507D01*
X4512326Y1675132D01*
X4511579Y1675382D01*
G01X4519079Y1667632D02*
X4518892Y1667757D01*
Y1668007D01*
X4519079Y1668132D01*
X4519266Y1668007D01*
Y1667757D01*
X4519079Y1667632D01*
G01X4526579Y1675382D02*
X4525832Y1675132D01*
X4525272Y1674507D01*
X4524899Y1673757D01*
X4524619Y1672757D01*
X4524526Y1671632D01*
X4524619Y1670507D01*
X4524899Y1669507D01*
X4525272Y1668757D01*
X4525832Y1668132D01*
X4526579Y1667882D01*
X4527326Y1668132D01*
X4527886Y1668757D01*
X4528259Y1669507D01*
X4528539Y1670507D01*
X4528632Y1671632D01*
X4528539Y1672757D01*
X4528259Y1673757D01*
X4527886Y1674507D01*
X4527326Y1675132D01*
X4526579Y1675382D01*
G01X4534079Y1667882D02*
Y1675382D01*
X4532959Y1673882D01*
G01Y1667882D02*
X4535199D01*
G01X4541392D02*
X4541579Y1669507D01*
X4541859Y1670882D01*
X4542232Y1672132D01*
X4542699Y1673507D01*
X4543446Y1675382D01*
X4539712D01*
G01X4548892Y1667882D02*
X4549079Y1669507D01*
X4549359Y1670882D01*
X4549732Y1672132D01*
X4550199Y1673507D01*
X4550946Y1675382D01*
X4547212D01*
G01X4555739Y1673757D02*
X4556206Y1675382D01*
G01X4557419D02*
X4556952Y1673757D01*
G01X4564546Y1665382D02*
X4565479Y1666632D01*
X4565946Y1667882D01*
Y1672882D01*
X4565479Y1674132D01*
X4564546Y1675382D01*
G01X4571579Y1667632D02*
X4571392Y1667757D01*
Y1668007D01*
X4571579Y1668132D01*
X4571766Y1668007D01*
Y1667757D01*
X4571579Y1667632D01*
G01X3854804Y1686737D02*
X3854244Y1687112D01*
X3853591Y1687362D01*
X3852844D01*
X3852004Y1686987D01*
X3851351Y1686362D01*
X3850884Y1685612D01*
X3850511Y1684362D01*
X3850418Y1683237D01*
X3850604Y1682112D01*
X3850884Y1681362D01*
X3851444Y1680612D01*
X3852098Y1680112D01*
X3852751Y1679862D01*
X3853404D01*
X3854058Y1680112D01*
X3854618Y1680487D01*
X3855084Y1680987D01*
G01X3860251Y1679862D02*
X3859504Y1679987D01*
X3858851Y1680487D01*
X3858291Y1681237D01*
X3857918Y1682112D01*
X3857731Y1683112D01*
Y1684112D01*
X3857918Y1685112D01*
X3858291Y1685987D01*
X3858851Y1686737D01*
X3859504Y1687237D01*
X3860251Y1687362D01*
X3860998Y1687237D01*
X3861651Y1686737D01*
X3862211Y1685987D01*
X3862584Y1685112D01*
X3862771Y1684112D01*
Y1683112D01*
X3862584Y1682112D01*
X3862211Y1681237D01*
X3861651Y1680487D01*
X3860998Y1679987D01*
X3860251Y1679862D01*
G01X3865884D02*
Y1687362D01*
X3868124D01*
X3868871Y1686987D01*
X3869431Y1686112D01*
X3869618Y1685112D01*
X3869431Y1684112D01*
X3868964Y1683362D01*
X3868124Y1682987D01*
X3865884D01*
G01X3873384Y1679862D02*
Y1687362D01*
X3875624D01*
X3876371Y1686987D01*
X3876931Y1686112D01*
X3877118Y1685112D01*
X3876931Y1684112D01*
X3876464Y1683362D01*
X3875624Y1682987D01*
X3873384D01*
G01X3884618Y1679862D02*
X3880884D01*
Y1687362D01*
X3884618D01*
G01X3883124Y1683737D02*
X3880884D01*
G01X3888384Y1679862D02*
Y1687362D01*
X3890718D01*
X3891464Y1686987D01*
X3891931Y1686487D01*
X3892118Y1685487D01*
X3891931Y1684487D01*
X3891371Y1683862D01*
X3890718Y1683487D01*
X3888384D01*
G01X3890718D02*
X3892118Y1679862D01*
G01X3905251D02*
X3904504Y1679987D01*
X3903851Y1680487D01*
X3903291Y1681237D01*
X3902918Y1682112D01*
X3902731Y1683112D01*
Y1684112D01*
X3902918Y1685112D01*
X3903291Y1685987D01*
X3903851Y1686737D01*
X3904504Y1687237D01*
X3905251Y1687362D01*
X3905998Y1687237D01*
X3906651Y1686737D01*
X3907211Y1685987D01*
X3907584Y1685112D01*
X3907771Y1684112D01*
Y1683112D01*
X3907584Y1682112D01*
X3907211Y1681237D01*
X3906651Y1680487D01*
X3905998Y1679987D01*
X3905251Y1679862D01*
G01X3910791Y1680862D02*
X3911538Y1680237D01*
X3912378Y1679862D01*
X3913124D01*
X3913871Y1680237D01*
X3914431Y1680862D01*
X3914711Y1681737D01*
X3914524Y1682612D01*
X3914058Y1683362D01*
X3913218Y1683862D01*
X3912098Y1684112D01*
X3911444Y1684612D01*
X3911164Y1685487D01*
X3911351Y1686362D01*
X3911818Y1686987D01*
X3912471Y1687362D01*
X3913124D01*
X3913778Y1687112D01*
X3914338Y1686487D01*
G01X3918384Y1679862D02*
Y1687362D01*
X3920624D01*
X3921371Y1686987D01*
X3921931Y1686112D01*
X3922118Y1685112D01*
X3921931Y1684112D01*
X3921464Y1683362D01*
X3920624Y1682987D01*
X3918384D01*
G01X3926071Y1679612D02*
X3929431Y1687362D01*
G01X3935251D02*
Y1679862D01*
G01X3933104Y1687362D02*
X3937398D01*
G01X3941631D02*
X3943871D01*
G01X3942751D02*
Y1679862D01*
G01X3941631D02*
X3943871D01*
G01X3948104D02*
Y1687362D01*
X3952398Y1679862D01*
Y1687362D01*
G01X3957284Y1677362D02*
X3956351Y1678612D01*
X3955884Y1679862D01*
Y1684862D01*
X3956351Y1686112D01*
X3957284Y1687362D01*
G01X3964131D02*
X3966371D01*
G01X3965251D02*
Y1679862D01*
G01X3964131D02*
X3966371D01*
G01X3970324D02*
Y1687362D01*
X3972751Y1681112D01*
X3975178Y1687362D01*
Y1679862D01*
G01X3977824D02*
Y1687362D01*
X3980251Y1681112D01*
X3982678Y1687362D01*
Y1679862D01*
G01X3989618D02*
X3985884D01*
Y1687362D01*
X3989618D01*
G01X3988124Y1683737D02*
X3985884D01*
G01X3993384Y1679862D02*
Y1687362D01*
X3995718D01*
X3996464Y1686987D01*
X3996931Y1686487D01*
X3997118Y1685487D01*
X3996931Y1684487D01*
X3996371Y1683862D01*
X3995718Y1683487D01*
X3993384D01*
G01X3995718D02*
X3997118Y1679862D01*
G01X4000791Y1680862D02*
X4001538Y1680237D01*
X4002378Y1679862D01*
X4003124D01*
X4003871Y1680237D01*
X4004431Y1680862D01*
X4004711Y1681737D01*
X4004524Y1682612D01*
X4004058Y1683362D01*
X4003218Y1683862D01*
X4002098Y1684112D01*
X4001444Y1684612D01*
X4001164Y1685487D01*
X4001351Y1686362D01*
X4001818Y1686987D01*
X4002471Y1687362D01*
X4003124D01*
X4003778Y1687112D01*
X4004338Y1686487D01*
G01X4009131Y1687362D02*
X4011371D01*
G01X4010251D02*
Y1679862D01*
G01X4009131D02*
X4011371D01*
G01X4017751D02*
X4017004Y1679987D01*
X4016351Y1680487D01*
X4015791Y1681237D01*
X4015418Y1682112D01*
X4015231Y1683112D01*
Y1684112D01*
X4015418Y1685112D01*
X4015791Y1685987D01*
X4016351Y1686737D01*
X4017004Y1687237D01*
X4017751Y1687362D01*
X4018498Y1687237D01*
X4019151Y1686737D01*
X4019711Y1685987D01*
X4020084Y1685112D01*
X4020271Y1684112D01*
Y1683112D01*
X4020084Y1682112D01*
X4019711Y1681237D01*
X4019151Y1680487D01*
X4018498Y1679987D01*
X4017751Y1679862D01*
G01X4023104D02*
Y1687362D01*
X4027398Y1679862D01*
Y1687362D01*
G01X4033218Y1677362D02*
X4034151Y1678612D01*
X4034618Y1679862D01*
Y1684862D01*
X4034151Y1686112D01*
X4033218Y1687362D01*
G01X4040251Y1679612D02*
X4040064Y1679737D01*
Y1679987D01*
X4040251Y1680112D01*
X4040438Y1679987D01*
Y1679737D01*
X4040251Y1679612D01*
G01Y1682987D02*
X4040064Y1683112D01*
Y1683362D01*
X4040251Y1683487D01*
X4040438Y1683362D01*
Y1683112D01*
X4040251Y1682987D01*
G01X4045884Y1679862D02*
Y1687362D01*
X4048218D01*
X4048964Y1686987D01*
X4049431Y1686487D01*
X4049618Y1685487D01*
X4049431Y1684487D01*
X4048871Y1683862D01*
X4048218Y1683487D01*
X4045884D01*
G01X4048218D02*
X4049618Y1679862D01*
G01X4057118D02*
X4053384D01*
Y1687362D01*
X4057118D01*
G01X4055624Y1683737D02*
X4053384D01*
G01X4064804Y1686737D02*
X4064244Y1687112D01*
X4063591Y1687362D01*
X4062844D01*
X4062004Y1686987D01*
X4061351Y1686362D01*
X4060884Y1685612D01*
X4060511Y1684362D01*
X4060418Y1683237D01*
X4060604Y1682112D01*
X4060884Y1681362D01*
X4061444Y1680612D01*
X4062098Y1680112D01*
X4062751Y1679862D01*
X4063404D01*
X4064058Y1680112D01*
X4064618Y1680487D01*
X4065084Y1680987D01*
G01X4070251Y1679862D02*
X4069504Y1679987D01*
X4068851Y1680487D01*
X4068291Y1681237D01*
X4067918Y1682112D01*
X4067731Y1683112D01*
Y1684112D01*
X4067918Y1685112D01*
X4068291Y1685987D01*
X4068851Y1686737D01*
X4069504Y1687237D01*
X4070251Y1687362D01*
X4070998Y1687237D01*
X4071651Y1686737D01*
X4072211Y1685987D01*
X4072584Y1685112D01*
X4072771Y1684112D01*
Y1683112D01*
X4072584Y1682112D01*
X4072211Y1681237D01*
X4071651Y1680487D01*
X4070998Y1679987D01*
X4070251Y1679862D01*
G01X4075324D02*
Y1687362D01*
X4077751Y1681112D01*
X4080178Y1687362D01*
Y1679862D01*
G01X4082824D02*
Y1687362D01*
X4085251Y1681112D01*
X4087678Y1687362D01*
Y1679862D01*
G01X4094618D02*
X4090884D01*
Y1687362D01*
X4094618D01*
G01X4093124Y1683737D02*
X4090884D01*
G01X4098104Y1679862D02*
Y1687362D01*
X4102398Y1679862D01*
Y1687362D01*
G01X4105698Y1679862D02*
Y1687362D01*
X4107564D01*
X4108311Y1686987D01*
X4108871Y1686487D01*
X4109338Y1685737D01*
X4109711Y1684862D01*
X4109804Y1683612D01*
X4109711Y1682362D01*
X4109338Y1681487D01*
X4108871Y1680737D01*
X4108311Y1680237D01*
X4107564Y1679862D01*
X4105698D01*
G01X4117118D02*
X4113384D01*
Y1687362D01*
X4117118D01*
G01X4115624Y1683737D02*
X4113384D01*
G01X4120698Y1679862D02*
Y1687362D01*
X4122564D01*
X4123311Y1686987D01*
X4123871Y1686487D01*
X4124338Y1685737D01*
X4124711Y1684862D01*
X4124804Y1683612D01*
X4124711Y1682362D01*
X4124338Y1681487D01*
X4123871Y1680737D01*
X4123311Y1680237D01*
X4122564Y1679862D01*
X4120698D01*
G01X4135698D02*
Y1687362D01*
X4137564D01*
X4138311Y1686987D01*
X4138871Y1686487D01*
X4139338Y1685737D01*
X4139711Y1684862D01*
X4139804Y1683612D01*
X4139711Y1682362D01*
X4139338Y1681487D01*
X4138871Y1680737D01*
X4138311Y1680237D01*
X4137564Y1679862D01*
X4135698D01*
G01X4143384D02*
Y1687362D01*
X4145718D01*
X4146464Y1686987D01*
X4146931Y1686487D01*
X4147118Y1685487D01*
X4146931Y1684487D01*
X4146371Y1683862D01*
X4145718Y1683487D01*
X4143384D01*
G01X4145718D02*
X4147118Y1679862D01*
G01X4151631Y1687362D02*
X4153871D01*
G01X4152751D02*
Y1679862D01*
G01X4151631D02*
X4153871D01*
G01X4158384Y1687362D02*
Y1679862D01*
X4162118D01*
G01X4165884Y1687362D02*
Y1679862D01*
X4169618D01*
G01X4180791Y1680862D02*
X4181538Y1680237D01*
X4182378Y1679862D01*
X4183124D01*
X4183871Y1680237D01*
X4184431Y1680862D01*
X4184711Y1681737D01*
X4184524Y1682612D01*
X4184058Y1683362D01*
X4183218Y1683862D01*
X4182098Y1684112D01*
X4181444Y1684612D01*
X4181164Y1685487D01*
X4181351Y1686362D01*
X4181818Y1686987D01*
X4182471Y1687362D01*
X4183124D01*
X4183778Y1687112D01*
X4184338Y1686487D01*
G01X4189131Y1687362D02*
X4191371D01*
G01X4190251D02*
Y1679862D01*
G01X4189131D02*
X4191371D01*
G01X4195978Y1687362D02*
X4199524D01*
X4195978Y1679862D01*
X4199524D01*
G01X4207118D02*
X4203384D01*
Y1687362D01*
X4207118D01*
G01X4205624Y1683737D02*
X4203384D01*
G01X4218478Y1679862D02*
Y1687362D01*
X4222024D01*
G01X4220718Y1683737D02*
X4218478D01*
G01X4227751Y1679862D02*
X4227004Y1679987D01*
X4226351Y1680487D01*
X4225791Y1681237D01*
X4225418Y1682112D01*
X4225231Y1683112D01*
Y1684112D01*
X4225418Y1685112D01*
X4225791Y1685987D01*
X4226351Y1686737D01*
X4227004Y1687237D01*
X4227751Y1687362D01*
X4228498Y1687237D01*
X4229151Y1686737D01*
X4229711Y1685987D01*
X4230084Y1685112D01*
X4230271Y1684112D01*
Y1683112D01*
X4230084Y1682112D01*
X4229711Y1681237D01*
X4229151Y1680487D01*
X4228498Y1679987D01*
X4227751Y1679862D01*
G01X4233384D02*
Y1687362D01*
X4235718D01*
X4236464Y1686987D01*
X4236931Y1686487D01*
X4237118Y1685487D01*
X4236931Y1684487D01*
X4236371Y1683862D01*
X4235718Y1683487D01*
X4233384D01*
G01X4235718D02*
X4237118Y1679862D01*
G01X4250251Y1687362D02*
X4249504Y1687112D01*
X4248944Y1686487D01*
X4248571Y1685737D01*
X4248291Y1684737D01*
X4248198Y1683612D01*
X4248291Y1682487D01*
X4248571Y1681487D01*
X4248944Y1680737D01*
X4249504Y1680112D01*
X4250251Y1679862D01*
X4250998Y1680112D01*
X4251558Y1680737D01*
X4251931Y1681487D01*
X4252211Y1682487D01*
X4252304Y1683612D01*
X4252211Y1684737D01*
X4251931Y1685737D01*
X4251558Y1686487D01*
X4250998Y1687112D01*
X4250251Y1687362D01*
G01X4257751Y1679612D02*
X4257564Y1679737D01*
Y1679987D01*
X4257751Y1680112D01*
X4257938Y1679987D01*
Y1679737D01*
X4257751Y1679612D01*
G01X4263198Y1681362D02*
X4263758Y1680487D01*
X4264504Y1679987D01*
X4265344Y1679862D01*
X4266091Y1679987D01*
X4266838Y1680612D01*
X4267304Y1681362D01*
X4267398Y1682112D01*
X4267211Y1682987D01*
X4266558Y1683612D01*
X4265904Y1683862D01*
X4265064D01*
G01X4265904D02*
X4266464Y1684237D01*
X4266931Y1684862D01*
X4267118Y1685612D01*
X4266931Y1686362D01*
X4266464Y1686987D01*
X4265624Y1687362D01*
X4264784Y1687237D01*
X4263944Y1686737D01*
G01X4270978Y1682987D02*
X4271631Y1683862D01*
X4272191Y1684362D01*
X4272938Y1684612D01*
X4273591Y1684362D01*
X4274058Y1683862D01*
X4274431Y1683112D01*
X4274524Y1682237D01*
X4274431Y1681487D01*
X4274058Y1680737D01*
X4273498Y1680112D01*
X4272844Y1679862D01*
X4272098Y1680112D01*
X4271444Y1680862D01*
X4271071Y1681987D01*
X4270978Y1683237D01*
X4271164Y1684862D01*
X4271444Y1685737D01*
X4271911Y1686612D01*
X4272564Y1687237D01*
X4273218Y1687362D01*
X4273871Y1687112D01*
X4274338Y1686487D01*
G01X4277824Y1679862D02*
Y1687362D01*
X4280251Y1681112D01*
X4282678Y1687362D01*
Y1679862D01*
G01X4285324D02*
Y1687362D01*
X4287751Y1681112D01*
X4290178Y1687362D01*
Y1679862D01*
G01X4300978D02*
Y1687362D01*
X4304524D01*
G01X4303218Y1683737D02*
X4300978D01*
G01X4309131Y1687362D02*
X4311371D01*
G01X4310251D02*
Y1679862D01*
G01X4309131D02*
X4311371D01*
G01X4315604D02*
Y1687362D01*
X4319898Y1679862D01*
Y1687362D01*
G01X4324131D02*
X4326371D01*
G01X4325251D02*
Y1679862D01*
G01X4324131D02*
X4326371D01*
G01X4330791Y1680862D02*
X4331538Y1680237D01*
X4332378Y1679862D01*
X4333124D01*
X4333871Y1680237D01*
X4334431Y1680862D01*
X4334711Y1681737D01*
X4334524Y1682612D01*
X4334058Y1683362D01*
X4333218Y1683862D01*
X4332098Y1684112D01*
X4331444Y1684612D01*
X4331164Y1685487D01*
X4331351Y1686362D01*
X4331818Y1686987D01*
X4332471Y1687362D01*
X4333124D01*
X4333778Y1687112D01*
X4334338Y1686487D01*
G01X4338291Y1679862D02*
Y1687362D01*
G01X4342211D02*
Y1679862D01*
G01Y1683612D02*
X4338291D01*
G01X4349618Y1679862D02*
X4345884D01*
Y1687362D01*
X4349618D01*
G01X4348124Y1683737D02*
X4345884D01*
G01X4353198Y1679862D02*
Y1687362D01*
X4355064D01*
X4355811Y1686987D01*
X4356371Y1686487D01*
X4356838Y1685737D01*
X4357211Y1684862D01*
X4357304Y1683612D01*
X4357211Y1682362D01*
X4356838Y1681487D01*
X4356371Y1680737D01*
X4355811Y1680237D01*
X4355064Y1679862D01*
X4353198D01*
G01X4368384D02*
Y1687362D01*
X4370624D01*
X4371371Y1686987D01*
X4371931Y1686112D01*
X4372118Y1685112D01*
X4371931Y1684112D01*
X4371464Y1683362D01*
X4370624Y1682987D01*
X4368384D01*
G01X4377751Y1687362D02*
Y1679862D01*
G01X4375604Y1687362D02*
X4379898D01*
G01X4383291Y1679862D02*
Y1687362D01*
G01X4387211D02*
Y1679862D01*
G01Y1683612D02*
X4383291D01*
G01X4399131Y1687362D02*
X4401371D01*
G01X4400251D02*
Y1679862D01*
G01X4399131D02*
X4401371D01*
G01X4405791Y1680862D02*
X4406538Y1680237D01*
X4407378Y1679862D01*
X4408124D01*
X4408871Y1680237D01*
X4409431Y1680862D01*
X4409711Y1681737D01*
X4409524Y1682612D01*
X4409058Y1683362D01*
X4408218Y1683862D01*
X4407098Y1684112D01*
X4406444Y1684612D01*
X4406164Y1685487D01*
X4406351Y1686362D01*
X4406818Y1686987D01*
X4407471Y1687362D01*
X4408124D01*
X4408778Y1687112D01*
X4409338Y1686487D01*
G01X4422751Y1687362D02*
X4422004Y1687112D01*
X4421444Y1686487D01*
X4421071Y1685737D01*
X4420791Y1684737D01*
X4420698Y1683612D01*
X4420791Y1682487D01*
X4421071Y1681487D01*
X4421444Y1680737D01*
X4422004Y1680112D01*
X4422751Y1679862D01*
X4423498Y1680112D01*
X4424058Y1680737D01*
X4424431Y1681487D01*
X4424711Y1682487D01*
X4424804Y1683612D01*
X4424711Y1684737D01*
X4424431Y1685737D01*
X4424058Y1686487D01*
X4423498Y1687112D01*
X4422751Y1687362D01*
G01X4430251Y1679612D02*
X4430064Y1679737D01*
Y1679987D01*
X4430251Y1680112D01*
X4430438Y1679987D01*
Y1679737D01*
X4430251Y1679612D01*
G01X4438871Y1679862D02*
Y1687362D01*
X4435418Y1681987D01*
X4440084D01*
G01X4443198Y1680987D02*
X4443758Y1680362D01*
X4444411Y1679987D01*
X4445251Y1679862D01*
X4446091Y1680112D01*
X4446744Y1680612D01*
X4447211Y1681487D01*
X4447304Y1682487D01*
X4447118Y1683487D01*
X4446651Y1684112D01*
X4445998Y1684612D01*
X4445344Y1684737D01*
X4444691Y1684612D01*
X4443851Y1684112D01*
X4444131Y1687362D01*
X4446651D01*
G01X4450324Y1679862D02*
Y1687362D01*
X4452751Y1681112D01*
X4455178Y1687362D01*
Y1679862D01*
G01X4457824D02*
Y1687362D01*
X4460251Y1681112D01*
X4462678Y1687362D01*
Y1679862D01*
G01X4472824D02*
Y1687362D01*
X4475251Y1681112D01*
X4477678Y1687362D01*
Y1679862D01*
G01X4484618D02*
X4480884D01*
Y1687362D01*
X4484618D01*
G01X4483124Y1683737D02*
X4480884D01*
G01X4490251Y1687362D02*
Y1679862D01*
G01X4488104Y1687362D02*
X4492398D01*
G01X4495884Y1679862D02*
Y1687362D01*
X4498218D01*
X4498964Y1686987D01*
X4499431Y1686487D01*
X4499618Y1685487D01*
X4499431Y1684487D01*
X4498871Y1683862D01*
X4498218Y1683487D01*
X4495884D01*
G01X4498218D02*
X4499618Y1679862D01*
G01X4504131Y1687362D02*
X4506371D01*
G01X4505251D02*
Y1679862D01*
G01X4504131D02*
X4506371D01*
G01X4514804Y1686737D02*
X4514244Y1687112D01*
X4513591Y1687362D01*
X4512844D01*
X4512004Y1686987D01*
X4511351Y1686362D01*
X4510884Y1685612D01*
X4510511Y1684362D01*
X4510418Y1683237D01*
X4510604Y1682112D01*
X4510884Y1681362D01*
X4511444Y1680612D01*
X4512098Y1680112D01*
X4512751Y1679862D01*
X4513404D01*
X4514058Y1680112D01*
X4514618Y1680487D01*
X4515084Y1680987D01*
G01X4525698Y1679862D02*
Y1687362D01*
X4527564D01*
X4528311Y1686987D01*
X4528871Y1686487D01*
X4529338Y1685737D01*
X4529711Y1684862D01*
X4529804Y1683612D01*
X4529711Y1682362D01*
X4529338Y1681487D01*
X4528871Y1680737D01*
X4528311Y1680237D01*
X4527564Y1679862D01*
X4525698D01*
G01X4533384D02*
Y1687362D01*
X4535718D01*
X4536464Y1686987D01*
X4536931Y1686487D01*
X4537118Y1685487D01*
X4536931Y1684487D01*
X4536371Y1683862D01*
X4535718Y1683487D01*
X4533384D01*
G01X4535718D02*
X4537118Y1679862D01*
G01X4541631Y1687362D02*
X4543871D01*
G01X4542751D02*
Y1679862D01*
G01X4541631D02*
X4543871D01*
G01X4548384Y1687362D02*
Y1679862D01*
X4552118D01*
G01X4555884Y1687362D02*
Y1679862D01*
X4559618D01*
G01X4564784Y1677362D02*
X4563851Y1678612D01*
X4563384Y1679862D01*
Y1684862D01*
X4563851Y1686112D01*
X4564784Y1687362D01*
G01X4572751D02*
X4572004Y1687112D01*
X4571444Y1686487D01*
X4571071Y1685737D01*
X4570791Y1684737D01*
X4570698Y1683612D01*
X4570791Y1682487D01*
X4571071Y1681487D01*
X4571444Y1680737D01*
X4572004Y1680112D01*
X4572751Y1679862D01*
X4573498Y1680112D01*
X4574058Y1680737D01*
X4574431Y1681487D01*
X4574711Y1682487D01*
X4574804Y1683612D01*
X4574711Y1684737D01*
X4574431Y1685737D01*
X4574058Y1686487D01*
X4573498Y1687112D01*
X4572751Y1687362D01*
G01X4580251Y1679612D02*
X4580064Y1679737D01*
Y1679987D01*
X4580251Y1680112D01*
X4580438Y1679987D01*
Y1679737D01*
X4580251Y1679612D01*
G01X4587751Y1687362D02*
X4587004Y1687112D01*
X4586444Y1686487D01*
X4586071Y1685737D01*
X4585791Y1684737D01*
X4585698Y1683612D01*
X4585791Y1682487D01*
X4586071Y1681487D01*
X4586444Y1680737D01*
X4587004Y1680112D01*
X4587751Y1679862D01*
X4588498Y1680112D01*
X4589058Y1680737D01*
X4589431Y1681487D01*
X4589711Y1682487D01*
X4589804Y1683612D01*
X4589711Y1684737D01*
X4589431Y1685737D01*
X4589058Y1686487D01*
X4588498Y1687112D01*
X4587751Y1687362D01*
G01X4595251Y1679862D02*
Y1687362D01*
X4594131Y1685862D01*
G01Y1679862D02*
X4596371D01*
G01X4602564D02*
X4602751Y1681487D01*
X4603031Y1682862D01*
X4603404Y1684112D01*
X4603871Y1685487D01*
X4604618Y1687362D01*
X4600884D01*
G01X4610064Y1679862D02*
X4610251Y1681487D01*
X4610531Y1682862D01*
X4610904Y1684112D01*
X4611371Y1685487D01*
X4612118Y1687362D01*
X4608384D01*
G01X4616911Y1685737D02*
X4617378Y1687362D01*
G01X4618591D02*
X4618124Y1685737D01*
G01X4625718Y1677362D02*
X4626651Y1678612D01*
X4627118Y1679862D01*
Y1684862D01*
X4626651Y1686112D01*
X4625718Y1687362D01*
G01X4632751Y1679612D02*
X4632564Y1679737D01*
Y1679987D01*
X4632751Y1680112D01*
X4632938Y1679987D01*
Y1679737D01*
X4632751Y1679612D01*
G01X3854396Y1609324D02*
X3855143Y1608699D01*
X3855983Y1608324D01*
X3856729D01*
X3857476Y1608699D01*
X3858036Y1609324D01*
X3858316Y1610199D01*
X3858129Y1611074D01*
X3857663Y1611824D01*
X3856823Y1612324D01*
X3855703Y1612574D01*
X3855049Y1613074D01*
X3854769Y1613949D01*
X3854956Y1614824D01*
X3855423Y1615449D01*
X3856076Y1615824D01*
X3856729D01*
X3857383Y1615574D01*
X3857943Y1614949D01*
G01X3862736Y1615824D02*
X3864976D01*
G01X3863856D02*
Y1608324D01*
G01X3862736D02*
X3864976D01*
G01X3869489Y1615824D02*
Y1608324D01*
X3873223D01*
G01X3876523Y1615824D02*
X3878856Y1608324D01*
X3881189Y1615824D01*
G01X3888223Y1608324D02*
X3884489D01*
Y1615824D01*
X3888223D01*
G01X3886729Y1612199D02*
X3884489D01*
G01X3891989Y1608324D02*
Y1615824D01*
X3894323D01*
X3895069Y1615449D01*
X3895536Y1614949D01*
X3895723Y1613949D01*
X3895536Y1612949D01*
X3894976Y1612324D01*
X3894323Y1611949D01*
X3891989D01*
G01X3894323D02*
X3895723Y1608324D01*
G01X3900889Y1605824D02*
X3899956Y1607074D01*
X3899489Y1608324D01*
Y1613324D01*
X3899956Y1614574D01*
X3900889Y1615824D01*
G01X3907736D02*
X3909976D01*
G01X3908856D02*
Y1608324D01*
G01X3907736D02*
X3909976D01*
G01X3913929D02*
Y1615824D01*
X3916356Y1609574D01*
X3918783Y1615824D01*
Y1608324D01*
G01X3921429D02*
Y1615824D01*
X3923856Y1609574D01*
X3926283Y1615824D01*
Y1608324D01*
G01X3933223D02*
X3929489D01*
Y1615824D01*
X3933223D01*
G01X3931729Y1612199D02*
X3929489D01*
G01X3936989Y1608324D02*
Y1615824D01*
X3939323D01*
X3940069Y1615449D01*
X3940536Y1614949D01*
X3940723Y1613949D01*
X3940536Y1612949D01*
X3939976Y1612324D01*
X3939323Y1611949D01*
X3936989D01*
G01X3939323D02*
X3940723Y1608324D01*
G01X3944396Y1609324D02*
X3945143Y1608699D01*
X3945983Y1608324D01*
X3946729D01*
X3947476Y1608699D01*
X3948036Y1609324D01*
X3948316Y1610199D01*
X3948129Y1611074D01*
X3947663Y1611824D01*
X3946823Y1612324D01*
X3945703Y1612574D01*
X3945049Y1613074D01*
X3944769Y1613949D01*
X3944956Y1614824D01*
X3945423Y1615449D01*
X3946076Y1615824D01*
X3946729D01*
X3947383Y1615574D01*
X3947943Y1614949D01*
G01X3952736Y1615824D02*
X3954976D01*
G01X3953856D02*
Y1608324D01*
G01X3952736D02*
X3954976D01*
G01X3961356D02*
X3960609Y1608449D01*
X3959956Y1608949D01*
X3959396Y1609699D01*
X3959023Y1610574D01*
X3958836Y1611574D01*
Y1612574D01*
X3959023Y1613574D01*
X3959396Y1614449D01*
X3959956Y1615199D01*
X3960609Y1615699D01*
X3961356Y1615824D01*
X3962103Y1615699D01*
X3962756Y1615199D01*
X3963316Y1614449D01*
X3963689Y1613574D01*
X3963876Y1612574D01*
Y1611574D01*
X3963689Y1610574D01*
X3963316Y1609699D01*
X3962756Y1608949D01*
X3962103Y1608449D01*
X3961356Y1608324D01*
G01X3966709D02*
Y1615824D01*
X3971003Y1608324D01*
Y1615824D01*
G01X3976823Y1605824D02*
X3977756Y1607074D01*
X3978223Y1608324D01*
Y1613324D01*
X3977756Y1614574D01*
X3976823Y1615824D01*
G01X3983856Y1608074D02*
X3983669Y1608199D01*
Y1608449D01*
X3983856Y1608574D01*
X3984043Y1608449D01*
Y1608199D01*
X3983856Y1608074D01*
G01Y1611449D02*
X3983669Y1611574D01*
Y1611824D01*
X3983856Y1611949D01*
X3984043Y1611824D01*
Y1611574D01*
X3983856Y1611449D01*
G01X3989489Y1608324D02*
Y1615824D01*
X3991823D01*
X3992569Y1615449D01*
X3993036Y1614949D01*
X3993223Y1613949D01*
X3993036Y1612949D01*
X3992476Y1612324D01*
X3991823Y1611949D01*
X3989489D01*
G01X3991823D02*
X3993223Y1608324D01*
G01X4000723D02*
X3996989D01*
Y1615824D01*
X4000723D01*
G01X3999229Y1612199D02*
X3996989D01*
G01X4008409Y1615199D02*
X4007849Y1615574D01*
X4007196Y1615824D01*
X4006449D01*
X4005609Y1615449D01*
X4004956Y1614824D01*
X4004489Y1614074D01*
X4004116Y1612824D01*
X4004023Y1611699D01*
X4004209Y1610574D01*
X4004489Y1609824D01*
X4005049Y1609074D01*
X4005703Y1608574D01*
X4006356Y1608324D01*
X4007009D01*
X4007663Y1608574D01*
X4008223Y1608949D01*
X4008689Y1609449D01*
G01X4013856Y1608324D02*
X4013109Y1608449D01*
X4012456Y1608949D01*
X4011896Y1609699D01*
X4011523Y1610574D01*
X4011336Y1611574D01*
Y1612574D01*
X4011523Y1613574D01*
X4011896Y1614449D01*
X4012456Y1615199D01*
X4013109Y1615699D01*
X4013856Y1615824D01*
X4014603Y1615699D01*
X4015256Y1615199D01*
X4015816Y1614449D01*
X4016189Y1613574D01*
X4016376Y1612574D01*
Y1611574D01*
X4016189Y1610574D01*
X4015816Y1609699D01*
X4015256Y1608949D01*
X4014603Y1608449D01*
X4013856Y1608324D01*
G01X4018929D02*
Y1615824D01*
X4021356Y1609574D01*
X4023783Y1615824D01*
Y1608324D01*
G01X4026429D02*
Y1615824D01*
X4028856Y1609574D01*
X4031283Y1615824D01*
Y1608324D01*
G01X4038223D02*
X4034489D01*
Y1615824D01*
X4038223D01*
G01X4036729Y1612199D02*
X4034489D01*
G01X4041709Y1608324D02*
Y1615824D01*
X4046003Y1608324D01*
Y1615824D01*
G01X4049303Y1608324D02*
Y1615824D01*
X4051169D01*
X4051916Y1615449D01*
X4052476Y1614949D01*
X4052943Y1614199D01*
X4053316Y1613324D01*
X4053409Y1612074D01*
X4053316Y1610824D01*
X4052943Y1609949D01*
X4052476Y1609199D01*
X4051916Y1608699D01*
X4051169Y1608324D01*
X4049303D01*
G01X4060723D02*
X4056989D01*
Y1615824D01*
X4060723D01*
G01X4059229Y1612199D02*
X4056989D01*
G01X4064303Y1608324D02*
Y1615824D01*
X4066169D01*
X4066916Y1615449D01*
X4067476Y1614949D01*
X4067943Y1614199D01*
X4068316Y1613324D01*
X4068409Y1612074D01*
X4068316Y1610824D01*
X4067943Y1609949D01*
X4067476Y1609199D01*
X4066916Y1608699D01*
X4066169Y1608324D01*
X4064303D01*
G01X4079303D02*
Y1615824D01*
X4081169D01*
X4081916Y1615449D01*
X4082476Y1614949D01*
X4082943Y1614199D01*
X4083316Y1613324D01*
X4083409Y1612074D01*
X4083316Y1610824D01*
X4082943Y1609949D01*
X4082476Y1609199D01*
X4081916Y1608699D01*
X4081169Y1608324D01*
X4079303D01*
G01X4086989D02*
Y1615824D01*
X4089323D01*
X4090069Y1615449D01*
X4090536Y1614949D01*
X4090723Y1613949D01*
X4090536Y1612949D01*
X4089976Y1612324D01*
X4089323Y1611949D01*
X4086989D01*
G01X4089323D02*
X4090723Y1608324D01*
G01X4095236Y1615824D02*
X4097476D01*
G01X4096356D02*
Y1608324D01*
G01X4095236D02*
X4097476D01*
G01X4101989Y1615824D02*
Y1608324D01*
X4105723D01*
G01X4109489Y1615824D02*
Y1608324D01*
X4113223D01*
G01X4124396Y1609324D02*
X4125143Y1608699D01*
X4125983Y1608324D01*
X4126729D01*
X4127476Y1608699D01*
X4128036Y1609324D01*
X4128316Y1610199D01*
X4128129Y1611074D01*
X4127663Y1611824D01*
X4126823Y1612324D01*
X4125703Y1612574D01*
X4125049Y1613074D01*
X4124769Y1613949D01*
X4124956Y1614824D01*
X4125423Y1615449D01*
X4126076Y1615824D01*
X4126729D01*
X4127383Y1615574D01*
X4127943Y1614949D01*
G01X4132736Y1615824D02*
X4134976D01*
G01X4133856D02*
Y1608324D01*
G01X4132736D02*
X4134976D01*
G01X4139583Y1615824D02*
X4143129D01*
X4139583Y1608324D01*
X4143129D01*
G01X4150723D02*
X4146989D01*
Y1615824D01*
X4150723D01*
G01X4149229Y1612199D02*
X4146989D01*
G01X4162083Y1608324D02*
Y1615824D01*
X4165629D01*
G01X4164323Y1612199D02*
X4162083D01*
G01X4171356Y1608324D02*
X4170609Y1608449D01*
X4169956Y1608949D01*
X4169396Y1609699D01*
X4169023Y1610574D01*
X4168836Y1611574D01*
Y1612574D01*
X4169023Y1613574D01*
X4169396Y1614449D01*
X4169956Y1615199D01*
X4170609Y1615699D01*
X4171356Y1615824D01*
X4172103Y1615699D01*
X4172756Y1615199D01*
X4173316Y1614449D01*
X4173689Y1613574D01*
X4173876Y1612574D01*
Y1611574D01*
X4173689Y1610574D01*
X4173316Y1609699D01*
X4172756Y1608949D01*
X4172103Y1608449D01*
X4171356Y1608324D01*
G01X4176989D02*
Y1615824D01*
X4179323D01*
X4180069Y1615449D01*
X4180536Y1614949D01*
X4180723Y1613949D01*
X4180536Y1612949D01*
X4179976Y1612324D01*
X4179323Y1611949D01*
X4176989D01*
G01X4179323D02*
X4180723Y1608324D01*
G01X4193856Y1615824D02*
X4193109Y1615574D01*
X4192549Y1614949D01*
X4192176Y1614199D01*
X4191896Y1613199D01*
X4191803Y1612074D01*
X4191896Y1610949D01*
X4192176Y1609949D01*
X4192549Y1609199D01*
X4193109Y1608574D01*
X4193856Y1608324D01*
X4194603Y1608574D01*
X4195163Y1609199D01*
X4195536Y1609949D01*
X4195816Y1610949D01*
X4195909Y1612074D01*
X4195816Y1613199D01*
X4195536Y1614199D01*
X4195163Y1614949D01*
X4194603Y1615574D01*
X4193856Y1615824D01*
G01X4201356Y1608074D02*
X4201169Y1608199D01*
Y1608449D01*
X4201356Y1608574D01*
X4201543Y1608449D01*
Y1608199D01*
X4201356Y1608074D01*
G01X4206803Y1609449D02*
X4207363Y1608824D01*
X4208016Y1608449D01*
X4208856Y1608324D01*
X4209696Y1608574D01*
X4210349Y1609074D01*
X4210816Y1609949D01*
X4210909Y1610949D01*
X4210723Y1611949D01*
X4210256Y1612574D01*
X4209603Y1613074D01*
X4208949Y1613199D01*
X4208296Y1613074D01*
X4207456Y1612574D01*
X4207736Y1615824D01*
X4210256D01*
G01X4213929Y1608324D02*
Y1615824D01*
X4216356Y1609574D01*
X4218783Y1615824D01*
Y1608324D01*
G01X4221429D02*
Y1615824D01*
X4223856Y1609574D01*
X4226283Y1615824D01*
Y1608324D01*
G01X4237083D02*
Y1615824D01*
X4240629D01*
G01X4239323Y1612199D02*
X4237083D01*
G01X4245236Y1615824D02*
X4247476D01*
G01X4246356D02*
Y1608324D01*
G01X4245236D02*
X4247476D01*
G01X4251709D02*
Y1615824D01*
X4256003Y1608324D01*
Y1615824D01*
G01X4260236D02*
X4262476D01*
G01X4261356D02*
Y1608324D01*
G01X4260236D02*
X4262476D01*
G01X4266896Y1609324D02*
X4267643Y1608699D01*
X4268483Y1608324D01*
X4269229D01*
X4269976Y1608699D01*
X4270536Y1609324D01*
X4270816Y1610199D01*
X4270629Y1611074D01*
X4270163Y1611824D01*
X4269323Y1612324D01*
X4268203Y1612574D01*
X4267549Y1613074D01*
X4267269Y1613949D01*
X4267456Y1614824D01*
X4267923Y1615449D01*
X4268576Y1615824D01*
X4269229D01*
X4269883Y1615574D01*
X4270443Y1614949D01*
G01X4274396Y1608324D02*
Y1615824D01*
G01X4278316D02*
Y1608324D01*
G01Y1612074D02*
X4274396D01*
G01X4285723Y1608324D02*
X4281989D01*
Y1615824D01*
X4285723D01*
G01X4284229Y1612199D02*
X4281989D01*
G01X4289303Y1608324D02*
Y1615824D01*
X4291169D01*
X4291916Y1615449D01*
X4292476Y1614949D01*
X4292943Y1614199D01*
X4293316Y1613324D01*
X4293409Y1612074D01*
X4293316Y1610824D01*
X4292943Y1609949D01*
X4292476Y1609199D01*
X4291916Y1608699D01*
X4291169Y1608324D01*
X4289303D01*
G01X4304489D02*
Y1615824D01*
X4306729D01*
X4307476Y1615449D01*
X4308036Y1614574D01*
X4308223Y1613574D01*
X4308036Y1612574D01*
X4307569Y1611824D01*
X4306729Y1611449D01*
X4304489D01*
G01X4313856Y1615824D02*
Y1608324D01*
G01X4311709Y1615824D02*
X4316003D01*
G01X4319396Y1608324D02*
Y1615824D01*
G01X4323316D02*
Y1608324D01*
G01Y1612074D02*
X4319396D01*
G01X4335236Y1615824D02*
X4337476D01*
G01X4336356D02*
Y1608324D01*
G01X4335236D02*
X4337476D01*
G01X4341896Y1609324D02*
X4342643Y1608699D01*
X4343483Y1608324D01*
X4344229D01*
X4344976Y1608699D01*
X4345536Y1609324D01*
X4345816Y1610199D01*
X4345629Y1611074D01*
X4345163Y1611824D01*
X4344323Y1612324D01*
X4343203Y1612574D01*
X4342549Y1613074D01*
X4342269Y1613949D01*
X4342456Y1614824D01*
X4342923Y1615449D01*
X4343576Y1615824D01*
X4344229D01*
X4344883Y1615574D01*
X4345443Y1614949D01*
G01X4358856Y1615824D02*
X4358109Y1615574D01*
X4357549Y1614949D01*
X4357176Y1614199D01*
X4356896Y1613199D01*
X4356803Y1612074D01*
X4356896Y1610949D01*
X4357176Y1609949D01*
X4357549Y1609199D01*
X4358109Y1608574D01*
X4358856Y1608324D01*
X4359603Y1608574D01*
X4360163Y1609199D01*
X4360536Y1609949D01*
X4360816Y1610949D01*
X4360909Y1612074D01*
X4360816Y1613199D01*
X4360536Y1614199D01*
X4360163Y1614949D01*
X4359603Y1615574D01*
X4358856Y1615824D01*
G01X4366356Y1608074D02*
X4366169Y1608199D01*
Y1608449D01*
X4366356Y1608574D01*
X4366543Y1608449D01*
Y1608199D01*
X4366356Y1608074D01*
G01X4372083Y1611449D02*
X4372736Y1612324D01*
X4373296Y1612824D01*
X4374043Y1613074D01*
X4374696Y1612824D01*
X4375163Y1612324D01*
X4375536Y1611574D01*
X4375629Y1610699D01*
X4375536Y1609949D01*
X4375163Y1609199D01*
X4374603Y1608574D01*
X4373949Y1608324D01*
X4373203Y1608574D01*
X4372549Y1609324D01*
X4372176Y1610449D01*
X4372083Y1611699D01*
X4372269Y1613324D01*
X4372549Y1614199D01*
X4373016Y1615074D01*
X4373669Y1615699D01*
X4374323Y1615824D01*
X4374976Y1615574D01*
X4375443Y1614949D01*
G01X4378929Y1608324D02*
Y1615824D01*
X4381356Y1609574D01*
X4383783Y1615824D01*
Y1608324D01*
G01X4386429D02*
Y1615824D01*
X4388856Y1609574D01*
X4391283Y1615824D01*
Y1608324D01*
G01X4401429D02*
Y1615824D01*
X4403856Y1609574D01*
X4406283Y1615824D01*
Y1608324D01*
G01X4413223D02*
X4409489D01*
Y1615824D01*
X4413223D01*
G01X4411729Y1612199D02*
X4409489D01*
G01X4418856Y1615824D02*
Y1608324D01*
G01X4416709Y1615824D02*
X4421003D01*
G01X4424489Y1608324D02*
Y1615824D01*
X4426823D01*
X4427569Y1615449D01*
X4428036Y1614949D01*
X4428223Y1613949D01*
X4428036Y1612949D01*
X4427476Y1612324D01*
X4426823Y1611949D01*
X4424489D01*
G01X4426823D02*
X4428223Y1608324D01*
G01X4432736Y1615824D02*
X4434976D01*
G01X4433856D02*
Y1608324D01*
G01X4432736D02*
X4434976D01*
G01X4443409Y1615199D02*
X4442849Y1615574D01*
X4442196Y1615824D01*
X4441449D01*
X4440609Y1615449D01*
X4439956Y1614824D01*
X4439489Y1614074D01*
X4439116Y1612824D01*
X4439023Y1611699D01*
X4439209Y1610574D01*
X4439489Y1609824D01*
X4440049Y1609074D01*
X4440703Y1608574D01*
X4441356Y1608324D01*
X4442009D01*
X4442663Y1608574D01*
X4443223Y1608949D01*
X4443689Y1609449D01*
G01X4454303Y1608324D02*
Y1615824D01*
X4456169D01*
X4456916Y1615449D01*
X4457476Y1614949D01*
X4457943Y1614199D01*
X4458316Y1613324D01*
X4458409Y1612074D01*
X4458316Y1610824D01*
X4457943Y1609949D01*
X4457476Y1609199D01*
X4456916Y1608699D01*
X4456169Y1608324D01*
X4454303D01*
G01X4461989D02*
Y1615824D01*
X4464323D01*
X4465069Y1615449D01*
X4465536Y1614949D01*
X4465723Y1613949D01*
X4465536Y1612949D01*
X4464976Y1612324D01*
X4464323Y1611949D01*
X4461989D01*
G01X4464323D02*
X4465723Y1608324D01*
G01X4470236Y1615824D02*
X4472476D01*
G01X4471356D02*
Y1608324D01*
G01X4470236D02*
X4472476D01*
G01X4476989Y1615824D02*
Y1608324D01*
X4480723D01*
G01X4484489Y1615824D02*
Y1608324D01*
X4488223D01*
G01X4493389Y1605824D02*
X4492456Y1607074D01*
X4491989Y1608324D01*
Y1613324D01*
X4492456Y1614574D01*
X4493389Y1615824D01*
G01X4501356D02*
X4500609Y1615574D01*
X4500049Y1614949D01*
X4499676Y1614199D01*
X4499396Y1613199D01*
X4499303Y1612074D01*
X4499396Y1610949D01*
X4499676Y1609949D01*
X4500049Y1609199D01*
X4500609Y1608574D01*
X4501356Y1608324D01*
X4502103Y1608574D01*
X4502663Y1609199D01*
X4503036Y1609949D01*
X4503316Y1610949D01*
X4503409Y1612074D01*
X4503316Y1613199D01*
X4503036Y1614199D01*
X4502663Y1614949D01*
X4502103Y1615574D01*
X4501356Y1615824D01*
G01X4508856Y1608074D02*
X4508669Y1608199D01*
Y1608449D01*
X4508856Y1608574D01*
X4509043Y1608449D01*
Y1608199D01*
X4508856Y1608074D01*
G01X4516356Y1615824D02*
X4515609Y1615574D01*
X4515049Y1614949D01*
X4514676Y1614199D01*
X4514396Y1613199D01*
X4514303Y1612074D01*
X4514396Y1610949D01*
X4514676Y1609949D01*
X4515049Y1609199D01*
X4515609Y1608574D01*
X4516356Y1608324D01*
X4517103Y1608574D01*
X4517663Y1609199D01*
X4518036Y1609949D01*
X4518316Y1610949D01*
X4518409Y1612074D01*
X4518316Y1613199D01*
X4518036Y1614199D01*
X4517663Y1614949D01*
X4517103Y1615574D01*
X4516356Y1615824D01*
G01X4522083Y1614574D02*
X4522643Y1615324D01*
X4523296Y1615699D01*
X4524043Y1615824D01*
X4524976Y1615574D01*
X4525629Y1614949D01*
X4525816Y1614199D01*
X4525723Y1613449D01*
X4525349Y1612824D01*
X4523483Y1611574D01*
X4522643Y1610699D01*
X4522083Y1609449D01*
X4521896Y1608324D01*
X4525816D01*
G01X4529303Y1609824D02*
X4529863Y1608949D01*
X4530609Y1608449D01*
X4531449Y1608324D01*
X4532196Y1608449D01*
X4532943Y1609074D01*
X4533409Y1609824D01*
X4533503Y1610574D01*
X4533316Y1611449D01*
X4532663Y1612074D01*
X4532009Y1612324D01*
X4531169D01*
G01X4532009D02*
X4532569Y1612699D01*
X4533036Y1613324D01*
X4533223Y1614074D01*
X4533036Y1614824D01*
X4532569Y1615449D01*
X4531729Y1615824D01*
X4530889Y1615699D01*
X4530049Y1615199D01*
G01X4537083Y1611449D02*
X4537736Y1612324D01*
X4538296Y1612824D01*
X4539043Y1613074D01*
X4539696Y1612824D01*
X4540163Y1612324D01*
X4540536Y1611574D01*
X4540629Y1610699D01*
X4540536Y1609949D01*
X4540163Y1609199D01*
X4539603Y1608574D01*
X4538949Y1608324D01*
X4538203Y1608574D01*
X4537549Y1609324D01*
X4537176Y1610449D01*
X4537083Y1611699D01*
X4537269Y1613324D01*
X4537549Y1614199D01*
X4538016Y1615074D01*
X4538669Y1615699D01*
X4539323Y1615824D01*
X4539976Y1615574D01*
X4540443Y1614949D01*
G01X4545516Y1614199D02*
X4545983Y1615824D01*
G01X4547196D02*
X4546729Y1614199D01*
G01X4554323Y1605824D02*
X4555256Y1607074D01*
X4555723Y1608324D01*
Y1613324D01*
X4555256Y1614574D01*
X4554323Y1615824D01*
G01X4561356Y1608074D02*
X4561169Y1608199D01*
Y1608449D01*
X4561356Y1608574D01*
X4561543Y1608449D01*
Y1608199D01*
X4561356Y1608074D01*
G01X3858409Y1628099D02*
X3857849Y1628474D01*
X3857196Y1628724D01*
X3856449D01*
X3855609Y1628349D01*
X3854956Y1627724D01*
X3854489Y1626974D01*
X3854116Y1625724D01*
X3854023Y1624599D01*
X3854209Y1623474D01*
X3854489Y1622724D01*
X3855049Y1621974D01*
X3855703Y1621474D01*
X3856356Y1621224D01*
X3857009D01*
X3857663Y1621474D01*
X3858223Y1621849D01*
X3858689Y1622349D01*
G01X3863856Y1621224D02*
X3863109Y1621349D01*
X3862456Y1621849D01*
X3861896Y1622599D01*
X3861523Y1623474D01*
X3861336Y1624474D01*
Y1625474D01*
X3861523Y1626474D01*
X3861896Y1627349D01*
X3862456Y1628099D01*
X3863109Y1628599D01*
X3863856Y1628724D01*
X3864603Y1628599D01*
X3865256Y1628099D01*
X3865816Y1627349D01*
X3866189Y1626474D01*
X3866376Y1625474D01*
Y1624474D01*
X3866189Y1623474D01*
X3865816Y1622599D01*
X3865256Y1621849D01*
X3864603Y1621349D01*
X3863856Y1621224D01*
G01X3869489D02*
Y1628724D01*
X3871729D01*
X3872476Y1628349D01*
X3873036Y1627474D01*
X3873223Y1626474D01*
X3873036Y1625474D01*
X3872569Y1624724D01*
X3871729Y1624349D01*
X3869489D01*
G01X3876989Y1621224D02*
Y1628724D01*
X3879229D01*
X3879976Y1628349D01*
X3880536Y1627474D01*
X3880723Y1626474D01*
X3880536Y1625474D01*
X3880069Y1624724D01*
X3879229Y1624349D01*
X3876989D01*
G01X3888223Y1621224D02*
X3884489D01*
Y1628724D01*
X3888223D01*
G01X3886729Y1625099D02*
X3884489D01*
G01X3891989Y1621224D02*
Y1628724D01*
X3894323D01*
X3895069Y1628349D01*
X3895536Y1627849D01*
X3895723Y1626849D01*
X3895536Y1625849D01*
X3894976Y1625224D01*
X3894323Y1624849D01*
X3891989D01*
G01X3894323D02*
X3895723Y1621224D01*
G01X3908856D02*
X3908109Y1621349D01*
X3907456Y1621849D01*
X3906896Y1622599D01*
X3906523Y1623474D01*
X3906336Y1624474D01*
Y1625474D01*
X3906523Y1626474D01*
X3906896Y1627349D01*
X3907456Y1628099D01*
X3908109Y1628599D01*
X3908856Y1628724D01*
X3909603Y1628599D01*
X3910256Y1628099D01*
X3910816Y1627349D01*
X3911189Y1626474D01*
X3911376Y1625474D01*
Y1624474D01*
X3911189Y1623474D01*
X3910816Y1622599D01*
X3910256Y1621849D01*
X3909603Y1621349D01*
X3908856Y1621224D01*
G01X3914396Y1622224D02*
X3915143Y1621599D01*
X3915983Y1621224D01*
X3916729D01*
X3917476Y1621599D01*
X3918036Y1622224D01*
X3918316Y1623099D01*
X3918129Y1623974D01*
X3917663Y1624724D01*
X3916823Y1625224D01*
X3915703Y1625474D01*
X3915049Y1625974D01*
X3914769Y1626849D01*
X3914956Y1627724D01*
X3915423Y1628349D01*
X3916076Y1628724D01*
X3916729D01*
X3917383Y1628474D01*
X3917943Y1627849D01*
G01X3921989Y1621224D02*
Y1628724D01*
X3924229D01*
X3924976Y1628349D01*
X3925536Y1627474D01*
X3925723Y1626474D01*
X3925536Y1625474D01*
X3925069Y1624724D01*
X3924229Y1624349D01*
X3921989D01*
G01X3929676Y1620974D02*
X3933036Y1628724D01*
G01X3938856D02*
Y1621224D01*
G01X3936709Y1628724D02*
X3941003D01*
G01X3945236D02*
X3947476D01*
G01X3946356D02*
Y1621224D01*
G01X3945236D02*
X3947476D01*
G01X3951709D02*
Y1628724D01*
X3956003Y1621224D01*
Y1628724D01*
G01X3960889Y1618724D02*
X3959956Y1619974D01*
X3959489Y1621224D01*
Y1626224D01*
X3959956Y1627474D01*
X3960889Y1628724D01*
G01X3967736D02*
X3969976D01*
G01X3968856D02*
Y1621224D01*
G01X3967736D02*
X3969976D01*
G01X3973929D02*
Y1628724D01*
X3976356Y1622474D01*
X3978783Y1628724D01*
Y1621224D01*
G01X3981429D02*
Y1628724D01*
X3983856Y1622474D01*
X3986283Y1628724D01*
Y1621224D01*
G01X3993223D02*
X3989489D01*
Y1628724D01*
X3993223D01*
G01X3991729Y1625099D02*
X3989489D01*
G01X3996989Y1621224D02*
Y1628724D01*
X3999323D01*
X4000069Y1628349D01*
X4000536Y1627849D01*
X4000723Y1626849D01*
X4000536Y1625849D01*
X3999976Y1625224D01*
X3999323Y1624849D01*
X3996989D01*
G01X3999323D02*
X4000723Y1621224D01*
G01X4004396Y1622224D02*
X4005143Y1621599D01*
X4005983Y1621224D01*
X4006729D01*
X4007476Y1621599D01*
X4008036Y1622224D01*
X4008316Y1623099D01*
X4008129Y1623974D01*
X4007663Y1624724D01*
X4006823Y1625224D01*
X4005703Y1625474D01*
X4005049Y1625974D01*
X4004769Y1626849D01*
X4004956Y1627724D01*
X4005423Y1628349D01*
X4006076Y1628724D01*
X4006729D01*
X4007383Y1628474D01*
X4007943Y1627849D01*
G01X4012736Y1628724D02*
X4014976D01*
G01X4013856D02*
Y1621224D01*
G01X4012736D02*
X4014976D01*
G01X4021356D02*
X4020609Y1621349D01*
X4019956Y1621849D01*
X4019396Y1622599D01*
X4019023Y1623474D01*
X4018836Y1624474D01*
Y1625474D01*
X4019023Y1626474D01*
X4019396Y1627349D01*
X4019956Y1628099D01*
X4020609Y1628599D01*
X4021356Y1628724D01*
X4022103Y1628599D01*
X4022756Y1628099D01*
X4023316Y1627349D01*
X4023689Y1626474D01*
X4023876Y1625474D01*
Y1624474D01*
X4023689Y1623474D01*
X4023316Y1622599D01*
X4022756Y1621849D01*
X4022103Y1621349D01*
X4021356Y1621224D01*
G01X4026709D02*
Y1628724D01*
X4031003Y1621224D01*
Y1628724D01*
G01X4036823Y1618724D02*
X4037756Y1619974D01*
X4038223Y1621224D01*
Y1626224D01*
X4037756Y1627474D01*
X4036823Y1628724D01*
G01X4043856Y1620974D02*
X4043669Y1621099D01*
Y1621349D01*
X4043856Y1621474D01*
X4044043Y1621349D01*
Y1621099D01*
X4043856Y1620974D01*
G01Y1624349D02*
X4043669Y1624474D01*
Y1624724D01*
X4043856Y1624849D01*
X4044043Y1624724D01*
Y1624474D01*
X4043856Y1624349D01*
G01X4049489Y1621224D02*
Y1628724D01*
X4051823D01*
X4052569Y1628349D01*
X4053036Y1627849D01*
X4053223Y1626849D01*
X4053036Y1625849D01*
X4052476Y1625224D01*
X4051823Y1624849D01*
X4049489D01*
G01X4051823D02*
X4053223Y1621224D01*
G01X4060723D02*
X4056989D01*
Y1628724D01*
X4060723D01*
G01X4059229Y1625099D02*
X4056989D01*
G01X4068409Y1628099D02*
X4067849Y1628474D01*
X4067196Y1628724D01*
X4066449D01*
X4065609Y1628349D01*
X4064956Y1627724D01*
X4064489Y1626974D01*
X4064116Y1625724D01*
X4064023Y1624599D01*
X4064209Y1623474D01*
X4064489Y1622724D01*
X4065049Y1621974D01*
X4065703Y1621474D01*
X4066356Y1621224D01*
X4067009D01*
X4067663Y1621474D01*
X4068223Y1621849D01*
X4068689Y1622349D01*
G01X4073856Y1621224D02*
X4073109Y1621349D01*
X4072456Y1621849D01*
X4071896Y1622599D01*
X4071523Y1623474D01*
X4071336Y1624474D01*
Y1625474D01*
X4071523Y1626474D01*
X4071896Y1627349D01*
X4072456Y1628099D01*
X4073109Y1628599D01*
X4073856Y1628724D01*
X4074603Y1628599D01*
X4075256Y1628099D01*
X4075816Y1627349D01*
X4076189Y1626474D01*
X4076376Y1625474D01*
Y1624474D01*
X4076189Y1623474D01*
X4075816Y1622599D01*
X4075256Y1621849D01*
X4074603Y1621349D01*
X4073856Y1621224D01*
G01X4078929D02*
Y1628724D01*
X4081356Y1622474D01*
X4083783Y1628724D01*
Y1621224D01*
G01X4086429D02*
Y1628724D01*
X4088856Y1622474D01*
X4091283Y1628724D01*
Y1621224D01*
G01X4098223D02*
X4094489D01*
Y1628724D01*
X4098223D01*
G01X4096729Y1625099D02*
X4094489D01*
G01X4101709Y1621224D02*
Y1628724D01*
X4106003Y1621224D01*
Y1628724D01*
G01X4109303Y1621224D02*
Y1628724D01*
X4111169D01*
X4111916Y1628349D01*
X4112476Y1627849D01*
X4112943Y1627099D01*
X4113316Y1626224D01*
X4113409Y1624974D01*
X4113316Y1623724D01*
X4112943Y1622849D01*
X4112476Y1622099D01*
X4111916Y1621599D01*
X4111169Y1621224D01*
X4109303D01*
G01X4120723D02*
X4116989D01*
Y1628724D01*
X4120723D01*
G01X4119229Y1625099D02*
X4116989D01*
G01X4124303Y1621224D02*
Y1628724D01*
X4126169D01*
X4126916Y1628349D01*
X4127476Y1627849D01*
X4127943Y1627099D01*
X4128316Y1626224D01*
X4128409Y1624974D01*
X4128316Y1623724D01*
X4127943Y1622849D01*
X4127476Y1622099D01*
X4126916Y1621599D01*
X4126169Y1621224D01*
X4124303D01*
G01X4139303D02*
Y1628724D01*
X4141169D01*
X4141916Y1628349D01*
X4142476Y1627849D01*
X4142943Y1627099D01*
X4143316Y1626224D01*
X4143409Y1624974D01*
X4143316Y1623724D01*
X4142943Y1622849D01*
X4142476Y1622099D01*
X4141916Y1621599D01*
X4141169Y1621224D01*
X4139303D01*
G01X4146989D02*
Y1628724D01*
X4149323D01*
X4150069Y1628349D01*
X4150536Y1627849D01*
X4150723Y1626849D01*
X4150536Y1625849D01*
X4149976Y1625224D01*
X4149323Y1624849D01*
X4146989D01*
G01X4149323D02*
X4150723Y1621224D01*
G01X4155236Y1628724D02*
X4157476D01*
G01X4156356D02*
Y1621224D01*
G01X4155236D02*
X4157476D01*
G01X4161989Y1628724D02*
Y1621224D01*
X4165723D01*
G01X4169489Y1628724D02*
Y1621224D01*
X4173223D01*
G01X4184396Y1622224D02*
X4185143Y1621599D01*
X4185983Y1621224D01*
X4186729D01*
X4187476Y1621599D01*
X4188036Y1622224D01*
X4188316Y1623099D01*
X4188129Y1623974D01*
X4187663Y1624724D01*
X4186823Y1625224D01*
X4185703Y1625474D01*
X4185049Y1625974D01*
X4184769Y1626849D01*
X4184956Y1627724D01*
X4185423Y1628349D01*
X4186076Y1628724D01*
X4186729D01*
X4187383Y1628474D01*
X4187943Y1627849D01*
G01X4192736Y1628724D02*
X4194976D01*
G01X4193856D02*
Y1621224D01*
G01X4192736D02*
X4194976D01*
G01X4199583Y1628724D02*
X4203129D01*
X4199583Y1621224D01*
X4203129D01*
G01X4210723D02*
X4206989D01*
Y1628724D01*
X4210723D01*
G01X4209229Y1625099D02*
X4206989D01*
G01X4222083Y1621224D02*
Y1628724D01*
X4225629D01*
G01X4224323Y1625099D02*
X4222083D01*
G01X4231356Y1621224D02*
X4230609Y1621349D01*
X4229956Y1621849D01*
X4229396Y1622599D01*
X4229023Y1623474D01*
X4228836Y1624474D01*
Y1625474D01*
X4229023Y1626474D01*
X4229396Y1627349D01*
X4229956Y1628099D01*
X4230609Y1628599D01*
X4231356Y1628724D01*
X4232103Y1628599D01*
X4232756Y1628099D01*
X4233316Y1627349D01*
X4233689Y1626474D01*
X4233876Y1625474D01*
Y1624474D01*
X4233689Y1623474D01*
X4233316Y1622599D01*
X4232756Y1621849D01*
X4232103Y1621349D01*
X4231356Y1621224D01*
G01X4236989D02*
Y1628724D01*
X4239323D01*
X4240069Y1628349D01*
X4240536Y1627849D01*
X4240723Y1626849D01*
X4240536Y1625849D01*
X4239976Y1625224D01*
X4239323Y1624849D01*
X4236989D01*
G01X4239323D02*
X4240723Y1621224D01*
G01X4253856Y1628724D02*
X4253109Y1628474D01*
X4252549Y1627849D01*
X4252176Y1627099D01*
X4251896Y1626099D01*
X4251803Y1624974D01*
X4251896Y1623849D01*
X4252176Y1622849D01*
X4252549Y1622099D01*
X4253109Y1621474D01*
X4253856Y1621224D01*
X4254603Y1621474D01*
X4255163Y1622099D01*
X4255536Y1622849D01*
X4255816Y1623849D01*
X4255909Y1624974D01*
X4255816Y1626099D01*
X4255536Y1627099D01*
X4255163Y1627849D01*
X4254603Y1628474D01*
X4253856Y1628724D01*
G01X4261356Y1620974D02*
X4261169Y1621099D01*
Y1621349D01*
X4261356Y1621474D01*
X4261543Y1621349D01*
Y1621099D01*
X4261356Y1620974D01*
G01X4266803Y1622349D02*
X4267363Y1621724D01*
X4268016Y1621349D01*
X4268856Y1621224D01*
X4269696Y1621474D01*
X4270349Y1621974D01*
X4270816Y1622849D01*
X4270909Y1623849D01*
X4270723Y1624849D01*
X4270256Y1625474D01*
X4269603Y1625974D01*
X4268949Y1626099D01*
X4268296Y1625974D01*
X4267456Y1625474D01*
X4267736Y1628724D01*
X4270256D01*
G01X4273929Y1621224D02*
Y1628724D01*
X4276356Y1622474D01*
X4278783Y1628724D01*
Y1621224D01*
G01X4281429D02*
Y1628724D01*
X4283856Y1622474D01*
X4286283Y1628724D01*
Y1621224D01*
G01X4297083D02*
Y1628724D01*
X4300629D01*
G01X4299323Y1625099D02*
X4297083D01*
G01X4305236Y1628724D02*
X4307476D01*
G01X4306356D02*
Y1621224D01*
G01X4305236D02*
X4307476D01*
G01X4311709D02*
Y1628724D01*
X4316003Y1621224D01*
Y1628724D01*
G01X4320236D02*
X4322476D01*
G01X4321356D02*
Y1621224D01*
G01X4320236D02*
X4322476D01*
G01X4326896Y1622224D02*
X4327643Y1621599D01*
X4328483Y1621224D01*
X4329229D01*
X4329976Y1621599D01*
X4330536Y1622224D01*
X4330816Y1623099D01*
X4330629Y1623974D01*
X4330163Y1624724D01*
X4329323Y1625224D01*
X4328203Y1625474D01*
X4327549Y1625974D01*
X4327269Y1626849D01*
X4327456Y1627724D01*
X4327923Y1628349D01*
X4328576Y1628724D01*
X4329229D01*
X4329883Y1628474D01*
X4330443Y1627849D01*
G01X4334396Y1621224D02*
Y1628724D01*
G01X4338316D02*
Y1621224D01*
G01Y1624974D02*
X4334396D01*
G01X4345723Y1621224D02*
X4341989D01*
Y1628724D01*
X4345723D01*
G01X4344229Y1625099D02*
X4341989D01*
G01X4349303Y1621224D02*
Y1628724D01*
X4351169D01*
X4351916Y1628349D01*
X4352476Y1627849D01*
X4352943Y1627099D01*
X4353316Y1626224D01*
X4353409Y1624974D01*
X4353316Y1623724D01*
X4352943Y1622849D01*
X4352476Y1622099D01*
X4351916Y1621599D01*
X4351169Y1621224D01*
X4349303D01*
G01X4364489D02*
Y1628724D01*
X4366729D01*
X4367476Y1628349D01*
X4368036Y1627474D01*
X4368223Y1626474D01*
X4368036Y1625474D01*
X4367569Y1624724D01*
X4366729Y1624349D01*
X4364489D01*
G01X4373856Y1628724D02*
Y1621224D01*
G01X4371709Y1628724D02*
X4376003D01*
G01X4379396Y1621224D02*
Y1628724D01*
G01X4383316D02*
Y1621224D01*
G01Y1624974D02*
X4379396D01*
G01X4395236Y1628724D02*
X4397476D01*
G01X4396356D02*
Y1621224D01*
G01X4395236D02*
X4397476D01*
G01X4401896Y1622224D02*
X4402643Y1621599D01*
X4403483Y1621224D01*
X4404229D01*
X4404976Y1621599D01*
X4405536Y1622224D01*
X4405816Y1623099D01*
X4405629Y1623974D01*
X4405163Y1624724D01*
X4404323Y1625224D01*
X4403203Y1625474D01*
X4402549Y1625974D01*
X4402269Y1626849D01*
X4402456Y1627724D01*
X4402923Y1628349D01*
X4403576Y1628724D01*
X4404229D01*
X4404883Y1628474D01*
X4405443Y1627849D01*
G01X4418856Y1628724D02*
X4418109Y1628474D01*
X4417549Y1627849D01*
X4417176Y1627099D01*
X4416896Y1626099D01*
X4416803Y1624974D01*
X4416896Y1623849D01*
X4417176Y1622849D01*
X4417549Y1622099D01*
X4418109Y1621474D01*
X4418856Y1621224D01*
X4419603Y1621474D01*
X4420163Y1622099D01*
X4420536Y1622849D01*
X4420816Y1623849D01*
X4420909Y1624974D01*
X4420816Y1626099D01*
X4420536Y1627099D01*
X4420163Y1627849D01*
X4419603Y1628474D01*
X4418856Y1628724D01*
G01X4426356Y1620974D02*
X4426169Y1621099D01*
Y1621349D01*
X4426356Y1621474D01*
X4426543Y1621349D01*
Y1621099D01*
X4426356Y1620974D01*
G01X4432083Y1624349D02*
X4432736Y1625224D01*
X4433296Y1625724D01*
X4434043Y1625974D01*
X4434696Y1625724D01*
X4435163Y1625224D01*
X4435536Y1624474D01*
X4435629Y1623599D01*
X4435536Y1622849D01*
X4435163Y1622099D01*
X4434603Y1621474D01*
X4433949Y1621224D01*
X4433203Y1621474D01*
X4432549Y1622224D01*
X4432176Y1623349D01*
X4432083Y1624599D01*
X4432269Y1626224D01*
X4432549Y1627099D01*
X4433016Y1627974D01*
X4433669Y1628599D01*
X4434323Y1628724D01*
X4434976Y1628474D01*
X4435443Y1627849D01*
G01X4438929Y1621224D02*
Y1628724D01*
X4441356Y1622474D01*
X4443783Y1628724D01*
Y1621224D01*
G01X4446429D02*
Y1628724D01*
X4448856Y1622474D01*
X4451283Y1628724D01*
Y1621224D01*
G01X4461429D02*
Y1628724D01*
X4463856Y1622474D01*
X4466283Y1628724D01*
Y1621224D01*
G01X4473223D02*
X4469489D01*
Y1628724D01*
X4473223D01*
G01X4471729Y1625099D02*
X4469489D01*
G01X4478856Y1628724D02*
Y1621224D01*
G01X4476709Y1628724D02*
X4481003D01*
G01X4484489Y1621224D02*
Y1628724D01*
X4486823D01*
X4487569Y1628349D01*
X4488036Y1627849D01*
X4488223Y1626849D01*
X4488036Y1625849D01*
X4487476Y1625224D01*
X4486823Y1624849D01*
X4484489D01*
G01X4486823D02*
X4488223Y1621224D01*
G01X4492736Y1628724D02*
X4494976D01*
G01X4493856D02*
Y1621224D01*
G01X4492736D02*
X4494976D01*
G01X4503409Y1628099D02*
X4502849Y1628474D01*
X4502196Y1628724D01*
X4501449D01*
X4500609Y1628349D01*
X4499956Y1627724D01*
X4499489Y1626974D01*
X4499116Y1625724D01*
X4499023Y1624599D01*
X4499209Y1623474D01*
X4499489Y1622724D01*
X4500049Y1621974D01*
X4500703Y1621474D01*
X4501356Y1621224D01*
X4502009D01*
X4502663Y1621474D01*
X4503223Y1621849D01*
X4503689Y1622349D01*
G01X4514303Y1621224D02*
Y1628724D01*
X4516169D01*
X4516916Y1628349D01*
X4517476Y1627849D01*
X4517943Y1627099D01*
X4518316Y1626224D01*
X4518409Y1624974D01*
X4518316Y1623724D01*
X4517943Y1622849D01*
X4517476Y1622099D01*
X4516916Y1621599D01*
X4516169Y1621224D01*
X4514303D01*
G01X4521989D02*
Y1628724D01*
X4524323D01*
X4525069Y1628349D01*
X4525536Y1627849D01*
X4525723Y1626849D01*
X4525536Y1625849D01*
X4524976Y1625224D01*
X4524323Y1624849D01*
X4521989D01*
G01X4524323D02*
X4525723Y1621224D01*
G01X4530236Y1628724D02*
X4532476D01*
G01X4531356D02*
Y1621224D01*
G01X4530236D02*
X4532476D01*
G01X4536989Y1628724D02*
Y1621224D01*
X4540723D01*
G01X4544489Y1628724D02*
Y1621224D01*
X4548223D01*
G01X4553389Y1618724D02*
X4552456Y1619974D01*
X4551989Y1621224D01*
Y1626224D01*
X4552456Y1627474D01*
X4553389Y1628724D01*
G01X4561356D02*
X4560609Y1628474D01*
X4560049Y1627849D01*
X4559676Y1627099D01*
X4559396Y1626099D01*
X4559303Y1624974D01*
X4559396Y1623849D01*
X4559676Y1622849D01*
X4560049Y1622099D01*
X4560609Y1621474D01*
X4561356Y1621224D01*
X4562103Y1621474D01*
X4562663Y1622099D01*
X4563036Y1622849D01*
X4563316Y1623849D01*
X4563409Y1624974D01*
X4563316Y1626099D01*
X4563036Y1627099D01*
X4562663Y1627849D01*
X4562103Y1628474D01*
X4561356Y1628724D01*
G01X4568856Y1620974D02*
X4568669Y1621099D01*
Y1621349D01*
X4568856Y1621474D01*
X4569043Y1621349D01*
Y1621099D01*
X4568856Y1620974D01*
G01X4576356Y1628724D02*
X4575609Y1628474D01*
X4575049Y1627849D01*
X4574676Y1627099D01*
X4574396Y1626099D01*
X4574303Y1624974D01*
X4574396Y1623849D01*
X4574676Y1622849D01*
X4575049Y1622099D01*
X4575609Y1621474D01*
X4576356Y1621224D01*
X4577103Y1621474D01*
X4577663Y1622099D01*
X4578036Y1622849D01*
X4578316Y1623849D01*
X4578409Y1624974D01*
X4578316Y1626099D01*
X4578036Y1627099D01*
X4577663Y1627849D01*
X4577103Y1628474D01*
X4576356Y1628724D01*
G01X4582083Y1627474D02*
X4582643Y1628224D01*
X4583296Y1628599D01*
X4584043Y1628724D01*
X4584976Y1628474D01*
X4585629Y1627849D01*
X4585816Y1627099D01*
X4585723Y1626349D01*
X4585349Y1625724D01*
X4583483Y1624474D01*
X4582643Y1623599D01*
X4582083Y1622349D01*
X4581896Y1621224D01*
X4585816D01*
G01X4589303Y1622724D02*
X4589863Y1621849D01*
X4590609Y1621349D01*
X4591449Y1621224D01*
X4592196Y1621349D01*
X4592943Y1621974D01*
X4593409Y1622724D01*
X4593503Y1623474D01*
X4593316Y1624349D01*
X4592663Y1624974D01*
X4592009Y1625224D01*
X4591169D01*
G01X4592009D02*
X4592569Y1625599D01*
X4593036Y1626224D01*
X4593223Y1626974D01*
X4593036Y1627724D01*
X4592569Y1628349D01*
X4591729Y1628724D01*
X4590889Y1628599D01*
X4590049Y1628099D01*
G01X4597083Y1624349D02*
X4597736Y1625224D01*
X4598296Y1625724D01*
X4599043Y1625974D01*
X4599696Y1625724D01*
X4600163Y1625224D01*
X4600536Y1624474D01*
X4600629Y1623599D01*
X4600536Y1622849D01*
X4600163Y1622099D01*
X4599603Y1621474D01*
X4598949Y1621224D01*
X4598203Y1621474D01*
X4597549Y1622224D01*
X4597176Y1623349D01*
X4597083Y1624599D01*
X4597269Y1626224D01*
X4597549Y1627099D01*
X4598016Y1627974D01*
X4598669Y1628599D01*
X4599323Y1628724D01*
X4599976Y1628474D01*
X4600443Y1627849D01*
G01X4605516Y1627099D02*
X4605983Y1628724D01*
G01X4607196D02*
X4606729Y1627099D01*
G01X4614323Y1618724D02*
X4615256Y1619974D01*
X4615723Y1621224D01*
Y1626224D01*
X4615256Y1627474D01*
X4614323Y1628724D01*
G01X4621356Y1620974D02*
X4621169Y1621099D01*
Y1621349D01*
X4621356Y1621474D01*
X4621543Y1621349D01*
Y1621099D01*
X4621356Y1620974D01*
G01X3884895Y3741772D02*
X3888770Y3754272D01*
X3892645Y3741772D01*
G01X3891250Y3746147D02*
X3886290D01*
G01X3898070Y3754272D02*
Y3741772D01*
X3904270D01*
G01X3910470Y3754272D02*
Y3741772D01*
X3916670D01*
G01X3934960Y3754272D02*
Y3745314D01*
X3935580Y3743438D01*
X3936820Y3742189D01*
X3938370Y3741772D01*
X3939920Y3742189D01*
X3941160Y3743438D01*
X3941780Y3745314D01*
Y3754272D01*
G01X3947205Y3741772D02*
Y3754272D01*
X3954335Y3741772D01*
Y3754272D01*
G01X3961310D02*
X3965030D01*
G01X3963170D02*
Y3741772D01*
G01X3961310D02*
X3965030D01*
G01X3975570Y3754272D02*
Y3741772D01*
G01X3972005Y3754272D02*
X3979135D01*
G01X3984715Y3743438D02*
X3985955Y3742397D01*
X3987350Y3741772D01*
X3988590D01*
X3989830Y3742397D01*
X3990760Y3743438D01*
X3991225Y3744897D01*
X3990915Y3746355D01*
X3990140Y3747605D01*
X3988745Y3748439D01*
X3986885Y3748855D01*
X3985800Y3749689D01*
X3985335Y3751147D01*
X3985645Y3752605D01*
X3986420Y3753647D01*
X3987505Y3754272D01*
X3988590D01*
X3989675Y3753855D01*
X3990605Y3752814D01*
G01X4008895Y3741772D02*
X4012770Y3754272D01*
X4016645Y3741772D01*
G01X4015250Y3746147D02*
X4010290D01*
G01X4022070Y3741772D02*
Y3754272D01*
X4025945D01*
X4027185Y3753647D01*
X4027960Y3752814D01*
X4028270Y3751147D01*
X4027960Y3749480D01*
X4027030Y3748439D01*
X4025945Y3747814D01*
X4022070D01*
G01X4025945D02*
X4028270Y3741772D01*
G01X4040670D02*
X4034470D01*
Y3754272D01*
X4040670D01*
G01X4038190Y3748230D02*
X4034470D01*
G01X4060510Y3754272D02*
X4064230D01*
G01X4062370D02*
Y3741772D01*
G01X4060510D02*
X4064230D01*
G01X4071205D02*
Y3754272D01*
X4078335Y3741772D01*
Y3754272D01*
G01X4095540Y3741772D02*
Y3754272D01*
X4099570Y3743855D01*
X4103600Y3754272D01*
Y3741772D01*
G01X4110110Y3754272D02*
X4113830D01*
G01X4111970D02*
Y3741772D01*
G01X4110110D02*
X4113830D01*
G01X4121270Y3754272D02*
Y3741772D01*
X4127470D01*
G01X4133515Y3743438D02*
X4134755Y3742397D01*
X4136150Y3741772D01*
X4137390D01*
X4138630Y3742397D01*
X4139560Y3743438D01*
X4140025Y3744897D01*
X4139715Y3746355D01*
X4138940Y3747605D01*
X4137545Y3748439D01*
X4135685Y3748855D01*
X4134600Y3749689D01*
X4134135Y3751147D01*
X4134445Y3752605D01*
X4135220Y3753647D01*
X4136305Y3754272D01*
X4137390D01*
X4138475Y3753855D01*
X4139405Y3752814D01*
G01X3883810Y3773439D02*
X3884430Y3774064D01*
X3884895Y3775105D01*
X3885205Y3776564D01*
X3884895Y3777814D01*
X3884275Y3778647D01*
X3883190Y3779272D01*
X3879005D01*
Y3766772D01*
X3884120D01*
X3885205Y3767605D01*
X3885825Y3768855D01*
X3886135Y3770314D01*
X3885825Y3771772D01*
X3884895Y3773022D01*
X3883810Y3773439D01*
X3879005D01*
G01X3891095Y3766772D02*
X3894970Y3779272D01*
X3898845Y3766772D01*
G01X3897450Y3771147D02*
X3892490D01*
G01X3910780Y3778230D02*
X3909850Y3778855D01*
X3908765Y3779272D01*
X3907525D01*
X3906130Y3778647D01*
X3905045Y3777605D01*
X3904270Y3776355D01*
X3903650Y3774272D01*
X3903495Y3772397D01*
X3903805Y3770522D01*
X3904270Y3769272D01*
X3905200Y3768022D01*
X3906285Y3767189D01*
X3907370Y3766772D01*
X3908455D01*
X3909540Y3767189D01*
X3910470Y3767813D01*
X3911245Y3768647D01*
G01X3916360Y3766772D02*
Y3779272D01*
G01X3922250D02*
X3916360Y3771563D01*
G01X3923180Y3766772D02*
X3918995Y3775105D01*
G01X3928760Y3766772D02*
Y3779272D01*
X3931860D01*
X3933100Y3778647D01*
X3934030Y3777814D01*
X3934805Y3776564D01*
X3935425Y3775105D01*
X3935580Y3773022D01*
X3935425Y3770939D01*
X3934805Y3769480D01*
X3934030Y3768230D01*
X3933100Y3767397D01*
X3931860Y3766772D01*
X3928760D01*
G01X3941470D02*
Y3779272D01*
X3945345D01*
X3946585Y3778647D01*
X3947360Y3777814D01*
X3947670Y3776147D01*
X3947360Y3774480D01*
X3946430Y3773439D01*
X3945345Y3772814D01*
X3941470D01*
G01X3945345D02*
X3947670Y3766772D01*
G01X3955110Y3779272D02*
X3958830D01*
G01X3956970D02*
Y3766772D01*
G01X3955110D02*
X3958830D01*
G01X3966270Y3779272D02*
Y3766772D01*
X3972470D01*
G01X3978670Y3779272D02*
Y3766772D01*
X3984870D01*
G01X3994170Y3766355D02*
X3993860Y3766564D01*
Y3766980D01*
X3994170Y3767189D01*
X3994480Y3766980D01*
Y3766564D01*
X3994170Y3766355D01*
G01Y3771980D02*
X3993860Y3772189D01*
Y3772605D01*
X3994170Y3772814D01*
X3994480Y3772605D01*
Y3772189D01*
X3994170Y3771980D01*
G01X4018970Y3779272D02*
Y3766772D01*
G01X4015405Y3779272D02*
X4022535D01*
G01X4031370Y3766772D02*
X4030130Y3766980D01*
X4029045Y3767813D01*
X4028115Y3769064D01*
X4027495Y3770522D01*
X4027185Y3772189D01*
Y3773855D01*
X4027495Y3775522D01*
X4028115Y3776980D01*
X4029045Y3778230D01*
X4030130Y3779064D01*
X4031370Y3779272D01*
X4032610Y3779064D01*
X4033695Y3778230D01*
X4034625Y3776980D01*
X4035245Y3775522D01*
X4035555Y3773855D01*
Y3772189D01*
X4035245Y3770522D01*
X4034625Y3769064D01*
X4033695Y3767813D01*
X4032610Y3766980D01*
X4031370Y3766772D01*
G01X4040670D02*
Y3779272D01*
X4044390D01*
X4045630Y3778647D01*
X4046560Y3777189D01*
X4046870Y3775522D01*
X4046560Y3773855D01*
X4045785Y3772605D01*
X4044390Y3771980D01*
X4040670D01*
G01X4068570Y3779272D02*
Y3766772D01*
G01X4066400Y3775105D02*
X4070740D01*
G01X4080970Y3766772D02*
X4080040Y3766980D01*
X4079110Y3767813D01*
X4078490Y3769272D01*
X4078180Y3770939D01*
X4078490Y3772605D01*
X4079110Y3774064D01*
X4080040Y3774897D01*
X4080970Y3775105D01*
X4081900Y3774897D01*
X4082830Y3774064D01*
X4083450Y3772605D01*
X4083605Y3770939D01*
X4083450Y3769272D01*
X4082830Y3767813D01*
X4081900Y3766980D01*
X4080970Y3766772D01*
G01X4106700Y3773022D02*
X4109800D01*
Y3769272D01*
X4108870Y3768022D01*
X4107785Y3767189D01*
X4106235Y3766772D01*
X4104685Y3767189D01*
X4103600Y3768022D01*
X4102670Y3769272D01*
X4102050Y3770730D01*
X4101740Y3772397D01*
Y3773855D01*
X4102050Y3775105D01*
X4102670Y3776564D01*
X4103600Y3777814D01*
X4104530Y3778647D01*
X4105770Y3779272D01*
X4106855D01*
X4108095Y3778855D01*
X4109025Y3778022D01*
G01X4114605Y3766772D02*
Y3779272D01*
X4121735Y3766772D01*
Y3779272D01*
G01X4127160Y3766772D02*
Y3779272D01*
X4130260D01*
X4131500Y3778647D01*
X4132430Y3777814D01*
X4133205Y3776564D01*
X4133825Y3775105D01*
X4133980Y3773022D01*
X4133825Y3770939D01*
X4133205Y3769480D01*
X4132430Y3768230D01*
X4131500Y3767397D01*
X4130260Y3766772D01*
X4127160D01*
G01X4140025Y3771980D02*
X4141110Y3773439D01*
X4142040Y3774272D01*
X4143280Y3774689D01*
X4144365Y3774272D01*
X4145140Y3773439D01*
X4145760Y3772189D01*
X4145915Y3770730D01*
X4145760Y3769480D01*
X4145140Y3768230D01*
X4144210Y3767189D01*
X4143125Y3766772D01*
X4141885Y3767189D01*
X4140800Y3768438D01*
X4140180Y3770314D01*
X4140025Y3772397D01*
X4140335Y3775105D01*
X4140800Y3776564D01*
X4141575Y3778022D01*
X4142660Y3779064D01*
X4143745Y3779272D01*
X4144830Y3778855D01*
X4145605Y3777814D01*
G01X3901790Y3716772D02*
Y3729272D01*
X3905820Y3718855D01*
X3909850Y3729272D01*
Y3716772D01*
G01X3914655D02*
Y3729272D01*
X3921785Y3716772D01*
Y3729272D01*
G01X3934030Y3728230D02*
X3933100Y3728855D01*
X3932015Y3729272D01*
X3930775D01*
X3929380Y3728647D01*
X3928295Y3727605D01*
X3927520Y3726355D01*
X3926900Y3724272D01*
X3926745Y3722397D01*
X3927055Y3720522D01*
X3927520Y3719272D01*
X3928450Y3718022D01*
X3929535Y3717189D01*
X3930620Y3716772D01*
X3931705D01*
X3932790Y3717189D01*
X3933720Y3717813D01*
X3934495Y3718647D01*
G01X3938370Y3712605D02*
X3947670D01*
G01X3952320Y3729272D02*
Y3716772D01*
X3958520D01*
G01X3963945D02*
X3967820Y3729272D01*
X3971695Y3716772D01*
G01X3970300Y3721147D02*
X3965340D01*
G01X3980220Y3716772D02*
Y3722397D01*
X3977120Y3729272D01*
G01X3983320D02*
X3980220Y3722397D01*
G01X3995720Y3716772D02*
X3989520D01*
Y3729272D01*
X3995720D01*
G01X3993240Y3723230D02*
X3989520D01*
G01X4001920Y3716772D02*
Y3729272D01*
X4005795D01*
X4007035Y3728647D01*
X4007810Y3727814D01*
X4008120Y3726147D01*
X4007810Y3724480D01*
X4006880Y3723439D01*
X4005795Y3722814D01*
X4001920D01*
G01X4005795D02*
X4008120Y3716772D01*
G01X3941160Y3704272D02*
X3944880D01*
G01X3943020D02*
Y3691772D01*
G01X3941160D02*
X3944880D01*
G01X3951855D02*
Y3704272D01*
X3958985Y3691772D01*
Y3704272D01*
G01X3964875Y3696980D02*
X3965960Y3698439D01*
X3966890Y3699272D01*
X3968130Y3699689D01*
X3969215Y3699272D01*
X3969990Y3698439D01*
X3970610Y3697189D01*
X3970765Y3695730D01*
X3970610Y3694480D01*
X3969990Y3693230D01*
X3969060Y3692189D01*
X3967975Y3691772D01*
X3966735Y3692189D01*
X3965650Y3693438D01*
X3965030Y3695314D01*
X3964875Y3697397D01*
X3965185Y3700105D01*
X3965650Y3701564D01*
X3966425Y3703022D01*
X3967510Y3704064D01*
X3968595Y3704272D01*
X3969680Y3703855D01*
X3970455Y3702814D01*
G01X4066090Y3716772D02*
Y3729272D01*
X4070120Y3718855D01*
X4074150Y3729272D01*
Y3716772D01*
G01X4078645D02*
X4082520Y3729272D01*
X4086395Y3716772D01*
G01X4085000Y3721147D02*
X4080040D01*
G01X4091665Y3716772D02*
X4098175Y3729272D01*
G01X4091665D02*
X4098175Y3716772D01*
G01X4102670Y3712605D02*
X4111970D01*
G01X4116310Y3716772D02*
Y3729272D01*
X4119410D01*
X4120650Y3728647D01*
X4121580Y3727814D01*
X4122355Y3726564D01*
X4122975Y3725105D01*
X4123130Y3723022D01*
X4122975Y3720939D01*
X4122355Y3719480D01*
X4121580Y3718230D01*
X4120650Y3717397D01*
X4119410Y3716772D01*
X4116310D01*
G01X4135220D02*
X4129020D01*
Y3729272D01*
X4135220D01*
G01X4132740Y3723230D02*
X4129020D01*
G01X4141420Y3716772D02*
Y3729272D01*
X4145140D01*
X4146380Y3728647D01*
X4147310Y3727189D01*
X4147620Y3725522D01*
X4147310Y3723855D01*
X4146535Y3722605D01*
X4145140Y3721980D01*
X4141420D01*
G01X4156920Y3729272D02*
Y3716772D01*
G01X4153355Y3729272D02*
X4160485D01*
G01X4166065Y3716772D02*
Y3729272D01*
G01X4172575D02*
Y3716772D01*
G01Y3723022D02*
X4166065D01*
G01X4101120Y3691772D02*
X4102205Y3691980D01*
X4103445Y3692605D01*
X4104220Y3693647D01*
X4104530Y3695105D01*
X4104220Y3696563D01*
X4103290Y3697814D01*
X4101895Y3698439D01*
X4100345D01*
X4099415Y3698855D01*
X4098640Y3699897D01*
X4098330Y3701355D01*
X4098795Y3702814D01*
X4099880Y3703855D01*
X4101120Y3704272D01*
X4102360Y3703855D01*
X4103445Y3702814D01*
X4103910Y3701355D01*
X4103600Y3699897D01*
X4102825Y3698855D01*
X4101895Y3698439D01*
X4100345D01*
X4098950Y3697814D01*
X4098020Y3696563D01*
X4097710Y3695105D01*
X4098020Y3693647D01*
X4098795Y3692605D01*
X4100035Y3691980D01*
X4101120Y3691772D01*
G01X4110110Y3694272D02*
X4111040Y3692813D01*
X4112280Y3691980D01*
X4113675Y3691772D01*
X4114915Y3691980D01*
X4116155Y3693022D01*
X4116930Y3694272D01*
X4117085Y3695522D01*
X4116775Y3696980D01*
X4115690Y3698022D01*
X4114605Y3698439D01*
X4113210D01*
G01X4114605D02*
X4115535Y3699064D01*
X4116310Y3700105D01*
X4116620Y3701355D01*
X4116310Y3702605D01*
X4115535Y3703647D01*
X4114140Y3704272D01*
X4112745Y3704064D01*
X4111350Y3703230D01*
G01X4125920Y3691355D02*
X4125610Y3691564D01*
Y3691980D01*
X4125920Y3692189D01*
X4126230Y3691980D01*
Y3691564D01*
X4125920Y3691355D01*
G01X4135375Y3702189D02*
X4136305Y3703438D01*
X4137390Y3704064D01*
X4138630Y3704272D01*
X4140180Y3703855D01*
X4141265Y3702814D01*
X4141575Y3701564D01*
X4141420Y3700313D01*
X4140800Y3699272D01*
X4137700Y3697189D01*
X4136305Y3695730D01*
X4135375Y3693647D01*
X4135065Y3691772D01*
X4141575D01*
G01X4199390Y3716772D02*
Y3729272D01*
X4203420Y3718855D01*
X4207450Y3729272D01*
Y3716772D01*
G01X4212875D02*
Y3729272D01*
X4218765D01*
G01X4216595Y3723230D02*
X4212875D01*
G01X4229150Y3723022D02*
X4232250D01*
Y3719272D01*
X4231320Y3718022D01*
X4230235Y3717189D01*
X4228685Y3716772D01*
X4227135Y3717189D01*
X4226050Y3718022D01*
X4225120Y3719272D01*
X4224500Y3720730D01*
X4224190Y3722397D01*
Y3723855D01*
X4224500Y3725105D01*
X4225120Y3726564D01*
X4226050Y3727814D01*
X4226980Y3728647D01*
X4228220Y3729272D01*
X4229305D01*
X4230545Y3728855D01*
X4231475Y3728022D01*
G01X4235970Y3712605D02*
X4245270D01*
G01X4249765Y3718438D02*
X4251005Y3717397D01*
X4252400Y3716772D01*
X4253640D01*
X4254880Y3717397D01*
X4255810Y3718438D01*
X4256275Y3719897D01*
X4255965Y3721355D01*
X4255190Y3722605D01*
X4253795Y3723439D01*
X4251935Y3723855D01*
X4250850Y3724689D01*
X4250385Y3726147D01*
X4250695Y3727605D01*
X4251470Y3728647D01*
X4252555Y3729272D01*
X4253640D01*
X4254725Y3728855D01*
X4255655Y3727814D01*
G01X4265420Y3729272D02*
Y3716772D01*
G01X4261855Y3729272D02*
X4268985D01*
G01X4274410D02*
Y3720314D01*
X4275030Y3718438D01*
X4276270Y3717189D01*
X4277820Y3716772D01*
X4279370Y3717189D01*
X4280610Y3718438D01*
X4281230Y3720314D01*
Y3729272D01*
G01X4291460Y3723439D02*
X4292080Y3724064D01*
X4292545Y3725105D01*
X4292855Y3726564D01*
X4292545Y3727814D01*
X4291925Y3728647D01*
X4290840Y3729272D01*
X4286655D01*
Y3716772D01*
X4291770D01*
X4292855Y3717605D01*
X4293475Y3718855D01*
X4293785Y3720314D01*
X4293475Y3721772D01*
X4292545Y3723022D01*
X4291460Y3723439D01*
X4286655D01*
G01X4244805Y3695939D02*
X4248835D01*
G01X4342920Y3691772D02*
Y3704272D01*
X4341060Y3701772D01*
G01Y3691772D02*
X4344780D01*
G01X4352375Y3702189D02*
X4353305Y3703438D01*
X4354390Y3704064D01*
X4355630Y3704272D01*
X4357180Y3703855D01*
X4358265Y3702814D01*
X4358575Y3701564D01*
X4358420Y3700313D01*
X4357800Y3699272D01*
X4354700Y3697189D01*
X4353305Y3695730D01*
X4352375Y3693647D01*
X4352065Y3691772D01*
X4358575D01*
G01X4336720Y3716772D02*
X4335480Y3716980D01*
X4334395Y3717813D01*
X4333465Y3719064D01*
X4332845Y3720522D01*
X4332535Y3722189D01*
Y3723855D01*
X4332845Y3725522D01*
X4333465Y3726980D01*
X4334395Y3728230D01*
X4335480Y3729064D01*
X4336720Y3729272D01*
X4337960Y3729064D01*
X4339045Y3728230D01*
X4339975Y3726980D01*
X4340595Y3725522D01*
X4340905Y3723855D01*
Y3722189D01*
X4340595Y3720522D01*
X4339975Y3719064D01*
X4339045Y3717813D01*
X4337960Y3716980D01*
X4336720Y3716772D01*
G01X4337960Y3720105D02*
X4339820Y3716772D01*
G01X4349120Y3729272D02*
Y3716772D01*
G01X4345555Y3729272D02*
X4352685D01*
G01X4361520Y3716772D02*
Y3722397D01*
X4358420Y3729272D01*
G01X4364620D02*
X4361520Y3722397D01*
G54D18*
X57646Y12480D03*
X137272D03*
X186622D03*
X266858D03*
X315598D03*
X502528Y33268D03*
X582154D03*
X631504D03*
X711740D03*
X760480D03*
X1156378Y133866D03*
X1532055Y12480D03*
X1611681D03*
X1661031D03*
X1741267D03*
X1790007D03*
X2822321Y1227129D03*
G54D27*
X322500Y1391830D03*
X537477Y1395413D03*
X1298642Y1391830D03*
X1513618Y1395413D03*
X2822321Y1049829D03*
G54D36*
X900196Y175197D03*
X944684Y155216D03*
X2822321Y1108929D03*
G54D37*
X922441Y154311D03*
Y243799D03*
X2822321Y-73071D03*
G54D28*
X450000Y278543D03*
X460000D03*
X470000D03*
X483500Y246362D03*
X473500D03*
X480000Y278543D03*
X493500Y246362D03*
X490000Y278543D03*
X500000D03*
X498563Y607067D03*
X510000Y278543D03*
X520000D03*
X518563Y607067D03*
X508563D03*
X549236Y1441207D03*
X559236D03*
X569236D03*
X688500Y1601900D03*
Y1611900D03*
Y1621900D03*
X1041435Y143357D03*
Y153357D03*
X1056225Y143131D03*
Y153131D03*
X1041435Y163357D03*
X1056225Y163131D03*
X1099970Y1702570D03*
Y1712570D03*
Y1722570D03*
X1689646Y115669D03*
X1679646D03*
X1689646Y125669D03*
Y135669D03*
X1679646Y125669D03*
Y135669D03*
X1689646Y145669D03*
Y155669D03*
X1679646Y145669D03*
Y155669D03*
X1689646Y165669D03*
X1679646D03*
X1689646Y175669D03*
X1679646D03*
X1771457Y1634646D03*
Y1624646D03*
Y1644646D03*
X2822321Y1345329D03*
G54D19*
X60303Y20354D03*
X312921Y24291D03*
X505185Y41142D03*
X757803Y45079D03*
X922441Y237697D03*
X929331Y160413D03*
X1534712Y20354D03*
X1787330Y24291D03*
X2822321Y636129D03*
G54D29*
X676508Y145866D03*
X2822321Y517929D03*
G54D38*
X928739Y321653D03*
X2822321Y-191271D03*
G54D39*
X1133779Y1653543D03*
X2822321Y931629D03*
M02*
